G04 ================== begin FILE IDENTIFICATION RECORD ==================*
G04 Layout Name:  12433-2a.brd*
G04 Film Name:    TSILK*
G04 File Format:  Gerber RS274X*
G04 File Origin:  Cadence Allegro 16.5-S056*
G04 Origin Date:  Fri Dec 11 16:47:35 2015*
G04 *
G04 Layer:  VIA CLASS/FILMMASKTOP*
G04 Layer:  REF DES/ASSEMBLY_TOP*
G04 Layer:  PACKAGE GEOMETRY/SILKSCREEN_TOP*
G04 Layer:  DRAWING FORMAT/LAYER_PCB_STORY*
G04 Layer:  DRAWING FORMAT/LAYER_SILK_T*
G04 Layer:  BOARD GEOMETRY/SILKSCREEN_TOP*
G04 *
G04 Offset:    (0.00 0.00)*
G04 Mirror:    No*
G04 Mode:      Positive*
G04 Rotation:  0*
G04 FullContactRelief:  No*
G04 UndefLineWidth:     6.00*
G04 ================== end FILE IDENTIFICATION RECORD ====================*
%FSLAX35Y35*MOIN*%
%IR0*IPPOS*OFA0.00000B0.00000*MIA0B0*SFA1.00000B1.00000*%
%ADD10C,.01*%
%ADD11C,.02*%
%ADD12C,.012*%
%ADD13C,.013*%
%ADD14C,.016*%
%ADD15C,.019*%
%ADD16C,.0005*%
%ADD17C,.002*%
%ADD18C,.005*%
%ADD19C,.006*%
%ADD20C,.008*%
G75*
%LPD*%
G75*
G36*
G01X67300Y433800D02*
X69000Y435500D01*
X70700Y433800D01*
X67300D01*
G37*
G36*
G01X80200Y971300D02*
Y981300D01*
X85200D01*
Y971300D01*
X80200D01*
G37*
G36*
G01X58700Y1569400D02*
X60400Y1571100D01*
X62100Y1569400D01*
X58700D01*
G37*
G36*
G01X71289Y1623299D02*
X73289Y1625299D01*
X69289D01*
X71289Y1623299D01*
G37*
G36*
G01X94800Y433300D02*
X96500Y435000D01*
X98200Y433300D01*
X94800D01*
G37*
G36*
G01X107435Y607629D02*
X97835D01*
Y616929D01*
X98135D01*
X107435Y607629D01*
G37*
G36*
G01X100100Y864354D02*
X116900D01*
Y850404D01*
X100100D01*
Y864354D01*
G37*
G36*
G01X103150Y1460850D02*
X108150Y1465850D01*
X103150D01*
Y1460850D01*
G37*
G36*
G01X126800Y1569300D02*
X128500Y1571000D01*
X130200Y1569300D01*
X126800D01*
G37*
G36*
G01X91800D02*
X93500Y1571000D01*
X95200Y1569300D01*
X91800D01*
G37*
G36*
G01X130289Y1623299D02*
X132289Y1625299D01*
X128289D01*
X130289Y1623299D01*
G37*
G36*
G01X101789D02*
X103789Y1625299D01*
X99789D01*
X101789Y1623299D01*
G37*
G36*
G01X139300Y433300D02*
X141000Y435000D01*
X142700Y433300D01*
X139300D01*
G37*
G36*
G01X167300D02*
X169000Y435000D01*
X170700Y433300D01*
X167300D01*
G37*
G36*
G01X172585Y652429D02*
X170485Y650329D01*
X168585Y652429D01*
X172585D01*
G37*
G36*
G01X155100Y728154D02*
X171900D01*
Y714204D01*
X155100D01*
Y728154D01*
G37*
G36*
G01X149500Y872500D02*
X154500D01*
Y892500D01*
X149500D01*
Y872500D01*
G37*
G36*
G01X177650Y872650D02*
X197350D01*
Y1081350D01*
X177650D01*
Y872650D01*
G37*
G36*
G01X136600Y977600D02*
Y963600D01*
X155600D01*
Y977600D01*
X136600D01*
G37*
G36*
G01X160800Y1569300D02*
X162500Y1571000D01*
X164200Y1569300D01*
X160800D01*
G37*
G36*
G01X157789Y1623299D02*
X159789Y1625299D01*
X155789D01*
X157789Y1623299D01*
G37*
G54D10*
G01X171828Y1968527D02*
G03X182301I5236J0D01*
G01X140333D02*
G03X150806I5236J0D01*
G01X234819D02*
G03X245291I5236J0D01*
G01X203323D02*
G03X213796I5236J0D01*
G01X266314D02*
G03X276786I5236J0D01*
G01X297809D02*
G03X308281I5236J0D01*
G54D20*
G01X22100Y688100D02*
X26100D01*
G01X26900D02*
X30900D01*
G01X30800Y1770700D02*
Y1771800D01*
G01Y1768000D02*
Y1769100D01*
G01X81047Y60598D02*
Y59498D01*
G01Y63298D02*
Y62198D01*
G01X78500Y72300D02*
Y73400D01*
G01Y69600D02*
Y70700D01*
G01X49498Y241699D02*
X45498D01*
G01X54200Y241700D02*
X50200D01*
G01X37200Y292300D02*
Y296300D01*
G01X64700Y257000D02*
X60700D01*
G01X53400Y250800D02*
Y254800D01*
G01X70700Y590200D02*
Y589100D01*
G01Y592900D02*
Y591800D01*
G01X45900Y580100D02*
X47000D01*
G01X43200D02*
X44300D01*
G01X72100Y573400D02*
X76100D01*
G01X81200Y705400D02*
X80100D01*
G01X83900D02*
X82800D01*
G01X61000Y664300D02*
Y660300D01*
G01Y659600D02*
Y655600D01*
G01X63635Y691106D02*
X67635D01*
G01X68535D02*
X72535D01*
G01X82300Y730400D02*
X83400D01*
G01X79600D02*
X80700D01*
G01X70200Y708200D02*
X74200D01*
G01X65200D02*
X69200D01*
G01X85500Y875654D02*
X89500D01*
G01X73800Y985800D02*
Y984700D01*
G01Y988500D02*
Y987400D01*
G01X70000Y978600D02*
X68900D01*
G01X72700D02*
X71600D01*
G01X63400Y1001300D02*
X62300D01*
G01X66100D02*
X65000D01*
G01X64800Y1024200D02*
Y1023100D01*
G01Y1026900D02*
Y1025800D01*
G01X80598Y1134953D02*
X79498D01*
G01X83298D02*
X82198D01*
G01X64002Y1131147D02*
X65102D01*
G01X61302D02*
X62402D01*
G01X51500Y1765500D02*
Y1766600D01*
G01Y1762800D02*
Y1763900D01*
G01X114100Y378100D02*
Y382100D01*
G01X105900Y479400D02*
X101900D01*
G01X88729Y532879D02*
Y531779D01*
G01Y535579D02*
Y534479D01*
G01X98300Y560500D02*
X94300D01*
G01X131065Y675894D02*
X127065D01*
G01X125465D02*
X121465D01*
G01X125700Y725400D02*
X126800D01*
G01X123000D02*
X124100D01*
G01X113000Y771100D02*
Y767100D01*
G01Y766100D02*
Y762100D01*
G01X90300Y875654D02*
X94300D01*
G01X93200Y960000D02*
X92100D01*
G01X95900D02*
X94800D01*
G01X123300Y967100D02*
X110800D01*
G01X123300Y981100D02*
Y967100D01*
G01X110800Y981100D02*
X123300D01*
G01X110800D02*
Y963600D01*
G01X113300Y974100D02*
X110800Y976600D01*
G01X113300Y974100D02*
X110800Y971600D01*
G01X95300Y979500D02*
X96400D01*
G01X92600D02*
X93700D01*
G01X104300Y984000D02*
Y988000D01*
G01Y988800D02*
Y992800D01*
G01X101500Y977000D02*
X105500D01*
G01X127900Y989700D02*
X131900D01*
G01X132800Y978600D02*
X128800D01*
G01X102500Y1060400D02*
Y1056400D01*
G01Y1055700D02*
Y1051700D01*
G01X92000Y1453500D02*
Y1457500D01*
G01X104000Y1472500D02*
Y1476500D01*
G01X135500Y1474000D02*
X131500D01*
G01X148700Y479500D02*
X144700D01*
G01X163100Y531300D02*
Y530200D01*
G01Y534000D02*
Y532900D01*
G01X162900Y551300D02*
Y555300D01*
G01X138400Y569600D02*
X142400D01*
G01X179221Y612535D02*
Y614535D01*
G01X157535Y606879D02*
X159535D01*
G01X165300Y699300D02*
X161300D01*
G01X146300Y1114100D02*
X142300D01*
G01X151002Y1114147D02*
X147002D01*
G01X157500Y1460500D02*
Y1464500D01*
G01X185100Y1654700D02*
Y1650700D01*
G01Y1650000D02*
Y1646000D01*
G01X144647Y1880698D02*
Y1876698D01*
G01X144600Y1885700D02*
Y1881700D01*
G54D11*
G01X-448201Y-66763D02*
X-480201D01*
G01X-448201Y-82763D02*
Y-162763D01*
G01Y-118263D02*
X752899D01*
G01X-448201Y-162763D02*
X752899D01*
G01X-452201Y-66763D02*
G02I-12000J0D01*
G01X-457351D02*
G02I-6850J0D01*
G01X-464201Y-82763D02*
Y-50763D01*
G01X-448201Y-82763D02*
X752899D01*
G01X-34601D02*
Y-162763D01*
G01X75000Y406800D02*
Y390200D01*
G01X53800Y389500D02*
Y406100D01*
G01X63700Y349400D02*
Y374400D01*
G01X75000Y427300D02*
Y410700D01*
G01X53800Y410000D02*
Y426600D01*
G01X53500Y580500D02*
Y587500D01*
G01X63200Y596500D02*
Y589500D01*
G01X50000Y658700D02*
Y675300D01*
G01X78300Y1015300D02*
Y1008300D01*
G01X85000Y968550D02*
X92000D01*
G01X82600Y1035600D02*
Y1028600D01*
G01X73702Y1120197D02*
X66702D01*
G01X92002Y1118097D02*
X85002D01*
G01X40500Y1401800D02*
X94000D01*
Y1272300D01*
X40000D01*
Y1401800D01*
G01X84000Y1475000D02*
Y1480000D01*
G01X87200Y1529600D02*
X70600D01*
G01X67500Y1543200D02*
Y1559800D01*
G01X66350Y1693100D02*
Y1667900D01*
G01X45100Y1749400D02*
X38100D01*
G01X39500Y1784500D02*
Y1777500D01*
G01X102899Y-82763D02*
Y-162763D01*
G01X96103Y58002D02*
Y51002D01*
G01X114000Y72000D02*
Y65000D01*
G01X107000Y96800D02*
Y80200D01*
G01X92600Y556900D02*
Y564900D01*
G01X111400Y560800D02*
Y555800D01*
G01X117556Y674265D02*
X109356D01*
G01X100000Y718900D02*
Y711900D01*
G01X99500Y743900D02*
Y736900D01*
G01X104500Y790100D02*
Y806700D01*
G01X97500Y842354D02*
Y850704D01*
G01X134800Y955600D02*
Y963600D01*
G01X110800Y967100D02*
Y959100D01*
G01X94600Y1082300D02*
Y1098900D01*
G01X87000Y1465500D02*
X92000D01*
G01X102970Y1478140D02*
Y1483140D01*
G01X115998Y1877403D02*
X132598D01*
G01X154300Y365000D02*
Y348400D01*
G01X154400Y406200D02*
Y389600D01*
G01X154500Y385200D02*
Y368600D01*
G01X146400Y374300D02*
Y349300D01*
G01X154400Y426700D02*
Y410100D01*
G01X174600Y545300D02*
X169600D01*
G01X156400Y555100D02*
Y563100D01*
G01X167600Y611400D02*
X172600D01*
G01X154765Y605171D02*
X149765D01*
G01X152500Y706154D02*
Y714504D01*
G01X140400Y704500D02*
Y716500D01*
G01X137498Y1120403D02*
X154098D01*
G01X139300Y1484400D02*
X145300D01*
G01X154000Y1539800D02*
Y1523200D01*
G01X151900Y1495200D02*
Y1520200D01*
G01X154100Y1559900D02*
Y1543300D01*
G01X187500Y1609000D02*
Y1604000D01*
G01X184500Y1643500D02*
Y1638500D01*
G01X217899Y-82763D02*
Y-162763D01*
G01X385399Y-82763D02*
Y-162763D01*
G01X555399Y-82763D02*
Y-162763D01*
G01X752899Y-82763D02*
Y-162763D01*
G01X780899Y-66763D02*
G02I-12000J0D01*
G01X775749D02*
G02I-6850J0D01*
G01X768899Y-82763D02*
Y-50763D01*
G01X784899Y-66763D02*
X752899D01*
G54D12*
G01X-206693Y39370D02*
X-175984D01*
G01X-214580Y199710D02*
Y169001D01*
G01X-214624Y467631D02*
Y436922D01*
G01X-214567Y733921D02*
Y703212D01*
G01Y1001681D02*
Y970972D01*
G01Y1265366D02*
Y1234657D01*
G01X-214570Y1532461D02*
Y1501752D01*
G01X-214567Y1798746D02*
Y1768037D01*
G01X-175984Y1929134D02*
X-206693D01*
G01X-76772Y7874D02*
Y31496D01*
G01X-76763Y1937008D02*
Y1960889D01*
G01X-7874Y11811D02*
Y42520D01*
G01X0Y11811D02*
Y42520D01*
G01X20106Y48110D02*
G02I-4200J0D01*
G01Y58110D02*
G02I-4200J0D01*
G01Y68110D02*
G02I-4200J0D01*
G01Y78110D02*
G02I-4200J0D01*
G01Y88110D02*
G02I-4200J0D01*
G01X35199Y220866D02*
G02I-3900J0D01*
G01Y210866D02*
G02I-3900J0D01*
G01Y230866D02*
G02I-3900J0D01*
G01X-7874Y278740D02*
Y309449D01*
G01X0Y278740D02*
Y309449D01*
G01X31299Y344663D02*
G02I0J3900D01*
G01Y334663D02*
G02I0J3900D01*
G01Y354663D02*
G02I0J3900D01*
G01X20106Y481339D02*
G02I-4200J0D01*
G01Y491339D02*
G02I-4200J0D01*
G01Y501339D02*
G02I-4200J0D01*
G01X-7874Y545669D02*
Y576378D01*
G01X0Y545669D02*
Y576378D01*
G01X20106Y511339D02*
G02I-4200J0D01*
G01Y521339D02*
G02I-4200J0D01*
G01Y741181D02*
G02I-4200J0D01*
G01Y751181D02*
G02I-4200J0D01*
G01Y761181D02*
G02I-4200J0D01*
G01Y771181D02*
G02I-4200J0D01*
G01Y781181D02*
G02I-4200J0D01*
G01X0Y862205D02*
Y831496D01*
G01X-7874Y862205D02*
Y831496D01*
G01X31299Y910017D02*
G02I0J3900D01*
G01Y900017D02*
G02I0J3900D01*
G01Y920017D02*
G02I0J3900D01*
G01Y1050687D02*
G02I0J3900D01*
G01Y1040687D02*
G02I0J3900D01*
G01Y1060687D02*
G02I0J3900D01*
G01X-7874Y1106299D02*
Y1137008D01*
G01X0Y1106299D02*
Y1137008D01*
G01X20106Y1187323D02*
G02I-4200J0D01*
G01Y1197323D02*
G02I-4200J0D01*
G01Y1207323D02*
G02I-4200J0D01*
G01Y1217323D02*
G02I-4200J0D01*
G01Y1227323D02*
G02I-4200J0D01*
G01X0Y1422835D02*
Y1392126D01*
G01X-7874Y1422835D02*
Y1392126D01*
G01X20106Y1447165D02*
G02I-4200J0D01*
G01Y1457165D02*
G02I-4200J0D01*
G01Y1467165D02*
G02I-4200J0D01*
G01Y1477165D02*
G02I-4200J0D01*
G01Y1487165D02*
G02I-4200J0D01*
G01X31299Y1616041D02*
G02I0J3900D01*
G01Y1606041D02*
G02I0J3900D01*
G01Y1626041D02*
G02I0J3900D01*
G01X0Y1689764D02*
Y1659055D01*
G01X-7874Y1689764D02*
Y1659055D01*
G01X35199Y1747638D02*
G02I-3900J0D01*
G01Y1737638D02*
G02I-3900J0D01*
G01Y1757638D02*
G02I-3900J0D01*
G01X20106Y1880394D02*
G02I-4200J0D01*
G01X-7874Y1956693D02*
Y1925984D01*
G01X0Y1956693D02*
Y1925984D01*
G01X20106Y1890394D02*
G02I-4200J0D01*
G01Y1900394D02*
G02I-4200J0D01*
G01Y1910394D02*
G02I-4200J0D01*
G01Y1920394D02*
G02I-4200J0D01*
G01X68889Y7615D02*
Y31496D01*
G01X84959Y161889D02*
G02I-4250J0D01*
G01Y171889D02*
G02I-4250J0D01*
G01Y181889D02*
G02I-4250J0D01*
G01Y191889D02*
G02I-4250J0D01*
G01Y204409D02*
G02I-4250J0D01*
G01Y214409D02*
G02I-4250J0D01*
G01Y224409D02*
G02I-4250J0D01*
G01Y234409D02*
G02I-4250J0D01*
G01Y244409D02*
G02I-4250J0D01*
G01Y256929D02*
G02I-4250J0D01*
G01Y266929D02*
G02I-4250J0D01*
G01Y276929D02*
G02I-4250J0D01*
G01Y286929D02*
G02I-4250J0D01*
G01X68898Y1960630D02*
Y1937008D01*
G01X114959Y161889D02*
G02I-4250J0D01*
G01Y171889D02*
G02I-4250J0D01*
G01Y181889D02*
G02I-4250J0D01*
G01Y191889D02*
G02I-4250J0D01*
G01X104959Y161889D02*
G02I-4250J0D01*
G01Y171889D02*
G02I-4250J0D01*
G01Y181889D02*
G02I-4250J0D01*
G01Y191889D02*
G02I-4250J0D01*
G01X94959Y161889D02*
G02I-4250J0D01*
G01Y171889D02*
G02I-4250J0D01*
G01Y181889D02*
G02I-4250J0D01*
G01Y191889D02*
G02I-4250J0D01*
G01X114959Y204409D02*
G02I-4250J0D01*
G01Y214409D02*
G02I-4250J0D01*
G01Y224409D02*
G02I-4250J0D01*
G01Y234409D02*
G02I-4250J0D01*
G01Y244409D02*
G02I-4250J0D01*
G01X104959Y204409D02*
G02I-4250J0D01*
G01Y214409D02*
G02I-4250J0D01*
G01Y224409D02*
G02I-4250J0D01*
G01Y234409D02*
G02I-4250J0D01*
G01Y244409D02*
G02I-4250J0D01*
G01X94959Y204409D02*
G02I-4250J0D01*
G01Y214409D02*
G02I-4250J0D01*
G01Y224409D02*
G02I-4250J0D01*
G01Y234409D02*
G02I-4250J0D01*
G01Y244409D02*
G02I-4250J0D01*
G01X114959Y256929D02*
G02I-4250J0D01*
G01Y266929D02*
G02I-4250J0D01*
G01Y276929D02*
G02I-4250J0D01*
G01Y286929D02*
G02I-4250J0D01*
G01X104959Y256929D02*
G02I-4250J0D01*
G01Y266929D02*
G02I-4250J0D01*
G01Y276929D02*
G02I-4250J0D01*
G01Y286929D02*
G02I-4250J0D01*
G01X94959Y256929D02*
G02I-4250J0D01*
G01Y266929D02*
G02I-4250J0D01*
G01Y276929D02*
G02I-4250J0D01*
G01Y286929D02*
G02I-4250J0D01*
G01X123137Y1778819D02*
G02I-4200J0D01*
G01X133137D02*
G02I-4200J0D01*
G01X143137D02*
G02I-4200J0D01*
G01X168110Y39370D02*
X198819D01*
G01X183856Y161889D02*
G02I-4250J0D01*
G01Y171889D02*
G02I-4250J0D01*
G01Y181889D02*
G02I-4250J0D01*
G01Y191889D02*
G02I-4250J0D01*
G01X173856Y161889D02*
G02I-4250J0D01*
G01Y171889D02*
G02I-4250J0D01*
G01Y181889D02*
G02I-4250J0D01*
G01Y191889D02*
G02I-4250J0D01*
G01X163856Y161889D02*
G02I-4250J0D01*
G01Y171889D02*
G02I-4250J0D01*
G01Y181889D02*
G02I-4250J0D01*
G01Y191889D02*
G02I-4250J0D01*
G01X153856Y161889D02*
G02I-4250J0D01*
G01Y171889D02*
G02I-4250J0D01*
G01Y181889D02*
G02I-4250J0D01*
G01Y191889D02*
G02I-4250J0D01*
G01X183856Y204409D02*
G02I-4250J0D01*
G01Y214409D02*
G02I-4250J0D01*
G01Y224409D02*
G02I-4250J0D01*
G01Y234409D02*
G02I-4250J0D01*
G01Y244409D02*
G02I-4250J0D01*
G01X173856Y204409D02*
G02I-4250J0D01*
G01Y214409D02*
G02I-4250J0D01*
G01Y224409D02*
G02I-4250J0D01*
G01Y234409D02*
G02I-4250J0D01*
G01Y244409D02*
G02I-4250J0D01*
G01X163856Y204409D02*
G02I-4250J0D01*
G01Y214409D02*
G02I-4250J0D01*
G01Y224409D02*
G02I-4250J0D01*
G01Y234409D02*
G02I-4250J0D01*
G01Y244409D02*
G02I-4250J0D01*
G01X153856Y204409D02*
G02I-4250J0D01*
G01Y214409D02*
G02I-4250J0D01*
G01Y224409D02*
G02I-4250J0D01*
G01Y234409D02*
G02I-4250J0D01*
G01Y244409D02*
G02I-4250J0D01*
G01X183856Y256929D02*
G02I-4250J0D01*
G01Y266929D02*
G02I-4250J0D01*
G01Y276929D02*
G02I-4250J0D01*
G01Y286929D02*
G02I-4250J0D01*
G01X173856Y256929D02*
G02I-4250J0D01*
G01Y266929D02*
G02I-4250J0D01*
G01Y276929D02*
G02I-4250J0D01*
G01Y286929D02*
G02I-4250J0D01*
G01X163856Y256929D02*
G02I-4250J0D01*
G01Y266929D02*
G02I-4250J0D01*
G01Y276929D02*
G02I-4250J0D01*
G01Y286929D02*
G02I-4250J0D01*
G01X153856Y256929D02*
G02I-4250J0D01*
G01Y266929D02*
G02I-4250J0D01*
G01Y276929D02*
G02I-4250J0D01*
G01Y286929D02*
G02I-4250J0D01*
G01X169200Y1370500D02*
G02I-4200J0D01*
G01Y1390500D02*
G02I-4200J0D01*
G01Y1380500D02*
G02I-4200J0D01*
G01X198819Y1929134D02*
X168110D01*
G01X222441Y39370D02*
X253150D01*
G01X206693Y169291D02*
Y200000D01*
G01X214567Y169291D02*
Y200000D01*
G01X206693Y436220D02*
Y466929D01*
G01X214567Y436220D02*
Y466929D01*
G01X206693Y733858D02*
Y703149D01*
G01X214567Y733858D02*
Y703149D01*
G01X206693Y997637D02*
Y966928D01*
G01X214567Y997637D02*
Y966928D01*
G01Y1265355D02*
Y1234646D01*
G01X206693Y1265355D02*
Y1234646D01*
G01X214567Y1532284D02*
Y1501575D01*
G01X206693Y1532284D02*
Y1501575D01*
G01X214567Y1799213D02*
Y1768504D01*
G01X206693Y1799213D02*
Y1768504D01*
G01X253150Y1929134D02*
X222441D01*
G01X352362Y7874D02*
Y31496D01*
G01X352370Y1960889D02*
Y1937008D01*
G01X429134Y11811D02*
Y42520D01*
G01X421260Y11811D02*
Y42520D01*
G01X429134Y278740D02*
Y309449D01*
G01X421260Y278740D02*
Y309449D01*
G01X429134Y545669D02*
Y576378D01*
G01X421260Y545669D02*
Y576378D01*
G01X429134Y862205D02*
Y831496D01*
G01X421260Y862205D02*
Y831496D01*
G01X429134Y1106299D02*
Y1137008D01*
G01X421260Y1106299D02*
Y1137008D01*
G01X429134Y1422835D02*
Y1392126D01*
G01X421260Y1422835D02*
Y1392126D01*
G01X429134Y1689764D02*
Y1659055D01*
G01X421260Y1689764D02*
Y1659055D01*
G01X429134Y1956693D02*
Y1925984D01*
G01X421260Y1956693D02*
Y1925984D01*
G01X498023Y7615D02*
Y31496D01*
G01X498032Y1960630D02*
Y1937008D01*
G01X627953Y39370D02*
X597244D01*
G01X627953Y1929134D02*
X597244D01*
G01X635827Y199972D02*
Y169263D01*
G01X635842Y467238D02*
Y436529D01*
G01X635827Y734932D02*
Y704223D01*
G01X635830Y1001701D02*
Y970992D01*
G01X635827Y1265290D02*
Y1234581D01*
G01X635831Y1532435D02*
Y1501726D01*
G01X635827Y1799178D02*
Y1768470D01*
G54D13*
G01X26096Y266203D02*
X30496D01*
Y262703D01*
G01X26300Y301700D02*
X21900D01*
Y305200D01*
G01X32400Y690600D02*
Y693450D01*
X35100D01*
G01X35518Y1090583D02*
Y1086183D01*
X32018D01*
G01X34000Y1652700D02*
X38400D01*
Y1649200D01*
G01X25917Y1718518D02*
X30317D01*
Y1715018D01*
G01X69700Y435400D02*
X68200D01*
G01X66835Y670756D02*
X63985D01*
Y673456D01*
G01X47900Y690600D02*
Y693450D01*
X50600D01*
G01X57317Y913518D02*
X61717D01*
Y910018D01*
G01X61100Y1571000D02*
X59600D01*
G01X71400Y1623450D02*
X65400D01*
Y1618100D01*
G01X97200Y434900D02*
X95700D01*
G01X115668Y568366D02*
Y563966D01*
X112168D01*
G01X132900Y718900D02*
X128500D01*
Y722400D01*
G01X115668Y1257343D02*
Y1252943D01*
X112168D01*
G01X140069Y1418619D02*
X135669D01*
Y1422119D01*
G01X129200Y1570900D02*
X127700D01*
G01X94200D02*
X92700D01*
G01X130400Y1623450D02*
X124400D01*
Y1618100D01*
G01X101900Y1623450D02*
X95900D01*
Y1618100D01*
G01X141700Y434900D02*
X140200D01*
G01X169700D02*
X168200D01*
G01X170478Y650374D02*
X176814D01*
Y644783D01*
G01X143000Y678600D02*
X138600D01*
Y682100D01*
G01X149400Y1397804D02*
X145000D01*
Y1401304D01*
G01X166869Y1433819D02*
X162469D01*
Y1437319D01*
G01X163200Y1570900D02*
X161700D01*
G01X157900Y1623450D02*
X151900D01*
Y1618100D01*
G54D14*
G01X20206Y89610D02*
Y94610D01*
X15206D01*
G01X20206Y522839D02*
Y527839D01*
X15206D01*
G01X20206Y782681D02*
Y787681D01*
X15206D01*
G01X20206Y1228823D02*
Y1233823D01*
X15206D01*
G01X20206Y1488665D02*
Y1493665D01*
X15206D01*
G01X20206Y1921894D02*
Y1926894D01*
X15206D01*
G01X112438Y1780319D02*
Y1785319D01*
X117438D01*
G01X163600Y1364500D02*
X158600D01*
Y1369500D01*
G01X143800Y1413796D02*
X138400D01*
G01X155900Y1434304D02*
X161300D01*
G54D15*
G01X116100Y1394700D02*
X112700D01*
G54D16*
G01X27548Y266191D02*
X27445D01*
G01X27623Y266266D02*
X27370D01*
G01X27698Y266341D02*
X27295D01*
G01X27773Y266416D02*
X27220D01*
G01X27848Y266491D02*
X27145D01*
G01X27923Y266566D02*
X27070D01*
G01X27998Y266641D02*
X26995D01*
G01X28073Y266716D02*
X26920D01*
G01X28148Y266791D02*
X26845D01*
G01X28223Y266866D02*
X26770D01*
G01X28298Y266941D02*
X26695D01*
G01X28373Y267016D02*
X26620D01*
G01X28448Y267091D02*
X26545D01*
G01X28523Y267166D02*
X26470D01*
G01X26427Y267250D02*
X28580Y267233D01*
G01X28633Y267276D02*
X27496Y266138D01*
G01D02*
X26357Y267278D01*
G01X26416D02*
X28576D01*
G01X28632D02*
X26357D01*
G01X28560Y267203D02*
X26432D01*
G01X28485Y267128D02*
X26507D01*
G01X28410Y267053D02*
X26582D01*
G01X28335Y266978D02*
X26657D01*
G01X28260Y266903D02*
X26732D01*
G01X28185Y266828D02*
X26807D01*
G01X28110Y266753D02*
X26882D01*
G01X28035Y266678D02*
X26957D01*
G01X27960Y266603D02*
X27032D01*
G01X27885Y266528D02*
X27107D01*
G01X27810Y266453D02*
X27182D01*
G01X27735Y266378D02*
X27257D01*
G01X27660Y266303D02*
X27332D01*
G01X27585Y266228D02*
X27407D01*
G01X27510Y266153D02*
X27482D01*
G01X24848Y301712D02*
X24951D01*
G01X24773Y301637D02*
X25026D01*
G01X24698Y301562D02*
X25101D01*
G01X24623Y301487D02*
X25176D01*
G01X24548Y301412D02*
X25251D01*
G01X24473Y301337D02*
X25326D01*
G01X24398Y301262D02*
X25401D01*
G01X24323Y301187D02*
X25476D01*
G01X24248Y301112D02*
X25551D01*
G01X24173Y301037D02*
X25626D01*
G01X24098Y300962D02*
X25701D01*
G01X24023Y300887D02*
X25776D01*
G01X23948Y300812D02*
X25851D01*
G01X23873Y300737D02*
X25926D01*
G01X25969Y300653D02*
X23816Y300670D01*
G01X23763Y300627D02*
X24900Y301765D01*
G01D02*
X26039Y300625D01*
G01X25980D02*
X23820D01*
G01X23764D02*
X26039D01*
G01X23836Y300700D02*
X25964D01*
G01X23911Y300775D02*
X25889D01*
G01X23986Y300850D02*
X25814D01*
G01X24061Y300925D02*
X25739D01*
G01X24136Y301000D02*
X25664D01*
G01X24211Y301075D02*
X25589D01*
G01X24286Y301150D02*
X25514D01*
G01X24361Y301225D02*
X25439D01*
G01X24436Y301300D02*
X25364D01*
G01X24511Y301375D02*
X25289D01*
G01X24586Y301450D02*
X25214D01*
G01X24661Y301525D02*
X25139D01*
G01X24736Y301600D02*
X25064D01*
G01X24811Y301675D02*
X24989D01*
G01X24886Y301750D02*
X24914D01*
G01X27369Y1718506D02*
X27266D01*
G01X27444Y1718581D02*
X27191D01*
G01X27519Y1718656D02*
X27116D01*
G01X27594Y1718731D02*
X27041D01*
G01X27669Y1718806D02*
X26966D01*
G01X27744Y1718881D02*
X26891D01*
G01X27819Y1718956D02*
X26816D01*
G01X27894Y1719031D02*
X26741D01*
G01X27969Y1719106D02*
X26666D01*
G01X28044Y1719181D02*
X26591D01*
G01X28119Y1719256D02*
X26516D01*
G01X28194Y1719331D02*
X26441D01*
G01X28269Y1719406D02*
X26366D01*
G01X28344Y1719481D02*
X26291D01*
G01X26248Y1719565D02*
X28401Y1719548D01*
G01X28454Y1719591D02*
X27317Y1718453D01*
G01D02*
X26178Y1719593D01*
G01X26237D02*
X28397D01*
G01X28453D02*
X26178D01*
G01X28381Y1719518D02*
X26253D01*
G01X28306Y1719443D02*
X26328D01*
G01X28231Y1719368D02*
X26403D01*
G01X28156Y1719293D02*
X26478D01*
G01X28081Y1719218D02*
X26553D01*
G01X28006Y1719143D02*
X26628D01*
G01X27931Y1719068D02*
X26703D01*
G01X27856Y1718993D02*
X26778D01*
G01X27781Y1718918D02*
X26853D01*
G01X27706Y1718843D02*
X26928D01*
G01X27631Y1718768D02*
X27003D01*
G01X27556Y1718693D02*
X27078D01*
G01X27481Y1718618D02*
X27153D01*
G01X27406Y1718543D02*
X27228D01*
G01X27331Y1718468D02*
X27303D01*
G01X58769Y913506D02*
X58666D01*
G01X58844Y913581D02*
X58591D01*
G01X58919Y913656D02*
X58516D01*
G01X58994Y913731D02*
X58441D01*
G01X59069Y913806D02*
X58366D01*
G01X59144Y913881D02*
X58291D01*
G01X59219Y913956D02*
X58216D01*
G01X59294Y914031D02*
X58141D01*
G01X59369Y914106D02*
X58066D01*
G01X59444Y914181D02*
X57991D01*
G01X59519Y914256D02*
X57916D01*
G01X59594Y914331D02*
X57841D01*
G01X59669Y914406D02*
X57766D01*
G01X59744Y914481D02*
X57691D01*
G01X57648Y914565D02*
X59801Y914548D01*
G01X59854Y914591D02*
X58717Y913453D01*
G01D02*
X57578Y914593D01*
G01X57637D02*
X59797D01*
G01X59853D02*
X57578D01*
G01X59781Y914518D02*
X57653D01*
G01X59706Y914443D02*
X57728D01*
G01X59631Y914368D02*
X57803D01*
G01X59556Y914293D02*
X57878D01*
G01X59481Y914218D02*
X57953D01*
G01X59406Y914143D02*
X58028D01*
G01X59331Y914068D02*
X58103D01*
G01X59256Y913993D02*
X58178D01*
G01X59181Y913918D02*
X58253D01*
G01X59106Y913843D02*
X58328D01*
G01X59031Y913768D02*
X58403D01*
G01X58956Y913693D02*
X58478D01*
G01X58881Y913618D02*
X58553D01*
G01X58806Y913543D02*
X58628D01*
G01X58731Y913468D02*
X58703D01*
G01X35506Y1089131D02*
Y1089234D01*
G01X35581Y1089056D02*
Y1089309D01*
G01X35656Y1088981D02*
Y1089384D01*
G01X35731Y1088906D02*
Y1089459D01*
G01X35806Y1088831D02*
Y1089534D01*
G01X35881Y1088756D02*
Y1089609D01*
G01X35956Y1088681D02*
Y1089684D01*
G01X36031Y1088606D02*
Y1089759D01*
G01X36106Y1088531D02*
Y1089834D01*
G01X36181Y1088456D02*
Y1089909D01*
G01X36256Y1088381D02*
Y1089984D01*
G01X36331Y1088306D02*
Y1090059D01*
G01X36406Y1088231D02*
Y1090134D01*
G01X36481Y1088156D02*
Y1090209D01*
G01X36565Y1090252D02*
X36548Y1088099D01*
G01X36591Y1088046D02*
X35453Y1089183D01*
G01D02*
X36593Y1090322D01*
G01Y1090263D02*
Y1088103D01*
G01Y1088047D02*
Y1090322D01*
G01X36518Y1088119D02*
Y1090247D01*
G01X36443Y1088194D02*
Y1090172D01*
G01X36368Y1088269D02*
Y1090097D01*
G01X36293Y1088344D02*
Y1090022D01*
G01X36218Y1088419D02*
Y1089947D01*
G01X36143Y1088494D02*
Y1089872D01*
G01X36068Y1088569D02*
Y1089797D01*
G01X35993Y1088644D02*
Y1089722D01*
G01X35918Y1088719D02*
Y1089647D01*
G01X35843Y1088794D02*
Y1089572D01*
G01X35768Y1088869D02*
Y1089497D01*
G01X35693Y1088944D02*
Y1089422D01*
G01X35618Y1089019D02*
Y1089347D01*
G01X35543Y1089094D02*
Y1089272D01*
G01X35468Y1089169D02*
Y1089197D01*
G01X35452Y1652688D02*
X35349D01*
G01X35527Y1652763D02*
X35274D01*
G01X35602Y1652838D02*
X35199D01*
G01X35677Y1652913D02*
X35124D01*
G01X35752Y1652988D02*
X35049D01*
G01X35827Y1653063D02*
X34974D01*
G01X35902Y1653138D02*
X34899D01*
G01X35977Y1653213D02*
X34824D01*
G01X36052Y1653288D02*
X34749D01*
G01X36127Y1653363D02*
X34674D01*
G01X36202Y1653438D02*
X34599D01*
G01X36277Y1653513D02*
X34524D01*
G01X36352Y1653588D02*
X34449D01*
G01X36427Y1653663D02*
X34374D01*
G01X34331Y1653747D02*
X36484Y1653730D01*
G01X36537Y1653773D02*
X35400Y1652635D01*
G01D02*
X34261Y1653775D01*
G01X34320D02*
X36480D01*
G01X36536D02*
X34261D01*
G01X36464Y1653700D02*
X34336D01*
G01X36389Y1653625D02*
X34411D01*
G01X36314Y1653550D02*
X34486D01*
G01X36239Y1653475D02*
X34561D01*
G01X36164Y1653400D02*
X34636D01*
G01X36089Y1653325D02*
X34711D01*
G01X36014Y1653250D02*
X34786D01*
G01X35939Y1653175D02*
X34861D01*
G01X35864Y1653100D02*
X34936D01*
G01X35789Y1653025D02*
X35011D01*
G01X35714Y1652950D02*
X35086D01*
G01X35639Y1652875D02*
X35161D01*
G01X35564Y1652800D02*
X35236D01*
G01X35489Y1652725D02*
X35311D01*
G01X35414Y1652650D02*
X35386D01*
G01X115656Y566914D02*
Y567017D01*
G01X115731Y566839D02*
Y567092D01*
G01X115806Y566764D02*
Y567167D01*
G01X115881Y566689D02*
Y567242D01*
G01X115956Y566614D02*
Y567317D01*
G01X116031Y566539D02*
Y567392D01*
G01X116106Y566464D02*
Y567467D01*
G01X116181Y566389D02*
Y567542D01*
G01X116256Y566314D02*
Y567617D01*
G01X116331Y566239D02*
Y567692D01*
G01X116406Y566164D02*
Y567767D01*
G01X116481Y566089D02*
Y567842D01*
G01X116556Y566014D02*
Y567917D01*
G01X116631Y565939D02*
Y567992D01*
G01X116715Y568035D02*
X116698Y565882D01*
G01X116741Y565829D02*
X115603Y566966D01*
G01D02*
X116743Y568105D01*
G01Y568046D02*
Y565886D01*
G01Y565830D02*
Y568105D01*
G01X116668Y565902D02*
Y568030D01*
G01X116593Y565977D02*
Y567955D01*
G01X116518Y566052D02*
Y567880D01*
G01X116443Y566127D02*
Y567805D01*
G01X116368Y566202D02*
Y567730D01*
G01X116293Y566277D02*
Y567655D01*
G01X116218Y566352D02*
Y567580D01*
G01X116143Y566427D02*
Y567505D01*
G01X116068Y566502D02*
Y567430D01*
G01X115993Y566577D02*
Y567355D01*
G01X115918Y566652D02*
Y567280D01*
G01X115843Y566727D02*
Y567205D01*
G01X115768Y566802D02*
Y567130D01*
G01X115693Y566877D02*
Y567055D01*
G01X115618Y566952D02*
Y566980D01*
G01X131448Y718912D02*
X131551D01*
G01X131373Y718837D02*
X131626D01*
G01X131298Y718762D02*
X131701D01*
G01X131223Y718687D02*
X131776D01*
G01X131148Y718612D02*
X131851D01*
G01X131073Y718537D02*
X131926D01*
G01X130998Y718462D02*
X132001D01*
G01X130923Y718387D02*
X132076D01*
G01X130848Y718312D02*
X132151D01*
G01X130773Y718237D02*
X132226D01*
G01X130698Y718162D02*
X132301D01*
G01X130623Y718087D02*
X132376D01*
G01X130548Y718012D02*
X132451D01*
G01X130473Y717937D02*
X132526D01*
G01X132569Y717853D02*
X130416Y717870D01*
G01X130363Y717827D02*
X131500Y718965D01*
G01D02*
X132639Y717825D01*
G01X132580D02*
X130420D01*
G01X130364D02*
X132639D01*
G01X130436Y717900D02*
X132564D01*
G01X130511Y717975D02*
X132489D01*
G01X130586Y718050D02*
X132414D01*
G01X130661Y718125D02*
X132339D01*
G01X130736Y718200D02*
X132264D01*
G01X130811Y718275D02*
X132189D01*
G01X130886Y718350D02*
X132114D01*
G01X130961Y718425D02*
X132039D01*
G01X131036Y718500D02*
X131964D01*
G01X131111Y718575D02*
X131889D01*
G01X131186Y718650D02*
X131814D01*
G01X131261Y718725D02*
X131739D01*
G01X131336Y718800D02*
X131664D01*
G01X131411Y718875D02*
X131589D01*
G01X131486Y718950D02*
X131514D01*
G01X115656Y1255891D02*
Y1255994D01*
G01X115731Y1255816D02*
Y1256069D01*
G01X115806Y1255741D02*
Y1256144D01*
G01X115881Y1255666D02*
Y1256219D01*
G01X115956Y1255591D02*
Y1256294D01*
G01X116031Y1255516D02*
Y1256369D01*
G01X116106Y1255441D02*
Y1256444D01*
G01X116181Y1255366D02*
Y1256519D01*
G01X116256Y1255291D02*
Y1256594D01*
G01X116331Y1255216D02*
Y1256669D01*
G01X116406Y1255141D02*
Y1256744D01*
G01X116481Y1255066D02*
Y1256819D01*
G01X116556Y1254991D02*
Y1256894D01*
G01X116631Y1254916D02*
Y1256969D01*
G01X116715Y1257012D02*
X116698Y1254859D01*
G01X116741Y1254806D02*
X115603Y1255943D01*
G01D02*
X116743Y1257082D01*
G01Y1257023D02*
Y1254863D01*
G01Y1254807D02*
Y1257082D01*
G01X116668Y1254879D02*
Y1257007D01*
G01X116593Y1254954D02*
Y1256932D01*
G01X116518Y1255029D02*
Y1256857D01*
G01X116443Y1255104D02*
Y1256782D01*
G01X116368Y1255179D02*
Y1256707D01*
G01X116293Y1255254D02*
Y1256632D01*
G01X116218Y1255329D02*
Y1256557D01*
G01X116143Y1255404D02*
Y1256482D01*
G01X116068Y1255479D02*
Y1256407D01*
G01X115993Y1255554D02*
Y1256332D01*
G01X115918Y1255629D02*
Y1256257D01*
G01X115843Y1255704D02*
Y1256182D01*
G01X115768Y1255779D02*
Y1256107D01*
G01X115693Y1255854D02*
Y1256032D01*
G01X115618Y1255929D02*
Y1255957D01*
G01X141548Y678612D02*
X141651D01*
G01X141473Y678537D02*
X141726D01*
G01X141398Y678462D02*
X141801D01*
G01X141323Y678387D02*
X141876D01*
G01X141248Y678312D02*
X141951D01*
G01X141173Y678237D02*
X142026D01*
G01X141098Y678162D02*
X142101D01*
G01X141023Y678087D02*
X142176D01*
G01X140948Y678012D02*
X142251D01*
G01X140873Y677937D02*
X142326D01*
G01X140798Y677862D02*
X142401D01*
G01X140723Y677787D02*
X142476D01*
G01X140648Y677712D02*
X142551D01*
G01X140573Y677637D02*
X142626D01*
G01X142669Y677553D02*
X140516Y677570D01*
G01X140463Y677527D02*
X141600Y678665D01*
G01D02*
X142739Y677525D01*
G01X142680D02*
X140520D01*
G01X140464D02*
X142739D01*
G01X140536Y677600D02*
X142664D01*
G01X140611Y677675D02*
X142589D01*
G01X140686Y677750D02*
X142514D01*
G01X140761Y677825D02*
X142439D01*
G01X140836Y677900D02*
X142364D01*
G01X140911Y677975D02*
X142289D01*
G01X140986Y678050D02*
X142214D01*
G01X141061Y678125D02*
X142139D01*
G01X141136Y678200D02*
X142064D01*
G01X141211Y678275D02*
X141989D01*
G01X141286Y678350D02*
X141914D01*
G01X141361Y678425D02*
X141839D01*
G01X141436Y678500D02*
X141764D01*
G01X141511Y678575D02*
X141689D01*
G01X141586Y678650D02*
X141614D01*
G01X138617Y1418631D02*
X138720D01*
G01X138542Y1418556D02*
X138795D01*
G01X138467Y1418481D02*
X138870D01*
G01X138392Y1418406D02*
X138945D01*
G01X138317Y1418331D02*
X139020D01*
G01X138242Y1418256D02*
X139095D01*
G01X138167Y1418181D02*
X139170D01*
G01X138092Y1418106D02*
X139245D01*
G01X138017Y1418031D02*
X139320D01*
G01X137942Y1417956D02*
X139395D01*
G01X137867Y1417881D02*
X139470D01*
G01X137792Y1417806D02*
X139545D01*
G01X137717Y1417731D02*
X139620D01*
G01X137642Y1417656D02*
X139695D01*
G01X139738Y1417572D02*
X137585Y1417589D01*
G01X137532Y1417546D02*
X138669Y1418684D01*
G01D02*
X139808Y1417544D01*
G01X139749D02*
X137589D01*
G01X137533D02*
X139808D01*
G01X137605Y1417619D02*
X139733D01*
G01X137680Y1417694D02*
X139658D01*
G01X137755Y1417769D02*
X139583D01*
G01X137830Y1417844D02*
X139508D01*
G01X137905Y1417919D02*
X139433D01*
G01X137980Y1417994D02*
X139358D01*
G01X138055Y1418069D02*
X139283D01*
G01X138130Y1418144D02*
X139208D01*
G01X138205Y1418219D02*
X139133D01*
G01X138280Y1418294D02*
X139058D01*
G01X138355Y1418369D02*
X138983D01*
G01X138430Y1418444D02*
X138908D01*
G01X138505Y1418519D02*
X138833D01*
G01X138580Y1418594D02*
X138758D01*
G01X138655Y1418669D02*
X138683D01*
G01X147948Y1397816D02*
X148051D01*
G01X147873Y1397741D02*
X148126D01*
G01X147798Y1397666D02*
X148201D01*
G01X147723Y1397591D02*
X148276D01*
G01X147648Y1397516D02*
X148351D01*
G01X147573Y1397441D02*
X148426D01*
G01X147498Y1397366D02*
X148501D01*
G01X147423Y1397291D02*
X148576D01*
G01X147348Y1397216D02*
X148651D01*
G01X147273Y1397141D02*
X148726D01*
G01X147198Y1397066D02*
X148801D01*
G01X147123Y1396991D02*
X148876D01*
G01X147048Y1396916D02*
X148951D01*
G01X146973Y1396841D02*
X149026D01*
G01X149069Y1396757D02*
X146916Y1396774D01*
G01X146863Y1396731D02*
X148000Y1397869D01*
G01D02*
X149139Y1396729D01*
G01X149080D02*
X146920D01*
G01X146864D02*
X149139D01*
G01X146936Y1396804D02*
X149064D01*
G01X147011Y1396879D02*
X148989D01*
G01X147086Y1396954D02*
X148914D01*
G01X147161Y1397029D02*
X148839D01*
G01X147236Y1397104D02*
X148764D01*
G01X147311Y1397179D02*
X148689D01*
G01X147386Y1397254D02*
X148614D01*
G01X147461Y1397329D02*
X148539D01*
G01X147536Y1397404D02*
X148464D01*
G01X147611Y1397479D02*
X148389D01*
G01X147686Y1397554D02*
X148314D01*
G01X147761Y1397629D02*
X148239D01*
G01X147836Y1397704D02*
X148164D01*
G01X147911Y1397779D02*
X148089D01*
G01X147986Y1397854D02*
X148014D01*
G01X165417Y1433831D02*
X165520D01*
G01X165342Y1433756D02*
X165595D01*
G01X165267Y1433681D02*
X165670D01*
G01X165192Y1433606D02*
X165745D01*
G01X165117Y1433531D02*
X165820D01*
G01X165042Y1433456D02*
X165895D01*
G01X164967Y1433381D02*
X165970D01*
G01X164892Y1433306D02*
X166045D01*
G01X164817Y1433231D02*
X166120D01*
G01X164742Y1433156D02*
X166195D01*
G01X164667Y1433081D02*
X166270D01*
G01X164592Y1433006D02*
X166345D01*
G01X164517Y1432931D02*
X166420D01*
G01X164442Y1432856D02*
X166495D01*
G01X166538Y1432772D02*
X164385Y1432789D01*
G01X164332Y1432746D02*
X165469Y1433884D01*
G01D02*
X166608Y1432744D01*
G01X166549D02*
X164389D01*
G01X164333D02*
X166608D01*
G01X164405Y1432819D02*
X166533D01*
G01X164480Y1432894D02*
X166458D01*
G01X164555Y1432969D02*
X166383D01*
G01X164630Y1433044D02*
X166308D01*
G01X164705Y1433119D02*
X166233D01*
G01X164780Y1433194D02*
X166158D01*
G01X164855Y1433269D02*
X166083D01*
G01X164930Y1433344D02*
X166008D01*
G01X165005Y1433419D02*
X165933D01*
G01X165080Y1433494D02*
X165858D01*
G01X165155Y1433569D02*
X165783D01*
G01X165230Y1433644D02*
X165708D01*
G01X165305Y1433719D02*
X165633D01*
G01X165380Y1433794D02*
X165558D01*
G01X165455Y1433869D02*
X165483D01*
G54D17*
G01X126900Y873370D02*
X126880Y873400D01*
G01X127440Y873370D02*
X126900D01*
G01X127460Y873380D02*
X127440Y873370D01*
G01X127570Y873430D02*
X127460Y873380D01*
G01X127580Y873440D02*
X127570Y873430D01*
G01X133170Y878620D02*
X127580Y873440D01*
G01X126910Y873370D02*
Y873430D01*
G01X127010Y873370D02*
Y873520D01*
G01X127120Y873610D02*
Y873370D01*
G01X127210D02*
Y873710D01*
G01X127320Y873800D02*
Y873370D01*
G01X127410D02*
Y873890D01*
G01X127510Y873990D02*
Y873400D01*
G01X127620Y873470D02*
Y874080D01*
G01X127710Y874170D02*
Y873560D01*
G01X127820Y873650D02*
Y874260D01*
G01X127910Y874360D02*
Y873750D01*
G01X128010Y873840D02*
Y874450D01*
G01X128120Y874540D02*
Y873930D01*
G01X128210Y874020D02*
Y874640D01*
G01X128320Y874730D02*
Y874120D01*
G01X128410Y874210D02*
Y874820D01*
G01X128510Y874920D02*
Y874300D01*
G01X128620Y874400D02*
Y875010D01*
G01X128710Y875100D02*
Y874490D01*
G01X128820Y874580D02*
Y875200D01*
G01X128910Y875290D02*
Y874680D01*
G01X129010Y874770D02*
Y875380D01*
G01X129120Y875480D02*
Y874860D01*
G01X129210Y874950D02*
Y875570D01*
G01X129320Y875660D02*
Y875050D01*
G01X129410Y875140D02*
Y875750D01*
G01X129510Y875850D02*
Y875230D01*
G01X129620Y875330D02*
Y875940D01*
G01X129710Y876030D02*
Y875420D01*
G01X129820Y875510D02*
Y876120D01*
G01X129910Y876220D02*
Y875610D01*
G01X130010Y875700D02*
Y876310D01*
G01X130120Y876400D02*
Y875790D01*
G01X130210Y875880D02*
Y876500D01*
G01X130320Y876590D02*
Y875980D01*
G01X130410Y876070D02*
Y876680D01*
G01X130510Y876780D02*
Y876160D01*
G01X130620Y876250D02*
Y876870D01*
G01X130710Y876960D02*
Y876350D01*
G01X130820Y876440D02*
Y877060D01*
G01X130910Y877150D02*
Y876530D01*
G01X131010Y876620D02*
Y877240D01*
G01X131120Y877340D02*
Y876720D01*
G01X131210Y876810D02*
Y877430D01*
G01X131320Y877520D02*
Y876900D01*
G01X131410Y876990D02*
Y877620D01*
G01X131510Y877710D02*
Y877090D01*
G01X131620Y877180D02*
Y877800D01*
G01X131710Y877890D02*
Y877270D01*
G01X131820Y877370D02*
Y877990D01*
G01X131910Y878080D02*
Y877460D01*
G01X132010Y877550D02*
Y878170D01*
G01X132120Y878270D02*
Y877650D01*
G01X132320Y877830D02*
Y879070D01*
G01X132510Y879080D02*
Y878020D01*
G01X130220Y877770D02*
Y878280D01*
G01X130260Y877730D02*
X130220Y877770D01*
G01X130720Y877730D02*
X130260D01*
G01X130760Y877770D02*
X130720Y877730D01*
G01X130320D02*
Y887980D01*
G01X130510Y887910D02*
Y877730D01*
G01X130710D02*
Y887750D01*
G01X129410Y880380D02*
Y878950D01*
G01X130150Y878370D02*
X130220Y878280D01*
G01X130100Y878390D02*
X130150Y878370D01*
G01X130090Y878390D02*
X130100D01*
G01X129840Y878510D02*
X130090Y878390D01*
G01X129830Y878530D02*
X129840Y878510D01*
G01X129410Y878960D02*
X129830Y878530D01*
G01X130210Y878290D02*
Y879020D01*
G01X129880Y879130D02*
X129810Y879240D01*
G01X130050Y878960D02*
X129880Y879130D01*
G01X130160Y878940D02*
X130050Y878960D01*
G01X130220Y879030D02*
X130160Y878940D01*
G01X129910Y879100D02*
Y878480D01*
G01X130010Y878430D02*
Y879000D01*
G01X130120Y878950D02*
Y878380D01*
G01X129710Y878640D02*
Y880320D01*
G01X129510D02*
Y878850D01*
G01X133110Y879200D02*
X136590Y882430D01*
G01X133110Y879190D02*
Y879200D01*
G01X133060Y879150D02*
X133110Y879190D01*
G01X133000Y879120D02*
X133060Y879150D01*
G01X130870Y878940D02*
X133000Y879120D01*
G01X130760Y879040D02*
X130870Y878940D01*
G01X136320D02*
Y879410D01*
G01X136120Y879390D02*
Y878920D01*
G01X135910Y878900D02*
Y879370D01*
G01X135710Y879360D02*
Y878890D01*
G01X135510Y878870D02*
Y879340D01*
G01X135320Y879320D02*
Y878850D01*
G01X135120Y878840D02*
Y879310D01*
G01X134910Y879290D02*
Y878820D01*
G01X134710Y878800D02*
Y879270D01*
G01X134510Y879250D02*
Y878790D01*
G01X134320Y878770D02*
Y879240D01*
G01X134120Y879220D02*
Y878750D01*
G01X134010Y878740D02*
Y879250D01*
G01X133710Y879750D02*
Y878720D01*
G01X133510Y878700D02*
Y879570D01*
G01X133200Y878640D02*
X133170Y878620D01*
G01X133300Y878680D02*
X133200Y878640D01*
G01X133310Y878680D02*
X133300D01*
G01X133320D02*
X133310D01*
G01X133320Y879380D02*
Y878680D01*
G01X133120Y878580D02*
Y879200D01*
G01X133010Y879130D02*
Y878480D01*
G01X132910Y878390D02*
Y879120D01*
G01X132820Y879110D02*
Y878300D01*
G01X132710Y878200D02*
Y879100D01*
G01X132620Y879090D02*
Y878110D01*
G01X132410Y877920D02*
Y879070D01*
G01X132210Y879060D02*
Y878580D01*
G01X130760Y878370D02*
Y877770D01*
G01X130850Y878470D02*
X130760Y878370D01*
G01X132200Y878590D02*
X130850Y878470D01*
G01X130820Y878430D02*
Y878990D01*
G01X130910Y878940D02*
Y878480D01*
G01X131010Y878490D02*
Y878960D01*
G01X131120D02*
Y878490D01*
G01X131210Y878500D02*
Y878970D01*
G01X131320Y878980D02*
Y878510D01*
G01X131410Y878520D02*
Y878990D01*
G01X131510Y879000D02*
Y878530D01*
G01X131620Y878540D02*
Y879010D01*
G01X131710D02*
Y878550D01*
G01X131820D02*
Y879020D01*
G01X131910Y879030D02*
Y878570D01*
G01X132010D02*
Y879040D01*
G01X132120Y879050D02*
Y878580D01*
G01X132270Y878420D02*
X126880Y873400D01*
G01X132300Y878530D02*
X132270Y878420D01*
G01X132200Y878590D02*
X132300Y878530D01*
G01X132210Y877740D02*
Y878360D01*
G01X133320Y878680D02*
X138470Y879120D01*
G01X136410Y878950D02*
Y879420D01*
G01X136210Y879400D02*
Y878930D01*
G01X136010Y878920D02*
Y879380D01*
G01X135820Y879360D02*
Y878900D01*
G01X135620Y878880D02*
Y879350D01*
G01X135410Y879330D02*
Y878860D01*
G01X135210Y878850D02*
Y879310D01*
G01X135010Y879300D02*
Y878830D01*
G01X134820Y878810D02*
Y879280D01*
G01X134620Y879260D02*
Y878790D01*
G01X134410Y878780D02*
Y879240D01*
G01X134210Y879230D02*
Y878760D01*
G01X133990Y879390D02*
X136930Y882120D01*
G01X133970Y879270D02*
X133990Y879390D01*
G01X134070Y879220D02*
X133970Y879270D01*
G01X139360Y879670D02*
X134070Y879220D01*
G01X134010Y879410D02*
Y880030D01*
G01X134210Y880220D02*
Y879600D01*
G01X134410Y879780D02*
Y880400D01*
G01X133620Y879660D02*
Y878710D01*
G01X133410Y878690D02*
Y879480D01*
G01X133210Y879290D02*
Y878650D01*
G01X129800Y879350D02*
X129810Y879240D01*
G01X129890Y879400D02*
X129800Y879350D01*
G01X130120Y879400D02*
X129890D01*
G01X130220Y879300D02*
X130120Y879400D01*
G01X130220Y879030D02*
Y879300D01*
G01X129820Y879230D02*
Y878540D01*
G01X128830Y879410D02*
X128810Y879440D01*
G01X128860Y879400D02*
X128830Y879410D01*
G01X129060Y879400D02*
X128860D01*
G01X129100Y879390D02*
X129060Y879400D01*
G01X129150Y879370D02*
X129100Y879390D01*
G01X129210Y879320D02*
X129150Y879370D01*
G01X129250Y879230D02*
X129210Y879320D01*
G01X129410Y878960D02*
X129250Y879230D01*
G01X128820Y879440D02*
Y880270D01*
G01X129010Y879400D02*
Y882290D01*
G01X129210Y882280D02*
Y879300D01*
G01X129820Y879350D02*
Y880320D01*
G01X130010D02*
Y879400D01*
G01X130210Y879310D02*
Y880420D01*
G01X136410Y881640D02*
Y882270D01*
G01X136210Y882080D02*
Y881460D01*
G01X136010Y881270D02*
Y881890D01*
G01X135820Y881710D02*
Y881080D01*
G01X135710Y880990D02*
Y881610D01*
G01X135620Y881520D02*
Y880900D01*
G01X135510Y880810D02*
Y881430D01*
G01X135410Y881330D02*
Y880710D01*
G01X135320Y880620D02*
Y881240D01*
G01X135210Y881150D02*
Y880530D01*
G01X135120Y880430D02*
Y881060D01*
G01X135010Y880960D02*
Y880340D01*
G01X134910Y880250D02*
Y880870D01*
G01X134820Y880780D02*
Y880150D01*
G01X134710Y880060D02*
Y880680D01*
G01X134620Y880590D02*
Y879970D01*
G01X134510Y879880D02*
Y880500D01*
G01X134320Y880310D02*
Y879690D01*
G01X134120Y879500D02*
Y880120D01*
G01X133910Y879940D02*
Y878740D01*
G01X133820Y878730D02*
Y879850D01*
G01X134540Y881700D02*
X134580Y881740D01*
G01X130120Y880320D02*
Y879400D01*
G01X130220Y880420D02*
X130120Y880320D01*
G01X129910Y879400D02*
Y880320D01*
G01X129210Y881650D02*
X129320Y881760D01*
G01X129240Y881380D02*
X129210Y881650D01*
G01X129270Y881100D02*
X129240Y881380D01*
G01X129280Y880980D02*
X129270Y881100D01*
G01X129300Y880880D02*
X129280Y880980D01*
G01X129340Y880630D02*
X129300Y880880D01*
G01X129340Y880620D02*
Y880630D01*
G01X129360Y880530D02*
X129340Y880620D01*
G01X129360Y880520D02*
Y880530D01*
G01X129380Y880400D02*
X129360Y880520D01*
G01X129480Y880320D02*
X129380Y880400D01*
G01X130120Y880320D02*
X129480D01*
G01X128810Y880260D02*
Y879440D01*
G01X128820Y880280D02*
X128810Y880260D01*
G01X128830Y880310D02*
X128820Y880280D01*
G01X128850Y880340D02*
X128830Y880310D01*
G01X128870Y880420D02*
X128850Y880340D01*
G01X128860Y880440D02*
X128870Y880420D01*
G01X128820Y880680D02*
X128860Y880440D01*
G01X128750Y881180D02*
X128820Y880680D01*
G01X128740Y881300D02*
X128750Y881180D01*
G01X128740Y881360D02*
Y881300D01*
G01X128720Y881520D02*
X128740Y881360D01*
G01X128710Y881660D02*
X128720Y881520D01*
G01X129320Y879120D02*
Y880770D01*
G01X129620Y880320D02*
Y878750D01*
G01X130220Y880420D02*
Y886260D01*
G01X128710Y884330D02*
Y881640D01*
G01Y881660D02*
X128610Y881760D01*
G01X136590Y882570D02*
X135120Y884000D01*
G01X135210Y883900D02*
Y884540D01*
G01X135410Y884350D02*
Y883710D01*
G01X135510Y883620D02*
Y884250D01*
G01X135620Y884160D02*
Y883520D01*
G01X135710Y883420D02*
Y884060D01*
G01X135820Y883970D02*
Y883330D01*
G01X135910Y883230D02*
Y883870D01*
G01X136010Y883770D02*
Y883130D01*
G01X136120Y883040D02*
Y883680D01*
G01X136210Y883580D02*
Y882940D01*
G01X136320Y882850D02*
Y883480D01*
G01X136410Y883390D02*
Y882750D01*
G01X136320Y882170D02*
Y881550D01*
G01X136120Y881360D02*
Y881990D01*
G01X135910Y881800D02*
Y881180D01*
G01X134580Y881790D02*
Y884280D01*
G01Y881740D02*
Y881790D01*
G01X134820Y884290D02*
Y884930D01*
G01X135010Y884740D02*
Y884100D01*
G01X134510Y885220D02*
Y881700D01*
G01X133550Y881740D02*
Y881790D01*
G01X133590Y881700D02*
X133550Y881740D01*
G01X134540Y881700D02*
X133590D01*
G01X133710D02*
Y884960D01*
G01X133910Y884990D02*
Y881700D01*
G01X134120D02*
Y885610D01*
G01X134320Y885410D02*
Y881700D01*
G01X129660Y881760D02*
X129320D01*
G01X129710Y881800D02*
X129660Y881760D01*
G01X129320Y881750D02*
Y884380D01*
G01X129710Y884250D02*
Y881800D01*
G01X129660Y884300D02*
X129710Y884250D01*
G01X129380Y884300D02*
X129660D01*
G01X129620Y881760D02*
Y884300D01*
G01X129510D02*
Y881760D01*
G01X129410D02*
Y884300D01*
G01X129100Y883850D02*
X129140D01*
G01X129000Y883750D02*
X129100Y883850D01*
G01X129000Y882310D02*
Y883750D01*
G01X129100Y882210D02*
X129000Y882310D01*
G01X129140Y882210D02*
X129100D01*
G01X129250Y882310D02*
X129140Y882210D01*
G01X129250Y883750D02*
Y882310D01*
G01X129140Y883850D02*
X129250Y883750D01*
G01X129120Y883850D02*
Y885820D01*
G01X129010Y885530D02*
Y883760D01*
G01X128580Y881760D02*
X128610D01*
G01X128540Y881800D02*
X128580Y881760D01*
G01X128540Y884250D02*
Y881800D01*
G01X128580Y884300D02*
X128540Y884250D01*
G01X128680Y884300D02*
X128580D01*
G01X128620Y881750D02*
Y884300D01*
G01X129120Y882210D02*
Y879380D01*
G01X128910Y879400D02*
Y885160D01*
G01X128780Y884380D02*
X128680Y884300D01*
G01X128780Y884430D02*
Y884380D01*
G01X128870Y884990D02*
X128780Y884430D01*
G01X128910Y885170D02*
X128870Y884990D01*
G01X128820Y884610D02*
Y880740D01*
G01X129350Y884810D02*
X129440Y885220D01*
G01X129300Y884520D02*
X129350Y884810D01*
G01X129300Y884490D02*
Y884520D01*
G01X129280Y884410D02*
X129300Y884490D01*
G01X129380Y884300D02*
X129280Y884410D01*
G01X129320Y884600D02*
Y886190D01*
G01X133550Y884910D02*
Y881790D01*
G01X133620Y881700D02*
Y884960D01*
G01X133590Y884950D02*
X133550Y884910D01*
G01X133940Y885130D02*
X133740Y885330D01*
G01X133970Y885020D02*
X133940Y885130D01*
G01X133870Y884960D02*
X133970Y885020D01*
G01X133690Y884960D02*
X133870D01*
G01X133680D02*
X133690D01*
G01X133590Y884950D02*
X133680Y884960D01*
G01X133910Y885160D02*
Y885800D01*
G01X133820Y884960D02*
Y881700D01*
G01X135320Y883810D02*
Y884450D01*
G01X134640Y884370D02*
X134580Y884280D01*
G01X134750Y884350D02*
X134640Y884370D01*
G01X135120Y884000D02*
X134750Y884350D01*
G01X135120Y884640D02*
Y884000D01*
G01X134620Y884330D02*
Y885120D01*
G01X134710Y885030D02*
Y884360D01*
G01X134910Y884200D02*
Y884830D01*
G01X139920Y885750D02*
X133690Y886260D01*
G01X133710Y885350D02*
X133740Y885330D01*
G01X133710Y885990D02*
Y885350D01*
G01D02*
X132870Y886160D01*
G01X133320Y885740D02*
Y888000D01*
G01X133510D02*
Y885550D01*
G01X133820Y885250D02*
Y885890D01*
G01X134010Y885700D02*
Y881700D01*
G01X134210D02*
Y885510D01*
G01X134410Y885310D02*
Y881700D01*
G01X129520Y885500D02*
X129440Y885220D01*
G01X129530Y885510D02*
X129520Y885500D01*
G01X129560Y885620D02*
X129530Y885510D01*
G01X129570Y885620D02*
X129560D01*
G01X129610Y885730D02*
X129570Y885620D01*
G01X129620Y885740D02*
X129610Y885730D01*
G01X129620Y886600D02*
Y885740D01*
G01X129510Y885460D02*
Y886490D01*
G01X128950Y885290D02*
X128910Y885170D01*
G01X128970Y885400D02*
X128950Y885290D01*
G01X129050Y885640D02*
X128970Y885400D01*
G01X129090Y885750D02*
X129050Y885640D01*
G01X129110Y885810D02*
X129090Y885750D01*
G01X129410Y885100D02*
Y886350D01*
G01X129210Y886030D02*
Y883780D01*
G01X130170Y886350D02*
X130220Y886260D01*
G01X130070Y886340D02*
X130170Y886350D01*
G01X129960Y886270D02*
X130070Y886340D01*
G01X129940Y886250D02*
X129960Y886270D01*
G01X129720Y885950D02*
X129940Y886250D01*
G01X129710Y885940D02*
X129720Y885950D01*
G01X129710Y885930D02*
Y885940D01*
G01X129620Y885740D02*
X129710Y885930D01*
G01X130210Y886270D02*
Y887990D01*
G01X130010Y887970D02*
Y886310D01*
G01X129820Y886080D02*
Y887890D01*
G01X131820Y888000D02*
Y886220D01*
G01X132840Y886190D02*
X132870Y886160D01*
G01X132780Y886220D02*
X132840Y886190D01*
G01X131760Y886220D02*
X132780D01*
G01X132910Y886120D02*
Y886790D01*
G01X132710Y886960D02*
Y886220D01*
G01X132510D02*
Y887150D01*
G01X132320Y887340D02*
Y886220D01*
G01X132210D02*
Y888000D01*
G01X132010D02*
Y886220D01*
G01X131680Y886330D02*
X131580Y886430D01*
G01X131680Y886260D02*
Y886330D01*
G01X131720Y886220D02*
X131680Y886260D01*
G01X131760Y886220D02*
X131720D01*
G01X133120Y885930D02*
Y888000D01*
G01X133820Y886720D02*
Y886250D01*
G01X133610Y886090D02*
X136940Y882880D01*
G01X133590Y886200D02*
X133610Y886090D01*
G01X133690Y886260D02*
X133590Y886200D01*
G01X136410Y886040D02*
Y886510D01*
G01X136210Y886520D02*
Y886060D01*
G01X136010Y886070D02*
Y886540D01*
G01X135820Y886560D02*
Y886090D01*
G01X135620Y886110D02*
Y886570D01*
G01X135410Y886590D02*
Y886120D01*
G01X135210Y886140D02*
Y886610D01*
G01X135010Y886620D02*
Y886160D01*
G01X134820Y886170D02*
Y886640D01*
G01X134620Y886650D02*
Y886190D01*
G01X134410Y886200D02*
Y886670D01*
G01X134210Y886690D02*
Y886220D01*
G01X134010Y886240D02*
Y886700D01*
G01X133620Y886090D02*
Y885450D01*
G01X129170Y885960D02*
X129110Y885810D01*
G01X129180Y885970D02*
X129170Y885960D01*
G01X129460Y887220D02*
X129450Y887280D01*
G01X129460Y887210D02*
Y887220D01*
G01X129490Y887100D02*
X129460Y887210D01*
G01X129490Y887090D02*
Y887100D01*
G01X129540Y886960D02*
X129490Y887090D01*
G01X129550Y886960D02*
X129540D01*
G01X129580Y886900D02*
X129550Y886960D01*
G01X129600Y886880D02*
X129580Y886900D01*
G01X129650Y886820D02*
X129600Y886880D01*
G01X129670Y886800D02*
X129650Y886820D01*
G01X129670Y886660D02*
Y886800D01*
G01X129500Y886480D02*
X129670Y886660D01*
G01X129490Y886470D02*
X129500Y886480D01*
G01X129180Y885970D02*
X129490Y886470D01*
G01X129510Y887030D02*
Y887550D01*
G01X130820Y887600D02*
Y886440D01*
G01X130870Y886490D02*
X131580Y886430D01*
G01X131620Y886400D02*
Y886950D01*
G01X130890Y887240D02*
X130900Y887270D01*
G01X130880Y887160D02*
X130890Y887240D01*
G01X130860Y887090D02*
X130880Y887160D01*
G01X130860Y887080D02*
Y887090D01*
G01X130950Y886950D02*
X130860Y887080D01*
G01X131560Y886900D02*
X130950Y886950D01*
G01X131670Y887000D02*
X131560Y886900D01*
G01X130910Y887000D02*
Y886490D01*
G01X130760Y886390D02*
Y879040D01*
G01X130870Y886490D02*
X130760Y886390D01*
G01X133010Y886030D02*
Y886850D01*
G01X132860Y886820D02*
X132280Y887370D01*
G01X132910Y886790D02*
X132860Y886820D01*
G01X132950Y886790D02*
X132910D01*
G01X133060Y886890D02*
X132950Y886790D01*
G01X132410Y887250D02*
Y886220D01*
G01X132620D02*
Y887050D01*
G01X132820Y886860D02*
Y886200D01*
G01X133620Y886220D02*
Y886750D01*
G01X133630Y886740D02*
X140560Y886170D01*
G01X136320Y886050D02*
Y886510D01*
G01X136120Y886530D02*
Y886070D01*
G01X135910Y886080D02*
Y886550D01*
G01X135710Y886570D02*
Y886100D01*
G01X135510Y886110D02*
Y886580D01*
G01X135320Y886600D02*
Y886130D01*
G01X135120Y886150D02*
Y886610D01*
G01X134910Y886630D02*
Y886160D01*
G01X134710Y886180D02*
Y886640D01*
G01X134510Y886660D02*
Y886200D01*
G01X134320Y886210D02*
Y886680D01*
G01X134120Y886700D02*
Y886230D01*
G01X133910Y886240D02*
Y886710D01*
G01X133710Y886730D02*
Y886260D01*
G01X133630Y886740D02*
X133540Y886830D01*
G01X131680Y887160D02*
Y887280D01*
G01X131670Y887000D02*
X131680Y887160D01*
G01X131510Y886910D02*
Y886440D01*
G01X131410Y886450D02*
Y886920D01*
G01X131320D02*
Y886460D01*
G01X131210D02*
Y886930D01*
G01X131120Y886940D02*
Y886470D01*
G01X131010Y886480D02*
Y886950D01*
G01X129450Y887350D02*
Y887280D01*
G01X129460Y887360D02*
X129450Y887350D01*
G01X129530Y887620D02*
X129460Y887360D01*
G01X129540Y887630D02*
X129530Y887620D01*
G01X129710Y887830D02*
X129540Y887630D01*
G01X129720Y887840D02*
X129710Y887830D01*
G01X129950Y887960D02*
X129720Y887840D01*
G01X129970Y887970D02*
X129950Y887960D01*
G01X130250Y887990D02*
X129970Y887970D01*
G01X130260Y887990D02*
X130250D01*
G01X130520Y887910D02*
X130260Y887990D01*
G01X130530Y887900D02*
X130520Y887910D01*
G01X130730Y887740D02*
X130530Y887900D01*
G01X130750Y887730D02*
X130730Y887740D01*
G01X130870Y887500D02*
X130750Y887730D01*
G01X130870Y887480D02*
Y887500D01*
G01X130890Y887360D02*
X130870Y887480D01*
G01X130890Y887350D02*
Y887360D01*
G01X130900Y887290D02*
X130890Y887350D01*
G01X130900Y887270D02*
Y887290D01*
G01X129620Y886860D02*
Y887720D01*
G01X129710Y887830D02*
Y885940D01*
G01X129910Y886220D02*
Y887940D01*
G01X130120Y887980D02*
Y886350D01*
G01X130620Y887840D02*
Y877730D01*
G01X130410D02*
Y887940D01*
G01X130710Y888250D02*
Y888880D01*
G01X130620Y888980D02*
Y888350D01*
G01X130510Y888440D02*
Y889080D01*
G01X130410Y889170D02*
Y888540D01*
G01X130320Y888640D02*
Y889270D01*
G01X130210Y889360D02*
Y888740D01*
G01X130120Y888830D02*
Y889460D01*
G01X130010Y889560D02*
Y888930D01*
G01X129910Y889030D02*
Y889660D01*
G01X129710Y889850D02*
Y889220D01*
G01X129510Y889410D02*
Y890040D01*
G01X130820Y888790D02*
Y888160D01*
G01X130910Y888060D02*
Y888690D01*
G01X131010Y888590D02*
Y887960D01*
G01X131120Y887860D02*
Y888500D01*
G01X131210Y888400D02*
Y887770D01*
G01X131320Y887670D02*
Y888310D01*
G01X131410Y888210D02*
Y887580D01*
G01X131510Y887480D02*
Y888110D01*
G01X133540Y887960D02*
Y886830D01*
G01X133520Y888000D02*
X133540Y887960D01*
G01X133510Y888000D02*
X133520D01*
G01X131690D02*
X133510D01*
G01X131680D02*
X131690D01*
G01X131600Y888030D02*
X131680Y888000D01*
G01X132260Y887480D02*
X132280Y887370D01*
G01X132360Y887540D02*
X132260Y887480D01*
G01X132960Y887540D02*
X132360D01*
G01X133060Y887440D02*
X132960Y887540D01*
G01X133060Y886890D02*
Y887440D01*
G01X132320Y887510D02*
Y888000D01*
G01X132410D02*
Y887540D01*
G01X132510D02*
Y888000D01*
G01X132620D02*
Y887540D01*
G01X132710D02*
Y888000D01*
G01X132820D02*
Y887540D01*
G01X132910D02*
Y888000D01*
G01X133010D02*
Y887490D01*
G01X133210Y888000D02*
Y885830D01*
G01X133410Y885640D02*
Y888000D01*
G01X132120D02*
Y886220D01*
G01X131910D02*
Y888000D01*
G01X131710D02*
Y886220D01*
G01X131680Y887280D02*
X131650Y887350D01*
G01X131620Y887380D02*
Y888020D01*
G01X131650Y887350D02*
X126910Y891930D01*
G01X127520Y891960D02*
X131600Y888030D01*
G01X129820Y889120D02*
Y889750D01*
G01X129620Y889940D02*
Y889310D01*
G01X129410Y889510D02*
Y890140D01*
G01X129320Y890240D02*
Y889610D01*
G01X129210Y889700D02*
Y890330D01*
G01X129120Y890430D02*
Y889800D01*
G01X129010Y889900D02*
Y890520D01*
G01X128910Y890620D02*
Y889990D01*
G01X128710Y890180D02*
Y890810D01*
G01X128510Y891010D02*
Y890380D01*
G01X128320Y890570D02*
Y891200D01*
G01X128410Y891100D02*
Y890480D01*
G01X128210Y890670D02*
Y891290D01*
G01X128120Y891390D02*
Y890760D01*
G01X128010Y890860D02*
Y891490D01*
G01X127910Y891590D02*
Y890960D01*
G01X127820Y891050D02*
Y891680D01*
G01X127710Y891780D02*
Y891150D01*
G01X127620Y891250D02*
Y891870D01*
G01X127410Y891980D02*
Y891440D01*
G01X127490Y891970D02*
X127410Y891980D01*
G01X127520Y891960D02*
X127490Y891970D01*
G01X127510Y891350D02*
Y891960D01*
G01X126920Y891980D02*
X126910Y891930D01*
G01X127410Y891980D02*
X126920D01*
G01X126910Y891920D02*
Y891960D01*
G01X127010Y891980D02*
Y891830D01*
G01X127120Y891730D02*
Y891980D01*
G01X127210D02*
Y891630D01*
G01X127320Y891540D02*
Y891980D01*
G01X128620Y890910D02*
Y890280D01*
G01X128820Y890090D02*
Y890720D01*
G01X144410Y875670D02*
Y875010D01*
G01X144320Y875110D02*
Y875770D01*
G01X144210Y875860D02*
Y875210D01*
G01X144120Y875310D02*
Y875960D01*
G01X144010Y876060D02*
Y875400D01*
G01X143910Y875500D02*
Y876150D01*
G01X143820Y876250D02*
Y875600D01*
G01X143710Y875690D02*
Y876350D01*
G01X143620Y876440D02*
Y875790D01*
G01X143510Y875880D02*
Y876540D01*
G01X143410Y876640D02*
Y875980D01*
G01X143320Y876080D02*
Y876730D01*
G01X143210Y876830D02*
Y876185D01*
G01Y876180D02*
Y876230D01*
G01X143120Y876270D02*
Y876310D01*
G01Y876270D02*
Y876920D01*
G01X143010Y877020D02*
Y876370D01*
G01X142910Y876470D02*
Y877120D01*
G01X142820Y877220D02*
Y876560D01*
G01X142710Y876660D02*
Y877310D01*
G01X142620Y877410D02*
Y876750D01*
G01X142510Y876850D02*
Y877510D01*
G01X142410Y877600D02*
Y876950D01*
G01X142320Y877050D02*
Y877700D01*
G01X142210Y877790D02*
Y877140D01*
G01X142120Y877240D02*
Y877890D01*
G01X142010Y877990D02*
Y877330D01*
G01X141910Y877430D02*
Y878090D01*
G01X141820Y878180D02*
Y877530D01*
G01X141710Y877620D02*
Y878280D01*
G01X141510Y878470D02*
Y877820D01*
G01X141320Y878010D02*
Y878660D01*
G01X136910Y879460D02*
Y878990D01*
G01X136710Y878980D02*
Y879440D01*
G01X136510Y879420D02*
Y878960D01*
G01X138510Y879130D02*
Y879600D01*
G01X138710Y879610D02*
Y879140D01*
G01X138910Y879160D02*
Y879630D01*
G01X139120Y879650D02*
Y879180D01*
G01X139320Y879200D02*
Y879670D01*
G01X139410Y879710D02*
Y879210D01*
G01X140060Y879220D02*
X140170Y879120D01*
G01X139990Y879250D02*
X140060Y879220D01*
G01X140210Y879070D02*
Y879760D01*
G01X140410D02*
Y878880D01*
G01X140620Y878690D02*
Y879780D01*
G01X140820Y879140D02*
Y878490D01*
G01X140910Y878400D02*
Y879050D01*
G01X141010Y878950D02*
Y878300D01*
G01X141120Y878200D02*
Y878860D01*
G01X141210Y878760D02*
Y878110D01*
G01X141410Y877920D02*
Y878570D01*
G01X141620Y878370D02*
Y877720D01*
G01X138210Y879100D02*
Y879570D01*
G01X138010Y879550D02*
Y879090D01*
G01X137820Y879070D02*
Y879540D01*
G01X137620Y879520D02*
Y879050D01*
G01X137410Y879030D02*
Y879500D01*
G01X137210Y879490D02*
Y879020D01*
G01X137120Y879010D02*
Y879480D01*
G01X137010Y879470D02*
Y879000D01*
G01X136820Y878980D02*
Y879450D01*
G01X136620Y879440D02*
Y878970D01*
G01X137320Y879490D02*
Y879030D01*
G01X137510Y879040D02*
Y879510D01*
G01X137710Y879530D02*
Y879060D01*
G01X137910Y879080D02*
Y879550D01*
G01X138120Y879560D02*
Y879090D01*
G01X138320Y879110D02*
Y879580D01*
G01X138410Y879590D02*
Y879120D01*
G01X139930Y879250D02*
X139990D01*
G01X138470Y879120D02*
X139930Y879250D01*
G01X140010Y879240D02*
Y879920D01*
G01X140190Y879770D02*
X140260Y879750D01*
G01X140110Y879820D02*
X140190Y879770D01*
G01X140320Y879750D02*
Y878980D01*
G01X140510Y878790D02*
Y879770D01*
G01X140820Y879790D02*
Y879290D01*
G01X140780Y879260D02*
X140800Y879160D01*
G01X143220Y879530D02*
Y879640D01*
G01X143210Y879530D02*
X143220D01*
G01X140860Y879330D02*
X143210Y879530D01*
G01X140780Y879260D02*
X140860Y879330D01*
G01X143120Y879630D02*
Y879520D01*
G01Y879525D02*
Y885120D01*
G01X143210Y885185D02*
Y879530D01*
G01X144260Y879770D02*
Y880660D01*
G01X144220Y879730D02*
X144260Y879770D01*
G01X143540Y879730D02*
X144220D01*
G01X143470Y879700D02*
X143540Y879730D01*
G01X143310Y879550D02*
X143470Y879700D01*
G01X143290Y879540D02*
X143310Y879550D01*
G01X143230Y879530D02*
X143290Y879540D01*
G01X144210Y880700D02*
Y879730D01*
G01X144010D02*
Y880700D01*
G01X143820D02*
Y879730D01*
G01X143620D02*
Y880700D01*
G01X142910Y879980D02*
Y879510D01*
G01X142820Y879490D02*
Y879960D01*
G01X142620Y879950D02*
Y879480D01*
G01X142410Y879460D02*
Y879930D01*
G01X142210Y879910D02*
Y879440D01*
G01X142010Y879430D02*
Y879900D01*
G01X141820Y879880D02*
Y879410D01*
G01X141620Y879390D02*
Y879860D01*
G01X141410Y879850D02*
Y879380D01*
G01X141210Y879360D02*
Y879830D01*
G01X141010Y879810D02*
Y879350D01*
G01X139820Y879240D02*
Y880110D01*
G01X139620Y880300D02*
Y879220D01*
G01X139210Y879190D02*
Y879660D01*
G01X138620Y879610D02*
Y879140D01*
G01X138820Y879150D02*
Y879620D01*
G01X139010Y879640D02*
Y879170D01*
G01X139450Y879740D02*
X139420Y879840D01*
G01X139360Y879670D02*
X139450Y879740D01*
G01X143410Y879650D02*
Y885430D01*
G01X142840Y879970D02*
X140260Y879750D01*
G01X142910Y879970D02*
X142840D01*
G01X143000Y880070D02*
X142910Y879970D01*
G01X143000Y884170D02*
Y880070D01*
G01X140120Y879820D02*
Y879170D01*
G01X139910Y879250D02*
Y880010D01*
G01X140110Y879830D02*
Y879820D01*
G01X140100Y879830D02*
X140110D01*
G01X140100D02*
X137410Y882420D01*
G01X137620Y882230D02*
Y881590D01*
G01X137820Y881390D02*
Y882040D01*
G01X138010Y881850D02*
Y881200D01*
G01X138210Y881010D02*
Y881650D01*
G01X138320Y881560D02*
Y880910D01*
G01X138260Y880960D02*
X139420Y879840D01*
G01X139410Y879850D02*
Y880490D01*
G01X139510Y880400D02*
Y879220D01*
G01X139710Y879230D02*
Y880210D01*
G01X139320Y879950D02*
Y880590D01*
G01X139210Y880690D02*
Y880050D01*
G01X139120Y880140D02*
Y880790D01*
G01X139010Y880880D02*
Y880240D01*
G01X138910Y880330D02*
Y880980D01*
G01X138820Y881070D02*
Y880430D01*
G01X138710Y880530D02*
Y881170D01*
G01X138620Y881270D02*
Y880620D01*
G01X138510Y880720D02*
Y881360D01*
G01X138410Y881460D02*
Y880810D01*
G01X140710Y879790D02*
Y878590D01*
G01X140910Y879330D02*
Y879800D01*
G01X141120Y879820D02*
Y879350D01*
G01X141320Y879370D02*
Y879840D01*
G01X141510Y879850D02*
Y879380D01*
G01X141710Y879400D02*
Y879870D01*
G01X141910Y879890D02*
Y879420D01*
G01X142120Y879440D02*
Y879900D01*
G01X142320Y879920D02*
Y879460D01*
G01X142510Y879470D02*
Y879940D01*
G01X142710Y879960D02*
Y879490D01*
G01X143510Y879720D02*
Y880770D01*
G01X144220Y880700D02*
X144260Y880660D01*
G01X143580Y880700D02*
X144220D01*
G01X143480Y880800D02*
X143580Y880700D01*
G01X144120D02*
Y879730D01*
G01X143910D02*
Y880700D01*
G01X143710D02*
Y879730D01*
G01X142530Y884270D02*
X142520D01*
G01X142600Y884260D02*
X142530Y884270D01*
G01X142860Y884260D02*
X142600D01*
G01X142880Y884270D02*
X142860Y884260D01*
G01X143000Y884170D02*
X142880Y884270D01*
G01X142510D02*
Y885040D01*
G01X142710Y885000D02*
Y884260D01*
G01X142910Y884240D02*
Y885040D01*
G01X137080Y882880D02*
X136940D01*
G01X139980Y885580D02*
X137080Y882880D01*
G01X136910Y882900D02*
Y882110D01*
G01X137070Y882120D02*
X138260Y880960D01*
G01X136930Y882120D02*
X137070D01*
G01X138120Y881110D02*
Y881750D01*
G01X137910Y881940D02*
Y881300D01*
G01X137710Y881490D02*
Y882140D01*
G01X137510Y882330D02*
Y881680D01*
G01X137410Y882570D02*
X139230Y884250D01*
G01X137410Y882420D02*
Y882570D01*
G01Y881780D02*
Y882420D01*
G01X139210Y884240D02*
Y884870D01*
G01X139010Y884680D02*
Y884050D01*
G01X138820Y883870D02*
Y884500D01*
G01X138620Y884310D02*
Y883680D01*
G01X138510Y883590D02*
Y884220D01*
G01X138410Y884120D02*
Y883490D01*
G01X138320Y883400D02*
Y884030D01*
G01X138210Y883940D02*
Y883310D01*
G01X138120Y883220D02*
Y883850D01*
G01X138010Y883750D02*
Y883120D01*
G01X137910Y883030D02*
Y883660D01*
G01X137820Y883570D02*
Y882940D01*
G01X137710Y882850D02*
Y883480D01*
G01X137620Y883380D02*
Y882750D01*
G01X137510Y882660D02*
Y883290D01*
G01X137410Y883200D02*
Y882550D01*
G01X137120Y882920D02*
Y882070D01*
G01X137010Y882120D02*
Y882880D01*
G01X136820Y883000D02*
Y882010D01*
G01X136710Y881920D02*
Y883100D01*
G01X136620Y883200D02*
Y881830D01*
G01X136510Y881740D02*
Y882360D01*
G01X136590Y882430D02*
Y882570D01*
G01X136510Y882650D02*
Y883290D01*
G01X137210Y883010D02*
Y881980D01*
G01X137320Y881880D02*
Y883100D01*
G01X138710Y884400D02*
Y883770D01*
G01X138910Y883960D02*
Y884590D01*
G01X139120Y884770D02*
Y884140D01*
G01X139320Y884330D02*
Y884960D01*
G01X139410Y885050D02*
Y884420D01*
G01X139510Y884510D02*
Y885150D01*
G01X139620Y885240D02*
Y884610D01*
G01X139710Y884700D02*
Y885330D01*
G01X139910Y885520D02*
Y884890D01*
G01X140120Y885070D02*
Y886210D01*
G01X140210Y886200D02*
Y885170D01*
G01X142340Y884310D02*
X142520Y884270D01*
G01X142330Y884310D02*
X142340D01*
G01X142020Y884420D02*
X142330Y884310D01*
G01X142010Y884430D02*
X142020Y884420D01*
G01X141700Y884640D02*
X142010Y884430D01*
G01X141690Y884650D02*
X141700Y884640D01*
G01X141470Y884890D02*
X141690Y884650D01*
G01X141470Y884900D02*
Y884890D01*
G01X141390Y885020D02*
X141470Y884900D01*
G01X141380Y885030D02*
X141390Y885020D01*
G01X141350Y885090D02*
X141380Y885030D01*
G01X141280Y885250D02*
X141350Y885090D01*
G01X142620Y884260D02*
Y885020D01*
G01X143010Y885060D02*
Y879510D01*
G01X142990Y885050D02*
X143010Y885060D01*
G01X142730Y885000D02*
X142990Y885050D01*
G01X142720Y885000D02*
X142730D01*
G01X142700D02*
X142720D01*
G01X143320Y879550D02*
Y885290D01*
G01X143250Y885210D02*
X143160Y885150D01*
G01X143260Y885220D02*
X143250Y885210D01*
G01X143270Y885230D02*
X143260Y885220D01*
G01X143020Y885070D02*
X143010Y885060D01*
G01X143150Y885150D02*
X143020Y885070D01*
G01X142820Y885020D02*
Y884260D01*
G01X142410Y884290D02*
Y885060D01*
G01X142440Y885050D02*
X142700Y885000D01*
G01X142420Y885060D02*
X142440Y885050D01*
G01X142690Y885280D02*
X142670Y885290D01*
G01X142160Y885230D02*
X142000Y885450D01*
G01X142170Y885220D02*
X142160Y885230D01*
G01X142190Y885210D02*
X142170Y885220D01*
G01X142400Y885070D02*
X142190Y885210D01*
G01X142420Y885060D02*
X142400Y885070D01*
G01X142120Y885290D02*
Y884390D01*
G01X142210Y884350D02*
Y885190D01*
G01X142320Y885120D02*
Y884310D01*
G01X141910Y884490D02*
Y885750D01*
G01X141320Y885160D02*
Y886830D01*
G01X141410Y886920D02*
Y884980D01*
G01X141620Y884740D02*
Y887110D01*
G01X141820Y887290D02*
Y884570D01*
G01X143210Y885150D02*
Y885190D01*
G01X143270Y885230D02*
X143430Y885450D01*
G01X144010Y885020D02*
Y886570D01*
G01X143910Y886730D02*
Y884840D01*
G01X143480Y884400D02*
Y880800D01*
G01X143510Y884480D02*
X143480Y884400D01*
G01X143520Y884490D02*
X143510Y884480D01*
G01X143530Y884490D02*
X143520D01*
G01X143600Y884530D02*
X143530Y884490D01*
G01X143600Y884540D02*
Y884530D01*
G01X143610Y884550D02*
X143600Y884540D01*
G01X143710Y884620D02*
X143610Y884550D01*
G01X143720Y884630D02*
X143710Y884620D01*
G01X143940Y884860D02*
X143720Y884630D01*
G01X143710D02*
Y886970D01*
G01X143950Y884880D02*
X143940Y884860D01*
G01X144250Y885680D02*
X144240Y886020D01*
G01X144250Y885670D02*
Y885680D01*
G01Y885660D02*
Y885670D01*
G01X144230Y885500D02*
X144250Y885660D01*
G01X144230Y885480D02*
Y885500D01*
G01X143950Y884880D02*
X144230Y885480D01*
G01X144210Y886130D02*
Y885460D01*
G01X143440D02*
X143430Y885450D01*
G01X143440Y885480D02*
Y885460D01*
G01X143500Y885650D02*
X143440Y885480D01*
G01X143510Y885870D02*
Y885890D01*
G01Y885740D02*
Y885870D01*
G01X143500Y885670D02*
X143510Y885740D01*
G01X143500Y885650D02*
Y885670D01*
G01X142880Y885310D02*
X142690Y885280D01*
G01X142910Y885320D02*
X142880Y885310D01*
G01X143130Y885490D02*
X142910Y885320D01*
G01X143140Y885510D02*
X143130Y885490D01*
G01X143220Y885680D02*
X143140Y885510D01*
G01X143220Y885690D02*
Y885680D01*
G01X143230Y885730D02*
X143220Y885690D01*
G01X143230Y885790D02*
Y885730D01*
G01Y885810D02*
Y885790D01*
G01X142200Y885840D02*
Y885850D01*
G01Y885750D02*
Y885840D01*
G01X142210Y885730D02*
X142200Y885750D01*
G01X142370Y885420D02*
X142210Y885730D01*
G01X142390Y885400D02*
X142370Y885420D01*
G01X142670Y885290D02*
X142390Y885400D01*
G01X141990Y885460D02*
X142000Y885450D01*
G01X141990Y885480D02*
Y885460D01*
G01X141930Y885650D02*
X141990Y885480D01*
G01X141930Y885670D02*
Y885650D01*
G01X141920Y885740D02*
X141930Y885670D01*
G01X141910Y885760D02*
X141920Y885740D01*
G01X141910Y885820D02*
Y885760D01*
G01X141920Y885850D02*
X141910Y885820D01*
G01X142010Y885430D02*
Y884430D01*
G01X142530Y885340D02*
Y886280D01*
G01X142730Y886300D02*
Y885290D01*
G01X142930Y885340D02*
Y886250D01*
G01X143130Y886070D02*
Y885500D01*
G01X143230Y885810D02*
X143210Y885940D01*
G01X142340Y886140D02*
Y885490D01*
G01X141920Y885890D02*
X141970Y886090D01*
G01X141920Y885850D02*
Y885890D01*
G01X141250Y885340D02*
X141280Y885250D01*
G01X141240Y885350D02*
X141250Y885340D01*
G01X141210Y885490D02*
X141240Y885350D01*
G01X141190Y885570D02*
X141210Y885490D01*
G01X140410Y885350D02*
X139230Y884250D01*
G01X140690Y885610D02*
X140410Y885350D01*
G01X140740Y885640D02*
X140690Y885610D01*
G01X140890Y885670D02*
X140740Y885640D01*
G01X140910Y885680D02*
X140890Y885670D01*
G01X140930Y885680D02*
X140910D01*
G01X141100Y885660D02*
X140930Y885680D01*
G01X141110Y885660D02*
X141100D01*
G01X141190Y885570D02*
X141110Y885660D01*
G01X139820Y884790D02*
Y885430D01*
G01X140000Y885690D02*
X139920Y885750D01*
G01X139980Y885580D02*
X140000Y885690D01*
G01X137910Y885920D02*
Y886380D01*
G01X138120Y886370D02*
Y885900D01*
G01X138320Y885880D02*
Y886350D01*
G01X138510Y886340D02*
Y885870D01*
G01X138710Y885850D02*
Y886320D01*
G01X138910Y886310D02*
Y885840D01*
G01X139120Y885820D02*
Y886290D01*
G01X139320Y886270D02*
Y885810D01*
G01X139510Y885790D02*
Y886250D01*
G01X139710Y886240D02*
Y885770D01*
G01X139910Y885750D02*
Y886220D01*
G01X140410Y886180D02*
Y885350D01*
G01X140620Y885540D02*
Y886180D01*
G01X140820Y886360D02*
Y885660D01*
G01X141010Y885670D02*
Y886550D01*
G01X137120Y885980D02*
Y886450D01*
G01X137010Y886460D02*
Y885990D01*
G01X136820Y886010D02*
Y886480D01*
G01X136620Y886490D02*
Y886030D01*
G01X137320Y885970D02*
Y886440D01*
G01X137510Y886420D02*
Y885950D01*
G01X137710Y885940D02*
Y886400D01*
G01X137820Y886390D02*
Y885930D01*
G01X138010Y885910D02*
Y886380D01*
G01X138210Y886360D02*
Y885890D01*
G01X138410Y885880D02*
Y886350D01*
G01X138620Y886330D02*
Y885860D01*
G01X138820Y885850D02*
Y886310D01*
G01X139010Y886300D02*
Y885830D01*
G01X139210Y885810D02*
Y886280D01*
G01X139410Y886260D02*
Y885800D01*
G01X139620Y885780D02*
Y886250D01*
G01X139820Y886230D02*
Y885760D01*
G01X140010Y886220D02*
Y884980D01*
G01X140320Y885260D02*
Y886190D01*
G01X140510Y886180D02*
Y885450D01*
G01X140710Y885620D02*
Y886260D01*
G01X140650Y886200D02*
X141670Y887160D01*
G01X142010Y887480D02*
Y886150D01*
G01X141990Y886130D02*
X141970Y886090D01*
G01X141990Y886130D02*
X142250Y886440D01*
G01X142430Y886210D02*
Y885380D01*
G01X142630Y885300D02*
Y886290D01*
G01X142300Y886100D02*
X142200Y885850D01*
G01X142310Y886120D02*
X142300Y886100D01*
G01X142510Y886270D02*
X142310Y886120D01*
G01X142540Y886280D02*
X142510Y886270D01*
G01X142230Y885940D02*
Y885670D01*
G01X143210Y885960D02*
Y885940D01*
G01X143070Y886180D02*
X143210Y885960D01*
G01X143050Y886190D02*
X143070Y886180D01*
G01X142820Y886300D02*
X143050Y886190D01*
G01X142800Y886310D02*
X142820Y886300D01*
G01X142540Y886280D02*
X142800Y886310D01*
G01X143410Y886150D02*
Y887170D01*
G01X144240Y886030D02*
Y886020D01*
G01X144170Y886320D02*
X144240Y886030D01*
G01X144160Y886330D02*
X144170Y886320D01*
G01X143850Y886840D02*
X144160Y886330D01*
G01X143460Y886090D02*
X143440Y886130D01*
G01X143510Y885890D02*
X143460Y886090D01*
G01X143030Y886200D02*
Y885420D01*
G01X142840Y885300D02*
Y886300D01*
G01X140630Y886190D02*
X140560Y886170D01*
G01X140640Y886200D02*
X140630Y886190D01*
G01X140650Y886200D02*
X140640D01*
G01X140910Y886450D02*
Y885680D01*
G01X141120Y885650D02*
Y886640D01*
G01X141210Y886730D02*
Y885460D01*
G01X141510Y884850D02*
Y887010D01*
G01X141710Y887200D02*
Y884630D01*
G01X143510Y884480D02*
Y887110D01*
G01X143760Y886930D02*
X143850Y886840D01*
G01X143690Y886990D02*
X143760Y886930D01*
G01X143500Y887120D02*
X143690Y886990D01*
G01X143820Y886880D02*
Y884730D01*
G01X143620Y884550D02*
Y887040D01*
G01X143250Y887240D02*
X143080Y887300D01*
G01X143350Y887200D02*
X143250Y887240D01*
G01X143360Y887200D02*
X143350D01*
G01X143490Y887130D02*
X143360Y887200D01*
G01X143500Y887120D02*
X143490Y887130D01*
G01X143120Y887290D02*
Y886475D01*
G01Y886480D02*
Y886540D01*
G01X143180Y886440D02*
X143440Y886130D01*
G01X143130Y886470D02*
X143180Y886440D01*
G01X143320Y886270D02*
Y887220D01*
G01X143210Y887250D02*
Y886460D01*
G01Y887220D02*
Y887250D01*
G01X142300Y886470D02*
X142250Y886440D01*
G01X142690Y886590D02*
X142300Y886470D01*
G01X142750Y886590D02*
X142690D01*
G01X143130Y886470D02*
X142750Y886590D01*
G01X142210Y886400D02*
Y887660D01*
G01X142410Y887850D02*
Y886510D01*
G01X142620Y886570D02*
Y888030D01*
G01X142820Y887330D02*
Y886570D01*
G01X143010Y886510D02*
Y887310D01*
G01X144120Y886400D02*
Y885240D01*
G01X137620Y885940D02*
Y886410D01*
G01X137410Y886430D02*
Y885960D01*
G01X137210Y885980D02*
Y886440D01*
G01X136910Y886470D02*
Y886000D01*
G01X136710Y886010D02*
Y886480D01*
G01X136510Y886500D02*
Y886030D01*
G01X141910Y887380D02*
Y885830D01*
G01X142120Y886270D02*
Y887570D01*
G01X142320Y887750D02*
Y886480D01*
G01X142510Y886530D02*
Y887940D01*
G01X142710Y888130D02*
Y887440D01*
G01X143060Y887300D02*
X143080D01*
G01X142790Y887340D02*
X143060Y887300D01*
G01X142710Y887400D02*
X142790Y887340D01*
G01X142910Y887320D02*
Y886540D01*
G01X142710Y887400D02*
X142730Y887510D01*
G01X142710Y886590D02*
Y887400D01*
G01X142820Y887590D02*
Y888220D01*
G01X142910Y888310D02*
Y887680D01*
G01X143010Y887770D02*
Y888410D01*
G01X143120Y888460D02*
Y888500D01*
G01Y888510D02*
Y887870D01*
G01X143210Y887960D02*
Y888595D01*
G01Y888590D02*
Y888540D01*
G01X143320Y888695D02*
Y888050D01*
G01X143410Y888140D02*
Y888780D01*
G01X143510Y888870D02*
Y888235D01*
G01X143620Y888335D02*
Y888970D01*
G01X143710Y889060D02*
Y888420D01*
G01X143820Y888525D02*
Y889150D01*
G01X143910Y889250D02*
Y888610D01*
G01X144010Y888700D02*
Y889340D01*
G01X144120Y889430D02*
Y888790D01*
G01X144210Y888880D02*
Y889530D01*
G01X144410Y889710D02*
Y889070D01*
G01X144320Y888980D02*
Y889620D01*
G01X144510Y889800D02*
Y889160D01*
G01X144620Y889260D02*
Y889900D01*
G01X144710Y889990D02*
Y889350D01*
G01X144820Y889440D02*
Y890080D01*
G01X144910Y890180D02*
Y889530D01*
G01X145010Y889630D02*
Y890270D01*
G01X145120Y890360D02*
Y889720D01*
G01X145210Y889810D02*
Y890460D01*
G01X145320Y890550D02*
Y889910D01*
G01X145410Y890000D02*
Y890640D01*
G01X145620Y890830D02*
Y890190D01*
G01X145820Y890370D02*
Y890980D01*
G01X145760Y890970D02*
X141670Y887160D01*
G01X146100Y890640D02*
X146120Y890660D01*
G01X142730Y887510D02*
X146100Y890640D01*
G01X146010Y890560D02*
Y890780D01*
G01X145780Y873700D02*
X140170Y879120D01*
G01X145810Y873670D02*
X145780Y873700D01*
G01X145830Y873680D02*
X145810Y873670D01*
G01X146100Y873990D02*
X145830Y873680D01*
G01X146110Y874020D02*
X146100Y873990D01*
G01Y874040D02*
X146110Y874020D01*
G01X140800Y879160D02*
X146100Y874040D01*
G01X146010Y874120D02*
Y873890D01*
G01X145910Y873770D02*
Y874220D01*
G01X145820Y874320D02*
Y873670D01*
G01X145710Y873760D02*
Y874420D01*
G01X145620Y874510D02*
Y873860D01*
G01X145510Y873950D02*
Y874610D01*
G01X145410Y874700D02*
Y874050D01*
G01X145320Y874140D02*
Y874800D01*
G01X145210Y874900D02*
Y874240D01*
G01X145120Y874340D02*
Y874990D01*
G01X145010Y875090D02*
Y874440D01*
G01X144910Y874530D02*
Y875190D01*
G01X144820Y875280D02*
Y874630D01*
G01X144710Y874730D02*
Y875380D01*
G01X144620Y875480D02*
Y874820D01*
G01X144510Y874920D02*
Y875570D01*
G01X145510Y890740D02*
Y890090D01*
G01X145710Y890280D02*
Y890920D01*
G01X146100Y890690D02*
X146120Y890660D01*
G01X145810Y890980D02*
X146100Y890690D01*
G01X145790Y890990D02*
X145810Y890980D01*
G01X145780D02*
X145790Y890990D01*
G01X145760Y890970D02*
X145780Y890980D01*
G01X145910Y890460D02*
Y890880D01*
G54D18*
G01X27500Y65233D02*
X23500D01*
Y67767D01*
G01X25433Y66833D02*
Y65233D01*
G01X27500Y69333D02*
X23500Y71000D01*
X27500Y72667D01*
G01X26100Y72067D02*
Y69933D01*
G01X27500Y73967D02*
X23500D01*
X27500Y77033D01*
X23500D01*
G01X25833Y78733D02*
X25367Y79200D01*
X25100Y79600D01*
X24967Y80133D01*
X25100Y80600D01*
X25367Y80933D01*
X25767Y81200D01*
X26233Y81267D01*
X26633Y81200D01*
X27033Y80933D01*
X27367Y80533D01*
X27500Y80067D01*
X27367Y79533D01*
X26967Y79067D01*
X26367Y78800D01*
X25700Y78733D01*
X24833Y78867D01*
X24367Y79067D01*
X23900Y79400D01*
X23567Y79867D01*
X23500Y80333D01*
X23633Y80800D01*
X23967Y81133D01*
G01X27500Y500733D02*
X23500D01*
Y503267D01*
G01X25433Y502333D02*
Y500733D01*
G01X27500Y504833D02*
X23500Y506500D01*
X27500Y508167D01*
G01X26100Y507567D02*
Y505433D01*
G01X27500Y509467D02*
X23500D01*
X27500Y512533D01*
X23500D01*
G01X26900Y514033D02*
X27233Y514433D01*
X27433Y514900D01*
X27500Y515500D01*
X27367Y516100D01*
X27100Y516567D01*
X26633Y516900D01*
X26100Y516967D01*
X25567Y516833D01*
X25233Y516500D01*
X24967Y516033D01*
X24900Y515567D01*
X24967Y515100D01*
X25233Y514500D01*
X23500Y514700D01*
Y516500D01*
G01X27000Y761733D02*
X23000D01*
Y764267D01*
G01X24933Y763333D02*
Y761733D01*
G01X27000Y765833D02*
X23000Y767500D01*
X27000Y769167D01*
G01X25600Y768567D02*
Y766433D01*
G01X27000Y770467D02*
X23000D01*
X27000Y773533D01*
X23000D01*
G01X27000Y777300D02*
X23000D01*
X25867Y774833D01*
Y778167D01*
G01X29000Y1198733D02*
X25000D01*
Y1201267D01*
G01X26933Y1200333D02*
Y1198733D01*
G01X29000Y1202833D02*
X25000Y1204500D01*
X29000Y1206167D01*
G01X27600Y1205567D02*
Y1203433D01*
G01X29000Y1207467D02*
X25000D01*
X29000Y1210533D01*
X25000D01*
G01X28200Y1212033D02*
X28667Y1212433D01*
X28933Y1212967D01*
X29000Y1213567D01*
X28933Y1214100D01*
X28600Y1214633D01*
X28200Y1214967D01*
X27800Y1215033D01*
X27333Y1214900D01*
X27000Y1214433D01*
X26867Y1213967D01*
Y1213367D01*
G01Y1213967D02*
X26667Y1214367D01*
X26333Y1214700D01*
X25933Y1214833D01*
X25533Y1214700D01*
X25200Y1214367D01*
X25000Y1213767D01*
X25067Y1213167D01*
X25333Y1212567D01*
G01X28000Y1456733D02*
X24000D01*
Y1459267D01*
G01X25933Y1458333D02*
Y1456733D01*
G01X28000Y1460833D02*
X24000Y1462500D01*
X28000Y1464167D01*
G01X26600Y1463567D02*
Y1461433D01*
G01X28000Y1465467D02*
X24000D01*
X28000Y1468533D01*
X24000D01*
G01X24667Y1470233D02*
X24267Y1470633D01*
X24067Y1471100D01*
X24000Y1471633D01*
X24133Y1472300D01*
X24467Y1472767D01*
X24867Y1472900D01*
X25267Y1472833D01*
X25600Y1472567D01*
X26267Y1471233D01*
X26733Y1470633D01*
X27400Y1470233D01*
X28000Y1470100D01*
Y1472900D01*
G01X29000Y1905233D02*
X25000D01*
Y1907767D01*
G01X26933Y1906833D02*
Y1905233D01*
G01X29000Y1909333D02*
X25000Y1911000D01*
X29000Y1912667D01*
G01X27600Y1912067D02*
Y1909933D01*
G01X29000Y1913967D02*
X25000D01*
X29000Y1917033D01*
X25000D01*
G01X29000Y1920000D02*
X25000D01*
X25800Y1919200D01*
G01X29000D02*
Y1920800D01*
G01X41000Y196733D02*
X37000D01*
Y199267D01*
G01X38933Y198333D02*
Y196733D01*
G01X41000Y200833D02*
X37000Y202500D01*
X41000Y204167D01*
G01X39600Y203567D02*
Y201433D01*
G01X41000Y205467D02*
X37000D01*
X41000Y208533D01*
X37000D01*
G01X39333Y210233D02*
X38867Y210700D01*
X38600Y211100D01*
X38467Y211633D01*
X38600Y212100D01*
X38867Y212433D01*
X39267Y212700D01*
X39733Y212767D01*
X40133Y212700D01*
X40533Y212433D01*
X40867Y212033D01*
X41000Y211567D01*
X40867Y211033D01*
X40467Y210567D01*
X39867Y210300D01*
X39200Y210233D01*
X38333Y210367D01*
X37867Y210567D01*
X37400Y210900D01*
X37067Y211367D01*
X37000Y211833D01*
X37133Y212300D01*
X37467Y212633D01*
G01X42333Y214000D02*
Y218000D01*
G01X37000Y219167D02*
X41000D01*
Y221833D01*
G01Y226333D02*
Y223667D01*
X37000D01*
Y226333D01*
G01X38933Y225267D02*
Y223667D01*
G01X41000Y228033D02*
X37000D01*
Y229367D01*
X37200Y229900D01*
X37467Y230300D01*
X37867Y230633D01*
X38333Y230900D01*
X39000Y230967D01*
X39667Y230900D01*
X40133Y230633D01*
X40533Y230300D01*
X40800Y229900D01*
X41000Y229367D01*
Y228033D01*
G01X46500Y342233D02*
X42500D01*
Y344767D01*
G01X44433Y343833D02*
Y342233D01*
G01X46500Y346333D02*
X42500Y348000D01*
X46500Y349667D01*
G01X45100Y349067D02*
Y346933D01*
G01X46500Y350967D02*
X42500D01*
X46500Y354033D01*
X42500D01*
G01X45900Y355533D02*
X46233Y355933D01*
X46433Y356400D01*
X46500Y357000D01*
X46367Y357600D01*
X46100Y358067D01*
X45633Y358400D01*
X45100Y358467D01*
X44567Y358333D01*
X44233Y358000D01*
X43967Y357533D01*
X43900Y357067D01*
X43967Y356600D01*
X44233Y356000D01*
X42500Y356200D01*
Y358000D01*
G01X47833Y359500D02*
Y363500D01*
G01X42500Y364667D02*
X46500D01*
Y367333D01*
G01Y371833D02*
Y369167D01*
X42500D01*
Y371833D01*
G01X44433Y370767D02*
Y369167D01*
G01X46500Y373533D02*
X42500D01*
Y374867D01*
X42700Y375400D01*
X42967Y375800D01*
X43367Y376133D01*
X43833Y376400D01*
X44500Y376467D01*
X45167Y376400D01*
X45633Y376133D01*
X46033Y375800D01*
X46300Y375400D01*
X46500Y374867D01*
Y373533D01*
G01X41000Y899733D02*
X37000D01*
Y902267D01*
G01X38933Y901333D02*
Y899733D01*
G01X41000Y903833D02*
X37000Y905500D01*
X41000Y907167D01*
G01X39600Y906567D02*
Y904433D01*
G01X41000Y908467D02*
X37000D01*
X41000Y911533D01*
X37000D01*
G01X41000Y915300D02*
X37000D01*
X39867Y912833D01*
Y916167D01*
G01X42333Y917000D02*
Y921000D01*
G01X37000Y922167D02*
X41000D01*
Y924833D01*
G01Y929333D02*
Y926667D01*
X37000D01*
Y929333D01*
G01X38933Y928267D02*
Y926667D01*
G01X41000Y931033D02*
X37000D01*
Y932367D01*
X37200Y932900D01*
X37467Y933300D01*
X37867Y933633D01*
X38333Y933900D01*
X39000Y933967D01*
X39667Y933900D01*
X40133Y933633D01*
X40533Y933300D01*
X40800Y932900D01*
X41000Y932367D01*
Y931033D01*
G01X43000Y1039733D02*
X39000D01*
Y1042267D01*
G01X40933Y1041333D02*
Y1039733D01*
G01X43000Y1043833D02*
X39000Y1045500D01*
X43000Y1047167D01*
G01X41600Y1046567D02*
Y1044433D01*
G01X43000Y1048467D02*
X39000D01*
X43000Y1051533D01*
X39000D01*
G01X42200Y1053033D02*
X42667Y1053433D01*
X42933Y1053967D01*
X43000Y1054567D01*
X42933Y1055100D01*
X42600Y1055633D01*
X42200Y1055967D01*
X41800Y1056033D01*
X41333Y1055900D01*
X41000Y1055433D01*
X40867Y1054967D01*
Y1054367D01*
G01Y1054967D02*
X40667Y1055367D01*
X40333Y1055700D01*
X39933Y1055833D01*
X39533Y1055700D01*
X39200Y1055367D01*
X39000Y1054767D01*
X39067Y1054167D01*
X39333Y1053567D01*
G01X44333Y1057000D02*
Y1061000D01*
G01X39000Y1062167D02*
X43000D01*
Y1064833D01*
G01Y1069333D02*
Y1066667D01*
X39000D01*
Y1069333D01*
G01X40933Y1068267D02*
Y1066667D01*
G01X43000Y1071033D02*
X39000D01*
Y1072367D01*
X39200Y1072900D01*
X39467Y1073300D01*
X39867Y1073633D01*
X40333Y1073900D01*
X41000Y1073967D01*
X41667Y1073900D01*
X42133Y1073633D01*
X42533Y1073300D01*
X42800Y1072900D01*
X43000Y1072367D01*
Y1071033D01*
G01X44000Y1601233D02*
X40000D01*
Y1603767D01*
G01X41933Y1602833D02*
Y1601233D01*
G01X44000Y1605333D02*
X40000Y1607000D01*
X44000Y1608667D01*
G01X42600Y1608067D02*
Y1605933D01*
G01X44000Y1609967D02*
X40000D01*
X44000Y1613033D01*
X40000D01*
G01X40667Y1614733D02*
X40267Y1615133D01*
X40067Y1615600D01*
X40000Y1616133D01*
X40133Y1616800D01*
X40467Y1617267D01*
X40867Y1617400D01*
X41267Y1617333D01*
X41600Y1617067D01*
X42267Y1615733D01*
X42733Y1615133D01*
X43400Y1614733D01*
X44000Y1614600D01*
Y1617400D01*
G01X45333Y1618500D02*
Y1622500D01*
G01X40000Y1623667D02*
X44000D01*
Y1626333D01*
G01Y1630833D02*
Y1628167D01*
X40000D01*
Y1630833D01*
G01X41933Y1629767D02*
Y1628167D01*
G01X44000Y1632533D02*
X40000D01*
Y1633867D01*
X40200Y1634400D01*
X40467Y1634800D01*
X40867Y1635133D01*
X41333Y1635400D01*
X42000Y1635467D01*
X42667Y1635400D01*
X43133Y1635133D01*
X43533Y1634800D01*
X43800Y1634400D01*
X44000Y1633867D01*
Y1632533D01*
G01X50000Y1710233D02*
X46000D01*
Y1712767D01*
G01X47933Y1711833D02*
Y1710233D01*
G01X50000Y1714333D02*
X46000Y1716000D01*
X50000Y1717667D01*
G01X48600Y1717067D02*
Y1714933D01*
G01X50000Y1718967D02*
X46000D01*
X50000Y1722033D01*
X46000D01*
G01X50000Y1725000D02*
X46000D01*
X46800Y1724200D01*
G01X50000D02*
Y1725800D01*
G01X51333Y1727500D02*
Y1731500D01*
G01X46000Y1732667D02*
X50000D01*
Y1735333D01*
G01Y1739833D02*
Y1737167D01*
X46000D01*
Y1739833D01*
G01X47933Y1738767D02*
Y1737167D01*
G01X50000Y1741533D02*
X46000D01*
Y1742867D01*
X46200Y1743400D01*
X46467Y1743800D01*
X46867Y1744133D01*
X47333Y1744400D01*
X48000Y1744467D01*
X48667Y1744400D01*
X49133Y1744133D01*
X49533Y1743800D01*
X49800Y1743400D01*
X50000Y1742867D01*
Y1741533D01*
G01X65500Y1788333D02*
X61500D01*
Y1789667D01*
X61700Y1790200D01*
X61967Y1790600D01*
X62367Y1790933D01*
X62833Y1791200D01*
X63500Y1791267D01*
X64167Y1791200D01*
X64633Y1790933D01*
X65033Y1790600D01*
X65300Y1790200D01*
X65500Y1789667D01*
Y1788333D01*
G01X61833Y1795767D02*
X61633Y1795367D01*
X61500Y1794900D01*
Y1794367D01*
X61700Y1793767D01*
X62033Y1793300D01*
X62433Y1792967D01*
X63100Y1792700D01*
X63700Y1792633D01*
X64300Y1792767D01*
X64700Y1792967D01*
X65100Y1793367D01*
X65367Y1793833D01*
X65500Y1794300D01*
Y1794767D01*
X65367Y1795233D01*
X65167Y1795633D01*
X64900Y1795967D01*
G01X61500Y1802500D02*
Y1804100D01*
G01Y1803300D02*
X65500D01*
G01Y1802500D02*
Y1804100D01*
G01Y1806267D02*
X61500D01*
X65500Y1809333D01*
X61500D01*
G01X65500Y1810967D02*
X61500D01*
Y1812567D01*
X61700Y1813100D01*
X62167Y1813500D01*
X62700Y1813633D01*
X63233Y1813500D01*
X63633Y1813167D01*
X63833Y1812567D01*
Y1810967D01*
G01X61500Y1815333D02*
X64367D01*
X64967Y1815600D01*
X65367Y1816133D01*
X65500Y1816800D01*
X65367Y1817467D01*
X64967Y1818000D01*
X64367Y1818267D01*
X61500D01*
G01Y1821300D02*
X65500D01*
G01X61500Y1819767D02*
Y1822833D01*
G01X65500Y1828967D02*
X61500D01*
Y1830633D01*
X61700Y1831167D01*
X61967Y1831500D01*
X62500Y1831633D01*
X63033Y1831500D01*
X63367Y1831100D01*
X63567Y1830633D01*
Y1828967D01*
G01Y1830633D02*
X65500Y1831633D01*
G01Y1833133D02*
X61500Y1834800D01*
X65500Y1836467D01*
G01X64100Y1835867D02*
Y1833733D01*
G01X61500Y1839300D02*
X65500D01*
G01X61500Y1837767D02*
Y1840833D01*
G01Y1843000D02*
Y1844600D01*
G01Y1843800D02*
X65500D01*
G01Y1843000D02*
Y1844600D01*
G01Y1846767D02*
X61500D01*
X65500Y1849833D01*
X61500D01*
G01X63500Y1853200D02*
Y1854533D01*
X64700D01*
X65100Y1854133D01*
X65367Y1853667D01*
X65500Y1853000D01*
X65367Y1852333D01*
X65100Y1851867D01*
X64700Y1851467D01*
X64233Y1851200D01*
X63700Y1851067D01*
X63233D01*
X62833Y1851200D01*
X62367Y1851467D01*
X61967Y1851867D01*
X61700Y1852267D01*
X61500Y1852800D01*
Y1853267D01*
X61633Y1853800D01*
X61900Y1854200D01*
G01X63833Y1860533D02*
X63367Y1861000D01*
X63100Y1861400D01*
X62967Y1861933D01*
X63100Y1862400D01*
X63367Y1862733D01*
X63767Y1863000D01*
X64233Y1863067D01*
X64633Y1863000D01*
X65033Y1862733D01*
X65367Y1862333D01*
X65500Y1861867D01*
X65367Y1861333D01*
X64967Y1860867D01*
X64367Y1860600D01*
X63700Y1860533D01*
X62833Y1860667D01*
X62367Y1860867D01*
X61900Y1861200D01*
X61567Y1861667D01*
X61500Y1862133D01*
X61633Y1862600D01*
X61967Y1862933D01*
G01X61500Y1866300D02*
X61633Y1865767D01*
X61967Y1865367D01*
X62367Y1865100D01*
X62900Y1864900D01*
X63500Y1864833D01*
X64100Y1864900D01*
X64633Y1865100D01*
X65033Y1865367D01*
X65367Y1865767D01*
X65500Y1866300D01*
X65367Y1866833D01*
X65033Y1867233D01*
X64633Y1867500D01*
X64100Y1867700D01*
X63500Y1867767D01*
X62900Y1867700D01*
X62367Y1867500D01*
X61967Y1867233D01*
X61633Y1866833D01*
X61500Y1866300D01*
G01X65500Y1869133D02*
X61500Y1870800D01*
X65500Y1872467D01*
G01X64100Y1871867D02*
Y1869733D01*
G01X126467Y534600D02*
X126800Y535133D01*
X127000Y535733D01*
Y536267D01*
X126800Y536800D01*
X126467Y537200D01*
X126000Y537400D01*
X125533Y537267D01*
X125133Y536933D01*
X124867Y536333D01*
X124733Y535533D01*
X124467Y535067D01*
X124000Y534867D01*
X123533Y535000D01*
X123200Y535333D01*
X123000Y535800D01*
Y536267D01*
X123133Y536733D01*
X123467Y537133D01*
G01X127000Y541833D02*
Y539167D01*
X123000D01*
Y541833D01*
G01X124933Y540767D02*
Y539167D01*
G01X127000Y543467D02*
X123000D01*
X127000Y546533D01*
X123000D01*
G01X126467Y548100D02*
X126800Y548633D01*
X127000Y549233D01*
Y549767D01*
X126800Y550300D01*
X126467Y550700D01*
X126000Y550900D01*
X125533Y550767D01*
X125133Y550433D01*
X124867Y549833D01*
X124733Y549033D01*
X124467Y548567D01*
X124000Y548367D01*
X123533Y548500D01*
X123200Y548833D01*
X123000Y549300D01*
Y549767D01*
X123133Y550233D01*
X123467Y550633D01*
G01X127000Y554000D02*
X126933Y553467D01*
X126667Y553000D01*
X126267Y552600D01*
X125800Y552333D01*
X125267Y552200D01*
X124733D01*
X124200Y552333D01*
X123733Y552600D01*
X123333Y553000D01*
X123067Y553467D01*
X123000Y554000D01*
X123067Y554533D01*
X123333Y555000D01*
X123733Y555400D01*
X124200Y555667D01*
X124733Y555800D01*
X125267D01*
X125800Y555667D01*
X126267Y555400D01*
X126667Y555000D01*
X126933Y554533D01*
X127000Y554000D01*
G01Y557167D02*
X123000D01*
Y558833D01*
X123200Y559367D01*
X123467Y559700D01*
X124000Y559833D01*
X124533Y559700D01*
X124867Y559300D01*
X125067Y558833D01*
Y557167D01*
G01Y558833D02*
X127000Y559833D01*
G01X123500Y519500D02*
X127500D01*
G01X123500Y517967D02*
Y521033D01*
G01X127500Y522267D02*
X123500D01*
X126833Y524000D01*
X123500Y525733D01*
X127500D01*
G01Y527167D02*
X123500D01*
Y528767D01*
X123700Y529300D01*
X124167Y529700D01*
X124700Y529833D01*
X125233Y529700D01*
X125633Y529367D01*
X125833Y528767D01*
Y527167D01*
G01X127000Y564000D02*
X123000D01*
X123800Y563200D01*
G01X127000D02*
Y564800D01*
G01X121000Y1232500D02*
X125000D01*
G01X121000Y1230967D02*
Y1234033D01*
G01X125000Y1235267D02*
X121000D01*
X124333Y1237000D01*
X121000Y1238733D01*
X125000D01*
G01Y1240167D02*
X121000D01*
Y1241767D01*
X121200Y1242300D01*
X121667Y1242700D01*
X122200Y1242833D01*
X122733Y1242700D01*
X123133Y1242367D01*
X123333Y1241767D01*
Y1240167D01*
G01X124467Y1249100D02*
X124800Y1249633D01*
X125000Y1250233D01*
Y1250767D01*
X124800Y1251300D01*
X124467Y1251700D01*
X124000Y1251900D01*
X123533Y1251767D01*
X123133Y1251433D01*
X122867Y1250833D01*
X122733Y1250033D01*
X122467Y1249567D01*
X122000Y1249367D01*
X121533Y1249500D01*
X121200Y1249833D01*
X121000Y1250300D01*
Y1250767D01*
X121133Y1251233D01*
X121467Y1251633D01*
G01X125000Y1256333D02*
Y1253667D01*
X121000D01*
Y1256333D01*
G01X122933Y1255267D02*
Y1253667D01*
G01X125000Y1257967D02*
X121000D01*
X125000Y1261033D01*
X121000D01*
G01X124467Y1262600D02*
X124800Y1263133D01*
X125000Y1263733D01*
Y1264267D01*
X124800Y1264800D01*
X124467Y1265200D01*
X124000Y1265400D01*
X123533Y1265267D01*
X123133Y1264933D01*
X122867Y1264333D01*
X122733Y1263533D01*
X122467Y1263067D01*
X122000Y1262867D01*
X121533Y1263000D01*
X121200Y1263333D01*
X121000Y1263800D01*
Y1264267D01*
X121133Y1264733D01*
X121467Y1265133D01*
G01X125000Y1268500D02*
X124933Y1267967D01*
X124667Y1267500D01*
X124267Y1267100D01*
X123800Y1266833D01*
X123267Y1266700D01*
X122733D01*
X122200Y1266833D01*
X121733Y1267100D01*
X121333Y1267500D01*
X121067Y1267967D01*
X121000Y1268500D01*
X121067Y1269033D01*
X121333Y1269500D01*
X121733Y1269900D01*
X122200Y1270167D01*
X122733Y1270300D01*
X123267D01*
X123800Y1270167D01*
X124267Y1269900D01*
X124667Y1269500D01*
X124933Y1269033D01*
X125000Y1268500D01*
G01Y1271667D02*
X121000D01*
Y1273333D01*
X121200Y1273867D01*
X121467Y1274200D01*
X122000Y1274333D01*
X122533Y1274200D01*
X122867Y1273800D01*
X123067Y1273333D01*
Y1271667D01*
G01Y1273333D02*
X125000Y1274333D01*
G01X121667Y1280733D02*
X121267Y1281133D01*
X121067Y1281600D01*
X121000Y1282133D01*
X121133Y1282800D01*
X121467Y1283267D01*
X121867Y1283400D01*
X122267Y1283333D01*
X122600Y1283067D01*
X123267Y1281733D01*
X123733Y1281133D01*
X124400Y1280733D01*
X125000Y1280600D01*
Y1283400D01*
G54D19*
G01X-430254Y-152763D02*
Y-135263D01*
G01X-421958D02*
X-430254Y-146055D01*
G01X-420648Y-152763D02*
X-426543Y-141097D01*
G01X-412973Y-152763D02*
Y-135263D01*
X-402929Y-152763D01*
Y-135263D01*
G01X-390451Y-152763D02*
X-392198Y-152471D01*
X-393726Y-151305D01*
X-395036Y-149555D01*
X-395910Y-147513D01*
X-396346Y-145180D01*
Y-142846D01*
X-395910Y-140513D01*
X-395036Y-138471D01*
X-393726Y-136722D01*
X-392198Y-135555D01*
X-390451Y-135263D01*
X-388705Y-135555D01*
X-387176Y-136722D01*
X-385866Y-138471D01*
X-384992Y-140513D01*
X-384556Y-142846D01*
Y-145180D01*
X-384992Y-147513D01*
X-385866Y-149555D01*
X-387176Y-151305D01*
X-388705Y-152471D01*
X-390451Y-152763D01*
G01X-377536D02*
X-368366Y-135263D01*
G01X-377536D02*
X-368366Y-152763D01*
G01X-362001Y-158596D02*
X-348901D01*
G01X-342099Y-152763D02*
Y-135263D01*
X-333803D01*
G01X-336859Y-143721D02*
X-342099D01*
G01X-325910Y-152763D02*
X-320451Y-135263D01*
X-314992Y-152763D01*
G01X-316958Y-146638D02*
X-323945D01*
G01X-307973Y-152763D02*
Y-135263D01*
X-297929Y-152763D01*
Y-135263D01*
G01X-263148Y-136722D02*
X-264458Y-135846D01*
X-265986Y-135263D01*
X-267733D01*
X-269698Y-136138D01*
X-271226Y-137596D01*
X-272318Y-139347D01*
X-273191Y-142263D01*
X-273410Y-144888D01*
X-272973Y-147513D01*
X-272318Y-149263D01*
X-271008Y-151013D01*
X-269479Y-152180D01*
X-267951Y-152763D01*
X-266423D01*
X-264894Y-152180D01*
X-263584Y-151305D01*
X-262492Y-150139D01*
G01X-250451Y-152763D02*
X-252198Y-152471D01*
X-253726Y-151305D01*
X-255036Y-149555D01*
X-255910Y-147513D01*
X-256346Y-145180D01*
Y-142846D01*
X-255910Y-140513D01*
X-255036Y-138471D01*
X-253726Y-136722D01*
X-252198Y-135555D01*
X-250451Y-135263D01*
X-248705Y-135555D01*
X-247176Y-136722D01*
X-245866Y-138471D01*
X-244992Y-140513D01*
X-244556Y-142846D01*
Y-145180D01*
X-244992Y-147513D01*
X-245866Y-149555D01*
X-247176Y-151305D01*
X-248705Y-152471D01*
X-250451Y-152763D01*
G01X-237973D02*
Y-135263D01*
X-227929Y-152763D01*
Y-135263D01*
G01X-215451D02*
Y-152763D01*
G01X-220473Y-135263D02*
X-210429D01*
G01X-202318Y-152763D02*
Y-135263D01*
X-196859D01*
X-195113Y-136138D01*
X-194021Y-137305D01*
X-193584Y-139638D01*
X-194021Y-141972D01*
X-195331Y-143430D01*
X-196859Y-144305D01*
X-202318D01*
G01X-196859D02*
X-193584Y-152763D01*
G01X-180451D02*
X-182198Y-152471D01*
X-183726Y-151305D01*
X-185036Y-149555D01*
X-185910Y-147513D01*
X-186346Y-145180D01*
Y-142846D01*
X-185910Y-140513D01*
X-185036Y-138471D01*
X-183726Y-136722D01*
X-182198Y-135555D01*
X-180451Y-135263D01*
X-178705Y-135555D01*
X-177176Y-136722D01*
X-175866Y-138471D01*
X-174992Y-140513D01*
X-174556Y-142846D01*
Y-145180D01*
X-174992Y-147513D01*
X-175866Y-149555D01*
X-177176Y-151305D01*
X-178705Y-152471D01*
X-180451Y-152763D01*
G01X-167318Y-135263D02*
Y-152763D01*
X-158584D01*
G01X-126205Y-143430D02*
X-125331Y-142555D01*
X-124676Y-141097D01*
X-124239Y-139054D01*
X-124676Y-137305D01*
X-125549Y-136138D01*
X-127078Y-135263D01*
X-132973D01*
Y-152763D01*
X-125768D01*
X-124239Y-151597D01*
X-123366Y-149846D01*
X-122929Y-147805D01*
X-123366Y-145763D01*
X-124676Y-144013D01*
X-126205Y-143430D01*
X-132973D01*
G01X-110451Y-152763D02*
X-112198Y-152471D01*
X-113726Y-151305D01*
X-115036Y-149555D01*
X-115910Y-147513D01*
X-116346Y-145180D01*
Y-142846D01*
X-115910Y-140513D01*
X-115036Y-138471D01*
X-113726Y-136722D01*
X-112198Y-135555D01*
X-110451Y-135263D01*
X-108705Y-135555D01*
X-107176Y-136722D01*
X-105866Y-138471D01*
X-104992Y-140513D01*
X-104556Y-142846D01*
Y-145180D01*
X-104992Y-147513D01*
X-105866Y-149555D01*
X-107176Y-151305D01*
X-108705Y-152471D01*
X-110451Y-152763D01*
G01X-98410D02*
X-92951Y-135263D01*
X-87492Y-152763D01*
G01X-89458Y-146638D02*
X-96445D01*
G01X-79818Y-152763D02*
Y-135263D01*
X-74359D01*
X-72613Y-136138D01*
X-71521Y-137305D01*
X-71084Y-139638D01*
X-71521Y-141972D01*
X-72831Y-143430D01*
X-74359Y-144305D01*
X-79818D01*
G01X-74359D02*
X-71084Y-152763D01*
G01X-62754D02*
Y-135263D01*
X-58388D01*
X-56641Y-136138D01*
X-55331Y-137305D01*
X-54239Y-139054D01*
X-53366Y-141097D01*
X-53148Y-144013D01*
X-53366Y-146930D01*
X-54239Y-148972D01*
X-55331Y-150722D01*
X-56641Y-151888D01*
X-58388Y-152763D01*
X-62754D01*
G01X-282378Y-107763D02*
Y-90263D01*
X-276701Y-104846D01*
X-271024Y-90263D01*
Y-107763D01*
G01X-259201D02*
X-260511Y-107471D01*
X-261821Y-106305D01*
X-262695Y-104263D01*
X-263131Y-101930D01*
X-262695Y-99596D01*
X-261821Y-97555D01*
X-260511Y-96388D01*
X-259201Y-96097D01*
X-257891Y-96388D01*
X-256581Y-97555D01*
X-255708Y-99596D01*
X-255489Y-101930D01*
X-255708Y-104263D01*
X-256581Y-106305D01*
X-257891Y-107471D01*
X-259201Y-107763D01*
G01X-237771Y-90263D02*
Y-107763D01*
G01Y-105139D02*
X-238644Y-106597D01*
X-239955Y-107471D01*
X-241483Y-107763D01*
X-243229Y-107180D01*
X-244539Y-105722D01*
X-245413Y-103972D01*
X-245631Y-101930D01*
X-245413Y-99888D01*
X-244539Y-98138D01*
X-243229Y-96680D01*
X-241483Y-96097D01*
X-239955Y-96388D01*
X-238863Y-96972D01*
X-237771Y-98138D01*
G01X-227476Y-99888D02*
X-220489D01*
X-221144Y-97846D01*
X-222236Y-96680D01*
X-223764Y-96097D01*
X-225293Y-96388D01*
X-226603Y-97263D01*
X-227476Y-99305D01*
X-227913Y-101055D01*
Y-102805D01*
X-227476Y-104555D01*
X-226384Y-106305D01*
X-225074Y-107471D01*
X-223546Y-107763D01*
X-222018Y-107180D01*
X-220489Y-105430D01*
G01X-206701Y-107763D02*
Y-90263D01*
G01X-14018Y-107763D02*
Y-90263D01*
X-8778D01*
X-7031Y-91138D01*
X-5721Y-93180D01*
X-5284Y-95513D01*
X-5721Y-97846D01*
X-6813Y-99596D01*
X-8778Y-100472D01*
X-14018D01*
G01X12652Y-91722D02*
X11342Y-90846D01*
X9814Y-90263D01*
X8067D01*
X6102Y-91138D01*
X4574Y-92596D01*
X3482Y-94347D01*
X2609Y-97263D01*
X2390Y-99888D01*
X2827Y-102513D01*
X3482Y-104263D01*
X4792Y-106013D01*
X6321Y-107180D01*
X7849Y-107763D01*
X9377D01*
X10906Y-107180D01*
X12216Y-106305D01*
X13308Y-105139D01*
G01X27095Y-98430D02*
X27969Y-97555D01*
X28624Y-96097D01*
X29061Y-94054D01*
X28624Y-92305D01*
X27751Y-91138D01*
X26222Y-90263D01*
X20327D01*
Y-107763D01*
X27532D01*
X29061Y-106597D01*
X29934Y-104846D01*
X30371Y-102805D01*
X29934Y-100763D01*
X28624Y-99013D01*
X27095Y-98430D01*
X20327D01*
G01X36299Y-113596D02*
X49399D01*
G01X55327Y-107763D02*
Y-90263D01*
X65371Y-107763D01*
Y-90263D01*
G01X77849Y-107763D02*
X76102Y-107471D01*
X74574Y-106305D01*
X73264Y-104555D01*
X72390Y-102513D01*
X71954Y-100180D01*
Y-97846D01*
X72390Y-95513D01*
X73264Y-93471D01*
X74574Y-91722D01*
X76102Y-90555D01*
X77849Y-90263D01*
X79595Y-90555D01*
X81124Y-91722D01*
X82434Y-93471D01*
X83308Y-95513D01*
X83744Y-97846D01*
Y-100180D01*
X83308Y-102513D01*
X82434Y-104555D01*
X81124Y-106305D01*
X79595Y-107471D01*
X77849Y-107763D01*
G01X-901Y-152763D02*
Y-135263D01*
X-3521Y-138763D01*
G01Y-152763D02*
X1719D01*
G01X12451Y-138180D02*
X13761Y-136430D01*
X15289Y-135555D01*
X17036Y-135263D01*
X19219Y-135846D01*
X20747Y-137305D01*
X21184Y-139054D01*
X20966Y-140805D01*
X20092Y-142263D01*
X15726Y-145180D01*
X13761Y-147221D01*
X12451Y-150139D01*
X12014Y-152763D01*
X21184D01*
G01X36719D02*
Y-135263D01*
X28640Y-147805D01*
X39558D01*
G01X46796Y-149263D02*
X48105Y-151305D01*
X49852Y-152471D01*
X51817Y-152763D01*
X53564Y-152471D01*
X55311Y-151013D01*
X56402Y-149263D01*
X56621Y-147513D01*
X56184Y-145472D01*
X54656Y-144013D01*
X53127Y-143430D01*
X51162D01*
G01X53127D02*
X54437Y-142555D01*
X55529Y-141097D01*
X55966Y-139347D01*
X55529Y-137596D01*
X54437Y-136138D01*
X52472Y-135263D01*
X50507Y-135555D01*
X48542Y-136722D01*
G01X64296Y-149263D02*
X65605Y-151305D01*
X67352Y-152471D01*
X69317Y-152763D01*
X71064Y-152471D01*
X72811Y-151013D01*
X73902Y-149263D01*
X74121Y-147513D01*
X73684Y-145472D01*
X72156Y-144013D01*
X70627Y-143430D01*
X68662D01*
G01X70627D02*
X71937Y-142555D01*
X73029Y-141097D01*
X73466Y-139347D01*
X73029Y-137596D01*
X71937Y-136138D01*
X69972Y-135263D01*
X68007Y-135555D01*
X66042Y-136722D01*
G01X128690Y-90263D02*
X134149Y-107763D01*
X139608Y-90263D01*
G01X156016Y-107763D02*
X147282D01*
Y-90263D01*
X156016D01*
G01X152522Y-98721D02*
X147282D01*
G01X164782Y-107763D02*
Y-90263D01*
X170241D01*
X171987Y-91138D01*
X173079Y-92305D01*
X173516Y-94638D01*
X173079Y-96972D01*
X171769Y-98430D01*
X170241Y-99305D01*
X164782D01*
G01X170241D02*
X173516Y-107763D01*
G01X186649Y-108346D02*
X186212Y-108055D01*
Y-107471D01*
X186649Y-107180D01*
X187086Y-107471D01*
Y-108055D01*
X186649Y-108346D01*
G01X97835Y617329D02*
X107535Y607629D01*
X97835D01*
Y617329D01*
G01X147501Y-138180D02*
X148811Y-136430D01*
X150339Y-135555D01*
X152086Y-135263D01*
X154269Y-135846D01*
X155797Y-137305D01*
X156234Y-139054D01*
X156016Y-140805D01*
X155142Y-142263D01*
X150776Y-145180D01*
X148811Y-147221D01*
X147501Y-150139D01*
X147064Y-152763D01*
X156234D01*
G01X163690D02*
X169149Y-135263D01*
X174608Y-152763D01*
G01X172642Y-146638D02*
X165655D01*
G01X253482Y-90263D02*
Y-107763D01*
X262216D01*
G01X279279D02*
Y-96097D01*
G01Y-98138D02*
X278406Y-96972D01*
X277095Y-96388D01*
X275567Y-96097D01*
X274039Y-96680D01*
X272729Y-97846D01*
X271855Y-99596D01*
X271419Y-101930D01*
X271855Y-104263D01*
X272729Y-106013D01*
X274039Y-107180D01*
X275567Y-107763D01*
X277095Y-107471D01*
X278406Y-106597D01*
X279279Y-105430D01*
G01X288264Y-113013D02*
X289574Y-113596D01*
X291321Y-113013D01*
X292412Y-111847D01*
X293286Y-110388D01*
X294595Y-105722D01*
X297434Y-96097D01*
G01X290447D02*
X294595Y-105722D01*
G01X307074Y-99888D02*
X314061D01*
X313406Y-97846D01*
X312314Y-96680D01*
X310786Y-96097D01*
X309257Y-96388D01*
X307947Y-97263D01*
X307074Y-99305D01*
X306637Y-101055D01*
Y-102805D01*
X307074Y-104555D01*
X308166Y-106305D01*
X309476Y-107471D01*
X311004Y-107763D01*
X312532Y-107180D01*
X314061Y-105430D01*
G01X324792Y-107763D02*
Y-96097D01*
G01Y-98430D02*
X325884Y-97263D01*
X326976Y-96388D01*
X328504Y-96097D01*
X329595Y-96388D01*
X330906Y-97263D01*
G01X342074Y-105722D02*
X343166Y-106888D01*
X344694Y-107763D01*
X346004D01*
X347314Y-107180D01*
X348187Y-106305D01*
X348624Y-105139D01*
X348406Y-103388D01*
X347532Y-102513D01*
X343602Y-100763D01*
X342729Y-98721D01*
X343166Y-97263D01*
X344039Y-96388D01*
X345349Y-96097D01*
X346659Y-96388D01*
X347969Y-97263D01*
G01X266599Y-135263D02*
Y-152763D01*
G01X261577Y-135263D02*
X271621D01*
G01X279514Y-150430D02*
X281261Y-151888D01*
X283226Y-152763D01*
X284972D01*
X286719Y-151888D01*
X288029Y-150430D01*
X288684Y-148388D01*
X288247Y-146347D01*
X287156Y-144596D01*
X285191Y-143430D01*
X282571Y-142846D01*
X281042Y-141680D01*
X280387Y-139638D01*
X280824Y-137596D01*
X281916Y-136138D01*
X283444Y-135263D01*
X284972D01*
X286501Y-135846D01*
X287811Y-137305D01*
G01X298979Y-135263D02*
X304219D01*
G01X301599D02*
Y-152763D01*
G01X298979D02*
X304219D01*
G01X314732Y-135263D02*
Y-152763D01*
X323466D01*
G01X331796D02*
Y-135263D01*
G01X340092D02*
X331796Y-146055D01*
G01X341402Y-152763D02*
X335507Y-141097D01*
G01X404346Y-107763D02*
Y-90263D01*
X408712D01*
X410459Y-91138D01*
X411769Y-92305D01*
X412861Y-94054D01*
X413734Y-96097D01*
X413952Y-99013D01*
X413734Y-101930D01*
X412861Y-103972D01*
X411769Y-105722D01*
X410459Y-106888D01*
X408712Y-107763D01*
X404346D01*
G01X423374Y-99888D02*
X430361D01*
X429706Y-97846D01*
X428614Y-96680D01*
X427086Y-96097D01*
X425557Y-96388D01*
X424247Y-97263D01*
X423374Y-99305D01*
X422937Y-101055D01*
Y-102805D01*
X423374Y-104555D01*
X424466Y-106305D01*
X425776Y-107471D01*
X427304Y-107763D01*
X428832Y-107180D01*
X430361Y-105430D01*
G01X440874Y-105722D02*
X441966Y-106888D01*
X443494Y-107763D01*
X444804D01*
X446114Y-107180D01*
X446987Y-106305D01*
X447424Y-105139D01*
X447206Y-103388D01*
X446332Y-102513D01*
X442402Y-100763D01*
X441529Y-98721D01*
X441966Y-97263D01*
X442839Y-96388D01*
X444149Y-96097D01*
X445459Y-96388D01*
X446769Y-97263D01*
G01X461649Y-96097D02*
Y-107763D01*
G01Y-91430D02*
X461212Y-91138D01*
Y-90555D01*
X461649Y-90263D01*
X462086Y-90555D01*
Y-91138D01*
X461649Y-91430D01*
G01X476092Y-112138D02*
X477621Y-113305D01*
X479367Y-113596D01*
X480895Y-113305D01*
X482206Y-111847D01*
X483079Y-109805D01*
Y-96097D01*
G01Y-98430D02*
X482206Y-97263D01*
X480895Y-96388D01*
X479367Y-96097D01*
X477621Y-96680D01*
X476529Y-97846D01*
X475655Y-99888D01*
X475219Y-101930D01*
X475437Y-103680D01*
X476311Y-105722D01*
X477621Y-107180D01*
X479367Y-107763D01*
X480677Y-107471D01*
X482206Y-106305D01*
X483079Y-105139D01*
G01X492937Y-107763D02*
Y-96097D01*
G01Y-99013D02*
X493811Y-97555D01*
X495121Y-96388D01*
X496867Y-96097D01*
X498395Y-96388D01*
X499706Y-97555D01*
X500361Y-99596D01*
Y-107763D01*
G01X510874Y-99888D02*
X517861D01*
X517206Y-97846D01*
X516114Y-96680D01*
X514586Y-96097D01*
X513057Y-96388D01*
X511747Y-97263D01*
X510874Y-99305D01*
X510437Y-101055D01*
Y-102805D01*
X510874Y-104555D01*
X511966Y-106305D01*
X513276Y-107471D01*
X514804Y-107763D01*
X516332Y-107180D01*
X517861Y-105430D01*
G01X528592Y-107763D02*
Y-96097D01*
G01Y-98430D02*
X529684Y-97263D01*
X530776Y-96388D01*
X532304Y-96097D01*
X533395Y-96388D01*
X534706Y-97263D01*
G01X429722Y-152763D02*
Y-135263D01*
X435399Y-149846D01*
X441076Y-135263D01*
Y-152763D01*
G01X452899D02*
X451152Y-152471D01*
X449624Y-151305D01*
X448314Y-149555D01*
X447440Y-147513D01*
X447004Y-145180D01*
Y-142846D01*
X447440Y-140513D01*
X448314Y-138471D01*
X449624Y-136722D01*
X451152Y-135555D01*
X452899Y-135263D01*
X454645Y-135555D01*
X456174Y-136722D01*
X457484Y-138471D01*
X458358Y-140513D01*
X458794Y-142846D01*
Y-145180D01*
X458358Y-147513D01*
X457484Y-149555D01*
X456174Y-151305D01*
X454645Y-152471D01*
X452899Y-152763D01*
G01X465814Y-150430D02*
X467561Y-151888D01*
X469526Y-152763D01*
X471272D01*
X473019Y-151888D01*
X474329Y-150430D01*
X474984Y-148388D01*
X474547Y-146347D01*
X473456Y-144596D01*
X471491Y-143430D01*
X468871Y-142846D01*
X467342Y-141680D01*
X466687Y-139638D01*
X467124Y-137596D01*
X468216Y-136138D01*
X469744Y-135263D01*
X471272D01*
X472801Y-135846D01*
X474111Y-137305D01*
G01X483314Y-150430D02*
X485061Y-151888D01*
X487026Y-152763D01*
X488772D01*
X490519Y-151888D01*
X491829Y-150430D01*
X492484Y-148388D01*
X492047Y-146347D01*
X490956Y-144596D01*
X488991Y-143430D01*
X486371Y-142846D01*
X484842Y-141680D01*
X484187Y-139638D01*
X484624Y-137596D01*
X485716Y-136138D01*
X487244Y-135263D01*
X488772D01*
X490301Y-135846D01*
X491611Y-137305D01*
G01X509766Y-152763D02*
X501032D01*
Y-135263D01*
X509766D01*
G01X506272Y-143721D02*
X501032D01*
G01X575349Y-152763D02*
Y-135263D01*
X572729Y-138763D01*
G01Y-152763D02*
X577969D01*
G01X588701Y-138180D02*
X590011Y-136430D01*
X591539Y-135555D01*
X593286Y-135263D01*
X595469Y-135846D01*
X596997Y-137305D01*
X597434Y-139054D01*
X597216Y-140805D01*
X596342Y-142263D01*
X591976Y-145180D01*
X590011Y-147221D01*
X588701Y-150139D01*
X588264Y-152763D01*
X597434D01*
G01X606419Y-153346D02*
X614279Y-135263D01*
G01X627849Y-152763D02*
Y-135263D01*
X625229Y-138763D01*
G01Y-152763D02*
X630469D01*
G01X645349D02*
Y-135263D01*
X642729Y-138763D01*
G01Y-152763D02*
X647969D01*
G01X658919Y-153346D02*
X666779Y-135263D01*
G01X676201Y-138180D02*
X677511Y-136430D01*
X679039Y-135555D01*
X680786Y-135263D01*
X682969Y-135846D01*
X684497Y-137305D01*
X684934Y-139054D01*
X684716Y-140805D01*
X683842Y-142263D01*
X679476Y-145180D01*
X677511Y-147221D01*
X676201Y-150139D01*
X675764Y-152763D01*
X684934D01*
G01X697849Y-135263D02*
X696102Y-135846D01*
X694792Y-137305D01*
X693919Y-139054D01*
X693264Y-141388D01*
X693046Y-144013D01*
X693264Y-146638D01*
X693919Y-148972D01*
X694792Y-150722D01*
X696102Y-152180D01*
X697849Y-152763D01*
X699595Y-152180D01*
X700906Y-150722D01*
X701779Y-148972D01*
X702434Y-146638D01*
X702652Y-144013D01*
X702434Y-141388D01*
X701779Y-139054D01*
X700906Y-137305D01*
X699595Y-135846D01*
X697849Y-135263D01*
G01X715349Y-152763D02*
Y-135263D01*
X712729Y-138763D01*
G01Y-152763D02*
X717969D01*
G01X728046Y-150139D02*
X729355Y-151597D01*
X730884Y-152471D01*
X732849Y-152763D01*
X734814Y-152180D01*
X736342Y-151013D01*
X737434Y-148972D01*
X737652Y-146638D01*
X737216Y-144305D01*
X736124Y-142846D01*
X734595Y-141680D01*
X733067Y-141388D01*
X731539Y-141680D01*
X729574Y-142846D01*
X730229Y-135263D01*
X736124D01*
G01X623046Y-107763D02*
Y-90263D01*
X627412D01*
X629159Y-91138D01*
X630469Y-92305D01*
X631561Y-94054D01*
X632434Y-96097D01*
X632652Y-99013D01*
X632434Y-101930D01*
X631561Y-103972D01*
X630469Y-105722D01*
X629159Y-106888D01*
X627412Y-107763D01*
X623046D01*
G01X649279D02*
Y-96097D01*
G01Y-98138D02*
X648406Y-96972D01*
X647095Y-96388D01*
X645567Y-96097D01*
X644039Y-96680D01*
X642729Y-97846D01*
X641855Y-99596D01*
X641419Y-101930D01*
X641855Y-104263D01*
X642729Y-106013D01*
X644039Y-107180D01*
X645567Y-107763D01*
X647095Y-107471D01*
X648406Y-106597D01*
X649279Y-105430D01*
G01X662849Y-90263D02*
Y-107763D01*
G01X659792Y-96097D02*
X665906D01*
G01X677074Y-99888D02*
X684061D01*
X683406Y-97846D01*
X682314Y-96680D01*
X680786Y-96097D01*
X679257Y-96388D01*
X677947Y-97263D01*
X677074Y-99305D01*
X676637Y-101055D01*
Y-102805D01*
X677074Y-104555D01*
X678166Y-106305D01*
X679476Y-107471D01*
X681004Y-107763D01*
X682532Y-107180D01*
X684061Y-105430D01*
G01X-24594Y94110D02*
Y42110D01*
X19706D01*
Y94110D01*
X-24594D01*
G01Y527339D02*
Y475339D01*
X19706D01*
Y527339D01*
X-24594D01*
G01Y787181D02*
Y735181D01*
X19706D01*
Y787181D01*
X-24594D01*
G01Y1233323D02*
Y1181323D01*
X19706D01*
Y1233323D01*
X-24594D01*
G01Y1493165D02*
Y1441165D01*
X19706D01*
Y1493165D01*
X-24594D01*
G01Y1926394D02*
Y1874394D01*
X19706D01*
Y1926394D01*
X-24594D01*
G01X25208Y54317D02*
X25083Y54067D01*
X25000Y53775D01*
Y53442D01*
X25125Y53067D01*
X25333Y52775D01*
X25583Y52567D01*
X26000Y52400D01*
X26375Y52358D01*
X26750Y52442D01*
X27000Y52567D01*
X27250Y52817D01*
X27417Y53108D01*
X27500Y53400D01*
Y53692D01*
X27417Y53983D01*
X27292Y54233D01*
X27125Y54442D01*
G01X27500Y55542D02*
X25000D01*
X27500Y57458D01*
X25000D01*
G01X26458Y58808D02*
X26167Y59100D01*
X26000Y59350D01*
X25917Y59683D01*
X26000Y59975D01*
X26167Y60183D01*
X26417Y60350D01*
X26708Y60392D01*
X26958Y60350D01*
X27208Y60183D01*
X27417Y59933D01*
X27500Y59642D01*
X27417Y59308D01*
X27167Y59017D01*
X26792Y58850D01*
X26375Y58808D01*
X25833Y58892D01*
X25542Y59017D01*
X25250Y59225D01*
X25042Y59517D01*
X25000Y59808D01*
X25083Y60100D01*
X25292Y60308D01*
G01X24175Y177500D02*
Y180000D01*
G01X25925D02*
Y177500D01*
G01Y178750D02*
X24175D01*
G01X27358Y179583D02*
X27608Y179833D01*
X27900Y179958D01*
X28233Y180000D01*
X28650Y179917D01*
X28942Y179708D01*
X29025Y179458D01*
X28983Y179208D01*
X28817Y179000D01*
X27983Y178583D01*
X27608Y178292D01*
X27358Y177875D01*
X27275Y177500D01*
X29025D01*
G01X13017Y204000D02*
Y201500D01*
X14683D01*
G01X17783D02*
X16117D01*
Y204000D01*
X17783D01*
G01X17117Y202792D02*
X16117D01*
G01X19133Y201500D02*
Y204000D01*
X19967D01*
X20300Y203875D01*
X20550Y203708D01*
X20758Y203458D01*
X20925Y203167D01*
X20967Y202750D01*
X20925Y202333D01*
X20758Y202042D01*
X20550Y201792D01*
X20300Y201625D01*
X19967Y201500D01*
X19133D01*
G01X22358Y202542D02*
X22650Y202833D01*
X22900Y203000D01*
X23233Y203083D01*
X23525Y203000D01*
X23733Y202833D01*
X23900Y202583D01*
X23942Y202292D01*
X23900Y202042D01*
X23733Y201792D01*
X23483Y201583D01*
X23192Y201500D01*
X22858Y201583D01*
X22567Y201833D01*
X22400Y202208D01*
X22358Y202625D01*
X22442Y203167D01*
X22567Y203458D01*
X22775Y203750D01*
X23067Y203958D01*
X23358Y204000D01*
X23650Y203917D01*
X23858Y203708D01*
G01X-9701Y227766D02*
X5099D01*
Y235066D01*
X34799D01*
Y206666D01*
X5099D01*
Y213966D01*
X-9701D01*
Y227766D01*
G01X12017Y242500D02*
Y245000D01*
X13058D01*
X13392Y244875D01*
X13600Y244708D01*
X13683Y244375D01*
X13600Y244042D01*
X13350Y243833D01*
X13058Y243708D01*
X12017D01*
G01X13058D02*
X13683Y242500D01*
G01X15950D02*
Y245000D01*
X15450Y244500D01*
G01Y242500D02*
X16450D01*
G01X18258Y244583D02*
X18508Y244833D01*
X18800Y244958D01*
X19133Y245000D01*
X19550Y244917D01*
X19842Y244708D01*
X19925Y244458D01*
X19883Y244208D01*
X19717Y244000D01*
X18883Y243583D01*
X18508Y243292D01*
X18258Y242875D01*
X18175Y242500D01*
X19925D01*
G01X21358Y244583D02*
X21608Y244833D01*
X21900Y244958D01*
X22233Y245000D01*
X22650Y244917D01*
X22942Y244708D01*
X23025Y244458D01*
X22983Y244208D01*
X22817Y244000D01*
X21983Y243583D01*
X21608Y243292D01*
X21358Y242875D01*
X21275Y242500D01*
X23025D01*
G01X42200Y250900D02*
Y242900D01*
X24600D01*
Y250900D01*
X42200D01*
G01X24317Y294792D02*
X24067Y294917D01*
X23775Y295000D01*
X23442D01*
X23067Y294875D01*
X22775Y294667D01*
X22567Y294417D01*
X22400Y294000D01*
X22358Y293625D01*
X22442Y293250D01*
X22567Y293000D01*
X22817Y292750D01*
X23108Y292583D01*
X23400Y292500D01*
X23692D01*
X23983Y292583D01*
X24233Y292708D01*
X24442Y292875D01*
G01X25708Y294583D02*
X25958Y294833D01*
X26250Y294958D01*
X26583Y295000D01*
X27000Y294917D01*
X27292Y294708D01*
X27375Y294458D01*
X27333Y294208D01*
X27167Y294000D01*
X26333Y293583D01*
X25958Y293292D01*
X25708Y292875D01*
X25625Y292500D01*
X27375D01*
G01X28683Y293000D02*
X28933Y292708D01*
X29267Y292542D01*
X29642Y292500D01*
X29975Y292542D01*
X30308Y292750D01*
X30517Y293000D01*
X30558Y293250D01*
X30475Y293542D01*
X30183Y293750D01*
X29892Y293833D01*
X29517D01*
G01X29892D02*
X30142Y293958D01*
X30350Y294167D01*
X30433Y294417D01*
X30350Y294667D01*
X30142Y294875D01*
X29767Y295000D01*
X29392Y294958D01*
X29017Y294792D01*
G01X32517Y267000D02*
Y269500D01*
X33558D01*
X33892Y269375D01*
X34100Y269208D01*
X34183Y268875D01*
X34100Y268542D01*
X33850Y268333D01*
X33558Y268208D01*
X32517D01*
G01X33558D02*
X34183Y267000D01*
G01X36450D02*
Y269500D01*
X35950Y269000D01*
G01Y267000D02*
X36950D01*
G01X39550D02*
Y269500D01*
X39050Y269000D01*
G01Y267000D02*
X40050D01*
G01X42650D02*
Y269500D01*
X42150Y269000D01*
G01Y267000D02*
X43150D01*
G01X38082Y262217D02*
Y266217D01*
X30682D01*
G01X15500Y253067D02*
X13000D01*
Y254108D01*
X13125Y254442D01*
X13292Y254650D01*
X13625Y254733D01*
X13958Y254650D01*
X14167Y254400D01*
X14292Y254108D01*
Y253067D01*
G01Y254108D02*
X15500Y254733D01*
G01X13417Y256208D02*
X13167Y256458D01*
X13042Y256750D01*
X13000Y257083D01*
X13083Y257500D01*
X13292Y257792D01*
X13542Y257875D01*
X13792Y257833D01*
X14000Y257667D01*
X14417Y256833D01*
X14708Y256458D01*
X15125Y256208D01*
X15500Y256125D01*
Y257875D01*
G01X14458Y259308D02*
X14167Y259600D01*
X14000Y259850D01*
X13917Y260183D01*
X14000Y260475D01*
X14167Y260683D01*
X14417Y260850D01*
X14708Y260892D01*
X14958Y260850D01*
X15208Y260683D01*
X15417Y260433D01*
X15500Y260142D01*
X15417Y259808D01*
X15167Y259517D01*
X14792Y259350D01*
X14375Y259308D01*
X13833Y259392D01*
X13542Y259517D01*
X13250Y259725D01*
X13042Y260017D01*
X13000Y260308D01*
X13083Y260600D01*
X13292Y260808D01*
G01X11500Y253067D02*
X9000D01*
Y254108D01*
X9125Y254442D01*
X9292Y254650D01*
X9625Y254733D01*
X9958Y254650D01*
X10167Y254400D01*
X10292Y254108D01*
Y253067D01*
G01Y254108D02*
X11500Y254733D01*
G01X9417Y256208D02*
X9167Y256458D01*
X9042Y256750D01*
X9000Y257083D01*
X9083Y257500D01*
X9292Y257792D01*
X9542Y257875D01*
X9792Y257833D01*
X10000Y257667D01*
X10417Y256833D01*
X10708Y256458D01*
X11125Y256208D01*
X11500Y256125D01*
Y257875D01*
G01X11125Y259183D02*
X11333Y259433D01*
X11458Y259725D01*
X11500Y260100D01*
X11417Y260475D01*
X11250Y260767D01*
X10958Y260975D01*
X10625Y261017D01*
X10292Y260933D01*
X10083Y260725D01*
X9917Y260433D01*
X9875Y260142D01*
X9917Y259850D01*
X10083Y259475D01*
X9000Y259600D01*
Y260725D01*
G01X34700Y258900D02*
X30700D01*
Y251500D01*
G01X29017Y276000D02*
Y278500D01*
X30058D01*
X30392Y278375D01*
X30600Y278208D01*
X30683Y277875D01*
X30600Y277542D01*
X30350Y277333D01*
X30058Y277208D01*
X29017D01*
G01X30058D02*
X30683Y276000D01*
G01X32950D02*
Y278500D01*
X32450Y278000D01*
G01Y276000D02*
X33450D01*
G01X35258Y277042D02*
X35550Y277333D01*
X35800Y277500D01*
X36133Y277583D01*
X36425Y277500D01*
X36633Y277333D01*
X36800Y277083D01*
X36842Y276792D01*
X36800Y276542D01*
X36633Y276292D01*
X36383Y276083D01*
X36092Y276000D01*
X35758Y276083D01*
X35467Y276333D01*
X35300Y276708D01*
X35258Y277125D01*
X35342Y277667D01*
X35467Y277958D01*
X35675Y278250D01*
X35967Y278458D01*
X36258Y278500D01*
X36550Y278417D01*
X36758Y278208D01*
G01X38358Y277042D02*
X38650Y277333D01*
X38900Y277500D01*
X39233Y277583D01*
X39525Y277500D01*
X39733Y277333D01*
X39900Y277083D01*
X39942Y276792D01*
X39900Y276542D01*
X39733Y276292D01*
X39483Y276083D01*
X39192Y276000D01*
X38858Y276083D01*
X38567Y276333D01*
X38400Y276708D01*
X38358Y277125D01*
X38442Y277667D01*
X38567Y277958D01*
X38775Y278250D01*
X39067Y278458D01*
X39358Y278500D01*
X39650Y278417D01*
X39858Y278208D01*
G01X30800Y274300D02*
Y270300D01*
X38200D01*
G01X7000Y253950D02*
X6958Y253617D01*
X6792Y253325D01*
X6542Y253075D01*
X6250Y252908D01*
X5917Y252825D01*
X5583D01*
X5250Y252908D01*
X4958Y253075D01*
X4708Y253325D01*
X4542Y253617D01*
X4500Y253950D01*
X4542Y254283D01*
X4708Y254575D01*
X4958Y254825D01*
X5250Y254992D01*
X5583Y255075D01*
X5917D01*
X6250Y254992D01*
X6542Y254825D01*
X6792Y254575D01*
X6958Y254283D01*
X7000Y253950D01*
G01X6333Y254283D02*
X7000Y254783D01*
G01X6500Y256133D02*
X6792Y256383D01*
X6958Y256717D01*
X7000Y257092D01*
X6958Y257425D01*
X6750Y257758D01*
X6500Y257967D01*
X6250Y258008D01*
X5958Y257925D01*
X5750Y257633D01*
X5667Y257342D01*
Y256967D01*
G01Y257342D02*
X5542Y257592D01*
X5333Y257800D01*
X5083Y257883D01*
X4833Y257800D01*
X4625Y257592D01*
X4500Y257217D01*
X4542Y256842D01*
X4708Y256467D01*
G01X30096Y251803D02*
Y265803D01*
G01X17096Y251803D02*
X30096D01*
G01X17096Y265803D02*
Y251803D01*
G01X30096Y265803D02*
X17096D01*
G01X-9701Y355463D02*
X5099D01*
Y362763D01*
X34799D01*
Y334363D01*
X5099D01*
Y341663D01*
X-9701D01*
Y355463D01*
G01X15500Y302517D02*
X13000D01*
Y303558D01*
X13125Y303892D01*
X13292Y304100D01*
X13625Y304183D01*
X13958Y304100D01*
X14167Y303850D01*
X14292Y303558D01*
Y302517D01*
G01Y303558D02*
X15500Y304183D01*
G01Y306450D02*
X13000D01*
X13500Y305950D01*
G01X15500D02*
Y306950D01*
G01Y309550D02*
X13000D01*
X13500Y309050D01*
G01X15500D02*
Y310050D01*
G01X15000Y311733D02*
X15292Y311983D01*
X15458Y312317D01*
X15500Y312692D01*
X15458Y313025D01*
X15250Y313358D01*
X15000Y313567D01*
X14750Y313608D01*
X14458Y313525D01*
X14250Y313233D01*
X14167Y312942D01*
Y312567D01*
G01Y312942D02*
X14042Y313192D01*
X13833Y313400D01*
X13583Y313483D01*
X13333Y313400D01*
X13125Y313192D01*
X13000Y312817D01*
X13042Y312442D01*
X13208Y312067D01*
G01X21283Y312682D02*
X17283D01*
Y305282D01*
G01X13667Y319500D02*
Y322000D01*
X14708D01*
X15042Y321875D01*
X15250Y321708D01*
X15333Y321375D01*
X15250Y321042D01*
X15000Y320833D01*
X14708Y320708D01*
X13667D01*
G01X14708D02*
X15333Y319500D01*
G01X16808Y321583D02*
X17058Y321833D01*
X17350Y321958D01*
X17683Y322000D01*
X18100Y321917D01*
X18392Y321708D01*
X18475Y321458D01*
X18433Y321208D01*
X18267Y321000D01*
X17433Y320583D01*
X17058Y320292D01*
X16808Y319875D01*
X16725Y319500D01*
X18475D01*
G01X19992Y319792D02*
X20283Y319583D01*
X20617Y319500D01*
X20950Y319583D01*
X21242Y319833D01*
X21450Y320208D01*
X21533Y320583D01*
Y321042D01*
X21450Y321417D01*
X21242Y321750D01*
X20992Y321917D01*
X20700Y322000D01*
X20367Y321917D01*
X20117Y321750D01*
X19950Y321500D01*
X19867Y321167D01*
X19950Y320875D01*
X20158Y320583D01*
X20408Y320417D01*
X20700Y320375D01*
X21033Y320458D01*
X21283Y320667D01*
X21533Y321042D01*
G01X27100Y323300D02*
Y319300D01*
X34500D01*
G01X22300Y316100D02*
Y302100D01*
G01X35300Y316100D02*
X22300D01*
G01Y302100D02*
X35300D01*
G01X9417Y327900D02*
Y330400D01*
X10458D01*
X10792Y330275D01*
X11000Y330108D01*
X11083Y329775D01*
X11000Y329442D01*
X10750Y329233D01*
X10458Y329108D01*
X9417D01*
G01X10458D02*
X11083Y327900D01*
G01X13350D02*
Y330400D01*
X12850Y329900D01*
G01Y327900D02*
X13850D01*
G01X15658Y329983D02*
X15908Y330233D01*
X16200Y330358D01*
X16533Y330400D01*
X16950Y330317D01*
X17242Y330108D01*
X17325Y329858D01*
X17283Y329608D01*
X17117Y329400D01*
X16283Y328983D01*
X15908Y328692D01*
X15658Y328275D01*
X15575Y327900D01*
X17325D01*
G01X18633Y328400D02*
X18883Y328108D01*
X19217Y327942D01*
X19592Y327900D01*
X19925Y327942D01*
X20258Y328150D01*
X20467Y328400D01*
X20508Y328650D01*
X20425Y328942D01*
X20133Y329150D01*
X19842Y329233D01*
X19467D01*
G01X19842D02*
X20092Y329358D01*
X20300Y329567D01*
X20383Y329817D01*
X20300Y330067D01*
X20092Y330275D01*
X19717Y330400D01*
X19342Y330358D01*
X18967Y330192D01*
G01X22000Y324500D02*
Y332500D01*
X39600D01*
Y324500D01*
X22000D01*
G01X33400Y381500D02*
Y379000D01*
G01X32442Y381500D02*
X34358D01*
G01X37417Y381292D02*
X37167Y381417D01*
X36875Y381500D01*
X36542D01*
X36167Y381375D01*
X35875Y381167D01*
X35667Y380917D01*
X35500Y380500D01*
X35458Y380125D01*
X35542Y379750D01*
X35667Y379500D01*
X35917Y379250D01*
X36208Y379083D01*
X36500Y379000D01*
X36792D01*
X37083Y379083D01*
X37333Y379208D01*
X37542Y379375D01*
G01X39600Y379000D02*
Y381500D01*
X39100Y381000D01*
G01Y379000D02*
X40100D01*
G01X16100Y388800D02*
Y406800D01*
G01X27300Y388800D02*
X16100D01*
G01X32700Y436800D02*
Y434300D01*
G01X31742Y436800D02*
X33658D01*
G01X36717Y436592D02*
X36467Y436717D01*
X36175Y436800D01*
X35842D01*
X35467Y436675D01*
X35175Y436467D01*
X34967Y436217D01*
X34800Y435800D01*
X34758Y435425D01*
X34842Y435050D01*
X34967Y434800D01*
X35217Y434550D01*
X35508Y434383D01*
X35800Y434300D01*
X36092D01*
X36383Y434383D01*
X36633Y434508D01*
X36842Y434675D01*
G01X38108Y436383D02*
X38358Y436633D01*
X38650Y436758D01*
X38983Y436800D01*
X39400Y436717D01*
X39692Y436508D01*
X39775Y436258D01*
X39733Y436008D01*
X39567Y435800D01*
X38733Y435383D01*
X38358Y435092D01*
X38108Y434675D01*
X38025Y434300D01*
X39775D01*
G01X16100Y427300D02*
X27300D01*
G01X16100Y409300D02*
Y427300D01*
G01X27300Y409300D02*
X16100D01*
G01Y406800D02*
X27300D01*
G01X23708Y489317D02*
X23583Y489067D01*
X23500Y488775D01*
Y488442D01*
X23625Y488067D01*
X23833Y487775D01*
X24083Y487567D01*
X24500Y487400D01*
X24875Y487358D01*
X25250Y487442D01*
X25500Y487567D01*
X25750Y487817D01*
X25917Y488108D01*
X26000Y488400D01*
Y488692D01*
X25917Y488983D01*
X25792Y489233D01*
X25625Y489442D01*
G01X26000Y490542D02*
X23500D01*
X26000Y492458D01*
X23500D01*
G01X25625Y493683D02*
X25833Y493933D01*
X25958Y494225D01*
X26000Y494600D01*
X25917Y494975D01*
X25750Y495267D01*
X25458Y495475D01*
X25125Y495517D01*
X24792Y495433D01*
X24583Y495225D01*
X24417Y494933D01*
X24375Y494642D01*
X24417Y494350D01*
X24583Y493975D01*
X23500Y494100D01*
Y495225D01*
G01X22300Y564217D02*
X17300D01*
Y567383D01*
G01X19717Y566217D02*
Y564217D01*
G01X18133Y569817D02*
X17633Y570317D01*
X17383Y570900D01*
X17300Y571567D01*
X17467Y572400D01*
X17883Y572983D01*
X18383Y573150D01*
X18883Y573067D01*
X19300Y572733D01*
X20133Y571067D01*
X20717Y570317D01*
X21550Y569817D01*
X22300Y569650D01*
Y573150D01*
G01X22467Y577000D02*
X22383Y576833D01*
X22217D01*
X22133Y577000D01*
X22217Y577167D01*
X22383D01*
X22467Y577000D01*
G01X20217D02*
X20133Y576833D01*
X19967D01*
X19883Y577000D01*
X19967Y577167D01*
X20133D01*
X20217Y577000D01*
G01X21300Y580767D02*
X21883Y581267D01*
X22217Y581933D01*
X22300Y582683D01*
X22217Y583350D01*
X21800Y584017D01*
X21300Y584433D01*
X20800Y584517D01*
X20217Y584350D01*
X19800Y583767D01*
X19633Y583183D01*
Y582433D01*
G01Y583183D02*
X19383Y583683D01*
X18967Y584100D01*
X18467Y584267D01*
X17967Y584100D01*
X17550Y583683D01*
X17300Y582933D01*
X17383Y582183D01*
X17717Y581433D01*
G01X22300Y586117D02*
X17300Y588200D01*
X22300Y590283D01*
G01X20550Y589533D02*
Y586867D01*
G01X22467Y592300D02*
X17300Y595300D01*
G01X22300Y599400D02*
X17300D01*
X18300Y598400D01*
G01X22300D02*
Y600400D01*
G01X21550Y603167D02*
X21967Y603667D01*
X22217Y604250D01*
X22300Y605000D01*
X22133Y605750D01*
X21800Y606333D01*
X21217Y606750D01*
X20550Y606833D01*
X19883Y606667D01*
X19467Y606250D01*
X19133Y605667D01*
X19050Y605083D01*
X19133Y604500D01*
X19467Y603750D01*
X17300Y604000D01*
Y606250D01*
G01Y608517D02*
X22300Y610600D01*
X17300Y612683D01*
G01X29067Y563500D02*
Y566000D01*
X30108D01*
X30442Y565875D01*
X30650Y565708D01*
X30733Y565375D01*
X30650Y565042D01*
X30400Y564833D01*
X30108Y564708D01*
X29067D01*
G01X30108D02*
X30733Y563500D01*
G01X32208Y564542D02*
X32500Y564833D01*
X32750Y565000D01*
X33083Y565083D01*
X33375Y565000D01*
X33583Y564833D01*
X33750Y564583D01*
X33792Y564292D01*
X33750Y564042D01*
X33583Y563792D01*
X33333Y563583D01*
X33042Y563500D01*
X32708Y563583D01*
X32417Y563833D01*
X32250Y564208D01*
X32208Y564625D01*
X32292Y565167D01*
X32417Y565458D01*
X32625Y565750D01*
X32917Y565958D01*
X33208Y566000D01*
X33500Y565917D01*
X33708Y565708D01*
G01X36600Y563500D02*
Y566000D01*
X35058Y564208D01*
X37142D01*
G01X35400Y568800D02*
Y572800D01*
X28000D01*
G01X33208Y589817D02*
X33083Y589567D01*
X33000Y589275D01*
Y588942D01*
X33125Y588567D01*
X33333Y588275D01*
X33583Y588067D01*
X34000Y587900D01*
X34375Y587858D01*
X34750Y587942D01*
X35000Y588067D01*
X35250Y588317D01*
X35417Y588608D01*
X35500Y588900D01*
Y589192D01*
X35417Y589483D01*
X35292Y589733D01*
X35125Y589942D01*
G01X33417Y591208D02*
X33167Y591458D01*
X33042Y591750D01*
X33000Y592083D01*
X33083Y592500D01*
X33292Y592792D01*
X33542Y592875D01*
X33792Y592833D01*
X34000Y592667D01*
X34417Y591833D01*
X34708Y591458D01*
X35125Y591208D01*
X35500Y591125D01*
Y592875D01*
G01Y595100D02*
X35458Y595392D01*
X35333Y595725D01*
X35125Y595933D01*
X34833Y596017D01*
X34542Y595933D01*
X34292Y595683D01*
X34167Y595308D01*
Y594892D01*
X34083Y594642D01*
X33875Y594433D01*
X33583Y594350D01*
X33292Y594475D01*
X33083Y594767D01*
X33000Y595100D01*
X33083Y595433D01*
X33292Y595725D01*
X33583Y595850D01*
X33875Y595767D01*
X34083Y595558D01*
X34167Y595308D01*
Y594892D01*
X34292Y594517D01*
X34542Y594267D01*
X34833Y594183D01*
X35125Y594267D01*
X35333Y594475D01*
X35458Y594808D01*
X35500Y595100D01*
G01X23850Y651000D02*
Y648500D01*
G01X22892Y651000D02*
X24808D01*
G01X27867Y650792D02*
X27617Y650917D01*
X27325Y651000D01*
X26992D01*
X26617Y650875D01*
X26325Y650667D01*
X26117Y650417D01*
X25950Y650000D01*
X25908Y649625D01*
X25992Y649250D01*
X26117Y649000D01*
X26367Y648750D01*
X26658Y648583D01*
X26950Y648500D01*
X27242D01*
X27533Y648583D01*
X27783Y648708D01*
X27992Y648875D01*
G01X30050Y648500D02*
Y651000D01*
X29550Y650500D01*
G01Y648500D02*
X30550D01*
G01X33650D02*
Y651000D01*
X32108Y649208D01*
X34192D01*
G01X11575Y646500D02*
Y649000D01*
G01X13325D02*
Y646500D01*
G01Y647750D02*
X11575D01*
G01X15467Y646500D02*
X15550Y647042D01*
X15675Y647500D01*
X15842Y647917D01*
X16050Y648375D01*
X16383Y649000D01*
X14717D01*
G01X12300Y676000D02*
X23500D01*
G01X12300Y658000D02*
Y676000D01*
G01X23500Y658000D02*
X12300D01*
G01X33983Y698000D02*
Y696208D01*
X34150Y695833D01*
X34483Y695583D01*
X34900Y695500D01*
X35317Y695583D01*
X35650Y695833D01*
X35817Y696208D01*
Y698000D01*
G01X38000Y695500D02*
Y698000D01*
X37500Y697500D01*
G01Y695500D02*
X38500D01*
G01X41100Y698000D02*
X40767Y697917D01*
X40517Y697708D01*
X40350Y697458D01*
X40225Y697125D01*
X40183Y696750D01*
X40225Y696375D01*
X40350Y696042D01*
X40517Y695792D01*
X40767Y695583D01*
X41100Y695500D01*
X41433Y695583D01*
X41683Y695792D01*
X41850Y696042D01*
X41975Y696375D01*
X42017Y696750D01*
X41975Y697125D01*
X41850Y697458D01*
X41683Y697708D01*
X41433Y697917D01*
X41100Y698000D01*
G01X46200Y683000D02*
X32800D01*
G01Y693000D02*
X46200D01*
G01X32800Y683000D02*
Y693000D01*
G01X13808Y685717D02*
X13683Y685467D01*
X13600Y685175D01*
Y684842D01*
X13725Y684467D01*
X13933Y684175D01*
X14183Y683967D01*
X14600Y683800D01*
X14975Y683758D01*
X15350Y683842D01*
X15600Y683967D01*
X15850Y684217D01*
X16017Y684508D01*
X16100Y684800D01*
Y685092D01*
X16017Y685383D01*
X15892Y685633D01*
X15725Y685842D01*
G01Y686983D02*
X15933Y687233D01*
X16058Y687525D01*
X16100Y687900D01*
X16017Y688275D01*
X15850Y688567D01*
X15558Y688775D01*
X15225Y688817D01*
X14892Y688733D01*
X14683Y688525D01*
X14517Y688233D01*
X14475Y687942D01*
X14517Y687650D01*
X14683Y687275D01*
X13600Y687400D01*
Y688525D01*
G01X15600Y690083D02*
X15892Y690333D01*
X16058Y690667D01*
X16100Y691042D01*
X16058Y691375D01*
X15850Y691708D01*
X15600Y691917D01*
X15350Y691958D01*
X15058Y691875D01*
X14850Y691583D01*
X14767Y691292D01*
Y690917D01*
G01Y691292D02*
X14642Y691542D01*
X14433Y691750D01*
X14183Y691833D01*
X13933Y691750D01*
X13725Y691542D01*
X13600Y691167D01*
X13642Y690792D01*
X13808Y690417D01*
G01X18208Y685717D02*
X18083Y685467D01*
X18000Y685175D01*
Y684842D01*
X18125Y684467D01*
X18333Y684175D01*
X18583Y683967D01*
X19000Y683800D01*
X19375Y683758D01*
X19750Y683842D01*
X20000Y683967D01*
X20250Y684217D01*
X20417Y684508D01*
X20500Y684800D01*
Y685092D01*
X20417Y685383D01*
X20292Y685633D01*
X20125Y685842D01*
G01Y686983D02*
X20333Y687233D01*
X20458Y687525D01*
X20500Y687900D01*
X20417Y688275D01*
X20250Y688567D01*
X19958Y688775D01*
X19625Y688817D01*
X19292Y688733D01*
X19083Y688525D01*
X18917Y688233D01*
X18875Y687942D01*
X18917Y687650D01*
X19083Y687275D01*
X18000Y687400D01*
Y688525D01*
G01X18417Y690208D02*
X18167Y690458D01*
X18042Y690750D01*
X18000Y691083D01*
X18083Y691500D01*
X18292Y691792D01*
X18542Y691875D01*
X18792Y691833D01*
X19000Y691667D01*
X19417Y690833D01*
X19708Y690458D01*
X20125Y690208D01*
X20500Y690125D01*
Y691875D01*
G01X30708Y765817D02*
X30583Y765567D01*
X30500Y765275D01*
Y764942D01*
X30625Y764567D01*
X30833Y764275D01*
X31083Y764067D01*
X31500Y763900D01*
X31875Y763858D01*
X32250Y763942D01*
X32500Y764067D01*
X32750Y764317D01*
X32917Y764608D01*
X33000Y764900D01*
Y765192D01*
X32917Y765483D01*
X32792Y765733D01*
X32625Y765942D01*
G01X33000Y767042D02*
X30500D01*
X33000Y768958D01*
X30500D01*
G01X33000Y771600D02*
X30500D01*
X32292Y770058D01*
Y772142D01*
G01X-9701Y920817D02*
X5099D01*
Y928117D01*
X34799D01*
Y899717D01*
X5099D01*
Y907017D01*
X-9701D01*
Y920817D01*
G01X32167Y894100D02*
Y896600D01*
X33208D01*
X33542Y896475D01*
X33750Y896308D01*
X33833Y895975D01*
X33750Y895642D01*
X33500Y895433D01*
X33208Y895308D01*
X32167D01*
G01X33208D02*
X33833Y894100D01*
G01X35183Y894600D02*
X35433Y894308D01*
X35767Y894142D01*
X36142Y894100D01*
X36475Y894142D01*
X36808Y894350D01*
X37017Y894600D01*
X37058Y894850D01*
X36975Y895142D01*
X36683Y895350D01*
X36392Y895433D01*
X36017D01*
G01X36392D02*
X36642Y895558D01*
X36850Y895767D01*
X36933Y896017D01*
X36850Y896267D01*
X36642Y896475D01*
X36267Y896600D01*
X35892Y896558D01*
X35517Y896392D01*
G01X38283Y894600D02*
X38533Y894308D01*
X38867Y894142D01*
X39242Y894100D01*
X39575Y894142D01*
X39908Y894350D01*
X40117Y894600D01*
X40158Y894850D01*
X40075Y895142D01*
X39783Y895350D01*
X39492Y895433D01*
X39117D01*
G01X39492D02*
X39742Y895558D01*
X39950Y895767D01*
X40033Y896017D01*
X39950Y896267D01*
X39742Y896475D01*
X39367Y896600D01*
X38992Y896558D01*
X38617Y896392D01*
G01X33217Y880300D02*
Y882800D01*
X34258D01*
X34592Y882675D01*
X34800Y882508D01*
X34883Y882175D01*
X34800Y881842D01*
X34550Y881633D01*
X34258Y881508D01*
X33217D01*
G01X34258D02*
X34883Y880300D01*
G01X37150D02*
Y882800D01*
X36650Y882300D01*
G01Y880300D02*
X37650D01*
G01X39458Y882383D02*
X39708Y882633D01*
X40000Y882758D01*
X40333Y882800D01*
X40750Y882717D01*
X41042Y882508D01*
X41125Y882258D01*
X41083Y882008D01*
X40917Y881800D01*
X40083Y881383D01*
X39708Y881092D01*
X39458Y880675D01*
X39375Y880300D01*
X41125D01*
G01X43850D02*
Y882800D01*
X42308Y881008D01*
X44392D01*
G01X22017Y933500D02*
Y931000D01*
X23683D01*
G01X26783D02*
X25117D01*
Y933500D01*
X26783D01*
G01X26117Y932292D02*
X25117D01*
G01X28133Y931000D02*
Y933500D01*
X28967D01*
X29300Y933375D01*
X29550Y933208D01*
X29758Y932958D01*
X29925Y932667D01*
X29967Y932250D01*
X29925Y931833D01*
X29758Y931542D01*
X29550Y931292D01*
X29300Y931125D01*
X28967Y931000D01*
X28133D01*
G01X32650D02*
Y933500D01*
X31108Y931708D01*
X33192D01*
G01X13517Y1037500D02*
Y1035000D01*
X15183D01*
G01X18283D02*
X16617D01*
Y1037500D01*
X18283D01*
G01X17617Y1036292D02*
X16617D01*
G01X19633Y1035000D02*
Y1037500D01*
X20467D01*
X20800Y1037375D01*
X21050Y1037208D01*
X21258Y1036958D01*
X21425Y1036667D01*
X21467Y1036250D01*
X21425Y1035833D01*
X21258Y1035542D01*
X21050Y1035292D01*
X20800Y1035125D01*
X20467Y1035000D01*
X19633D01*
G01X22733Y1035500D02*
X22983Y1035208D01*
X23317Y1035042D01*
X23692Y1035000D01*
X24025Y1035042D01*
X24358Y1035250D01*
X24567Y1035500D01*
X24608Y1035750D01*
X24525Y1036042D01*
X24233Y1036250D01*
X23942Y1036333D01*
X23567D01*
G01X23942D02*
X24192Y1036458D01*
X24400Y1036667D01*
X24483Y1036917D01*
X24400Y1037167D01*
X24192Y1037375D01*
X23817Y1037500D01*
X23442Y1037458D01*
X23067Y1037292D01*
G01X-9701Y1061487D02*
X5099D01*
Y1068787D01*
X34799D01*
Y1040387D01*
X5099D01*
Y1047687D01*
X-9701D01*
Y1061487D01*
G01X34617Y1014800D02*
Y1017300D01*
X35658D01*
X35992Y1017175D01*
X36200Y1017008D01*
X36283Y1016675D01*
X36200Y1016342D01*
X35950Y1016133D01*
X35658Y1016008D01*
X34617D01*
G01X35658D02*
X36283Y1014800D01*
G01X38550D02*
Y1017300D01*
X38050Y1016800D01*
G01Y1014800D02*
X39050D01*
G01X40858Y1016883D02*
X41108Y1017133D01*
X41400Y1017258D01*
X41733Y1017300D01*
X42150Y1017217D01*
X42442Y1017008D01*
X42525Y1016758D01*
X42483Y1016508D01*
X42317Y1016300D01*
X41483Y1015883D01*
X41108Y1015592D01*
X40858Y1015175D01*
X40775Y1014800D01*
X42525D01*
G01X43833Y1015175D02*
X44083Y1014967D01*
X44375Y1014842D01*
X44750Y1014800D01*
X45125Y1014883D01*
X45417Y1015050D01*
X45625Y1015342D01*
X45667Y1015675D01*
X45583Y1016008D01*
X45375Y1016217D01*
X45083Y1016383D01*
X44792Y1016425D01*
X44500Y1016383D01*
X44125Y1016217D01*
X44250Y1017300D01*
X45375D01*
G01X28100Y1085600D02*
Y1081600D01*
X35500D01*
G01X22967Y1109200D02*
Y1111700D01*
X24008D01*
X24342Y1111575D01*
X24550Y1111408D01*
X24633Y1111075D01*
X24550Y1110742D01*
X24300Y1110533D01*
X24008Y1110408D01*
X22967D01*
G01X24008D02*
X24633Y1109200D01*
G01X25983Y1109700D02*
X26233Y1109408D01*
X26567Y1109242D01*
X26942Y1109200D01*
X27275Y1109242D01*
X27608Y1109450D01*
X27817Y1109700D01*
X27858Y1109950D01*
X27775Y1110242D01*
X27483Y1110450D01*
X27192Y1110533D01*
X26817D01*
G01X27192D02*
X27442Y1110658D01*
X27650Y1110867D01*
X27733Y1111117D01*
X27650Y1111367D01*
X27442Y1111575D01*
X27067Y1111700D01*
X26692Y1111658D01*
X26317Y1111492D01*
G01X29917Y1109200D02*
X30000Y1109742D01*
X30125Y1110200D01*
X30292Y1110617D01*
X30500Y1111075D01*
X30833Y1111700D01*
X29167D01*
G01X29700Y1104000D02*
Y1108000D01*
X22300D01*
G01X19500Y1090950D02*
X19458Y1090617D01*
X19292Y1090325D01*
X19042Y1090075D01*
X18750Y1089908D01*
X18417Y1089825D01*
X18083D01*
X17750Y1089908D01*
X17458Y1090075D01*
X17208Y1090325D01*
X17042Y1090617D01*
X17000Y1090950D01*
X17042Y1091283D01*
X17208Y1091575D01*
X17458Y1091825D01*
X17750Y1091992D01*
X18083Y1092075D01*
X18417D01*
X18750Y1091992D01*
X19042Y1091825D01*
X19292Y1091575D01*
X19458Y1091283D01*
X19500Y1090950D01*
G01X18833Y1091283D02*
X19500Y1091783D01*
G01X18458Y1093258D02*
X18167Y1093550D01*
X18000Y1093800D01*
X17917Y1094133D01*
X18000Y1094425D01*
X18167Y1094633D01*
X18417Y1094800D01*
X18708Y1094842D01*
X18958Y1094800D01*
X19208Y1094633D01*
X19417Y1094383D01*
X19500Y1094092D01*
X19417Y1093758D01*
X19167Y1093467D01*
X18792Y1093300D01*
X18375Y1093258D01*
X17833Y1093342D01*
X17542Y1093467D01*
X17250Y1093675D01*
X17042Y1093967D01*
X17000Y1094258D01*
X17083Y1094550D01*
X17292Y1094758D01*
G01X21118Y1086583D02*
X35118D01*
G01X21118Y1099583D02*
Y1086583D01*
G01X35118Y1099583D02*
X21118D01*
G01X32208Y1203817D02*
X32083Y1203567D01*
X32000Y1203275D01*
Y1202942D01*
X32125Y1202567D01*
X32333Y1202275D01*
X32583Y1202067D01*
X33000Y1201900D01*
X33375Y1201858D01*
X33750Y1201942D01*
X34000Y1202067D01*
X34250Y1202317D01*
X34417Y1202608D01*
X34500Y1202900D01*
Y1203192D01*
X34417Y1203483D01*
X34292Y1203733D01*
X34125Y1203942D01*
G01X34500Y1205042D02*
X32000D01*
X34500Y1206958D01*
X32000D01*
G01X34000Y1208183D02*
X34292Y1208433D01*
X34458Y1208767D01*
X34500Y1209142D01*
X34458Y1209475D01*
X34250Y1209808D01*
X34000Y1210017D01*
X33750Y1210058D01*
X33458Y1209975D01*
X33250Y1209683D01*
X33167Y1209392D01*
Y1209017D01*
G01Y1209392D02*
X33042Y1209642D01*
X32833Y1209850D01*
X32583Y1209933D01*
X32333Y1209850D01*
X32125Y1209642D01*
X32000Y1209267D01*
X32042Y1208892D01*
X32208Y1208517D01*
G01X17575Y1359000D02*
Y1361500D01*
G01X19325D02*
Y1359000D01*
G01Y1360250D02*
X17575D01*
G01X22050Y1359000D02*
Y1361500D01*
X20508Y1359708D01*
X22592D01*
G01X31208Y1460817D02*
X31083Y1460567D01*
X31000Y1460275D01*
Y1459942D01*
X31125Y1459567D01*
X31333Y1459275D01*
X31583Y1459067D01*
X32000Y1458900D01*
X32375Y1458858D01*
X32750Y1458942D01*
X33000Y1459067D01*
X33250Y1459317D01*
X33417Y1459608D01*
X33500Y1459900D01*
Y1460192D01*
X33417Y1460483D01*
X33292Y1460733D01*
X33125Y1460942D01*
G01X33500Y1462042D02*
X31000D01*
X33500Y1463958D01*
X31000D01*
G01X31417Y1465308D02*
X31167Y1465558D01*
X31042Y1465850D01*
X31000Y1466183D01*
X31083Y1466600D01*
X31292Y1466892D01*
X31542Y1466975D01*
X31792Y1466933D01*
X32000Y1466767D01*
X32417Y1465933D01*
X32708Y1465558D01*
X33125Y1465308D01*
X33500Y1465225D01*
Y1466975D01*
G01X29800Y1560500D02*
X41000D01*
G01X29800Y1542500D02*
Y1560500D01*
G01X41000Y1542500D02*
X29800D01*
G01X12517Y1602000D02*
Y1599500D01*
X14183D01*
G01X17283D02*
X15617D01*
Y1602000D01*
X17283D01*
G01X16617Y1600792D02*
X15617D01*
G01X18633Y1599500D02*
Y1602000D01*
X19467D01*
X19800Y1601875D01*
X20050Y1601708D01*
X20258Y1601458D01*
X20425Y1601167D01*
X20467Y1600750D01*
X20425Y1600333D01*
X20258Y1600042D01*
X20050Y1599792D01*
X19800Y1599625D01*
X19467Y1599500D01*
X18633D01*
G01X21858Y1601583D02*
X22108Y1601833D01*
X22400Y1601958D01*
X22733Y1602000D01*
X23150Y1601917D01*
X23442Y1601708D01*
X23525Y1601458D01*
X23483Y1601208D01*
X23317Y1601000D01*
X22483Y1600583D01*
X22108Y1600292D01*
X21858Y1599875D01*
X21775Y1599500D01*
X23525D01*
G01X-9701Y1626841D02*
X5099D01*
Y1634141D01*
X34799D01*
Y1605741D01*
X5099D01*
Y1613041D01*
X-9701D01*
Y1626841D01*
G01X34900Y1666200D02*
X30900D01*
Y1658800D01*
G01X5819Y1642924D02*
Y1645424D01*
X6860D01*
X7194Y1645299D01*
X7402Y1645132D01*
X7485Y1644799D01*
X7402Y1644466D01*
X7152Y1644257D01*
X6860Y1644132D01*
X5819D01*
G01X6860D02*
X7485Y1642924D01*
G01X8960Y1645007D02*
X9210Y1645257D01*
X9502Y1645382D01*
X9835Y1645424D01*
X10252Y1645341D01*
X10544Y1645132D01*
X10627Y1644882D01*
X10585Y1644632D01*
X10419Y1644424D01*
X9585Y1644007D01*
X9210Y1643716D01*
X8960Y1643299D01*
X8877Y1642924D01*
X10627D01*
G01X12769D02*
X12852Y1643466D01*
X12977Y1643924D01*
X13144Y1644341D01*
X13352Y1644799D01*
X13685Y1645424D01*
X12019D01*
G01X16600Y1646300D02*
Y1642300D01*
X24000D01*
G01X5919Y1638324D02*
Y1640824D01*
X6960D01*
X7294Y1640699D01*
X7502Y1640532D01*
X7585Y1640199D01*
X7502Y1639866D01*
X7252Y1639657D01*
X6960Y1639532D01*
X5919D01*
G01X6960D02*
X7585Y1638324D01*
G01X9060Y1640407D02*
X9310Y1640657D01*
X9602Y1640782D01*
X9935Y1640824D01*
X10352Y1640741D01*
X10644Y1640532D01*
X10727Y1640282D01*
X10685Y1640032D01*
X10519Y1639824D01*
X9685Y1639407D01*
X9310Y1639116D01*
X9060Y1638699D01*
X8977Y1638324D01*
X10727D01*
G01X12952D02*
X13244Y1638366D01*
X13577Y1638491D01*
X13785Y1638699D01*
X13869Y1638991D01*
X13785Y1639282D01*
X13535Y1639532D01*
X13160Y1639657D01*
X12744D01*
X12494Y1639741D01*
X12285Y1639949D01*
X12202Y1640241D01*
X12327Y1640532D01*
X12619Y1640741D01*
X12952Y1640824D01*
X13285Y1640741D01*
X13577Y1640532D01*
X13702Y1640241D01*
X13619Y1639949D01*
X13410Y1639741D01*
X13160Y1639657D01*
X12744D01*
X12369Y1639532D01*
X12119Y1639282D01*
X12035Y1638991D01*
X12119Y1638699D01*
X12327Y1638491D01*
X12660Y1638366D01*
X12952Y1638324D01*
G01X24000Y1638200D02*
Y1642200D01*
X16600D01*
G01X25000Y1638300D02*
X38000D01*
G01X25000Y1652300D02*
Y1638300D01*
G01X38000Y1652300D02*
X25000D01*
G01X65650Y1667900D02*
Y1693100D01*
X27350D01*
Y1667900D01*
X65650D01*
G01X14717Y1663700D02*
Y1666200D01*
X15758D01*
X16092Y1666075D01*
X16300Y1665908D01*
X16383Y1665575D01*
X16300Y1665242D01*
X16050Y1665033D01*
X15758Y1664908D01*
X14717D01*
G01X15758D02*
X16383Y1663700D01*
G01X18650D02*
Y1666200D01*
X18150Y1665700D01*
G01Y1663700D02*
X19150D01*
G01X20958Y1665783D02*
X21208Y1666033D01*
X21500Y1666158D01*
X21833Y1666200D01*
X22250Y1666117D01*
X22542Y1665908D01*
X22625Y1665658D01*
X22583Y1665408D01*
X22417Y1665200D01*
X21583Y1664783D01*
X21208Y1664492D01*
X20958Y1664075D01*
X20875Y1663700D01*
X22625D01*
G01X24058Y1664742D02*
X24350Y1665033D01*
X24600Y1665200D01*
X24933Y1665283D01*
X25225Y1665200D01*
X25433Y1665033D01*
X25600Y1664783D01*
X25642Y1664492D01*
X25600Y1664242D01*
X25433Y1663992D01*
X25183Y1663783D01*
X24892Y1663700D01*
X24558Y1663783D01*
X24267Y1664033D01*
X24100Y1664408D01*
X24058Y1664825D01*
X24142Y1665367D01*
X24267Y1665658D01*
X24475Y1665950D01*
X24767Y1666158D01*
X25058Y1666200D01*
X25350Y1666117D01*
X25558Y1665908D01*
G01X12900Y1653100D02*
Y1661100D01*
X30500D01*
Y1653100D01*
X12900D01*
G01X4017Y1719500D02*
Y1722000D01*
X5058D01*
X5392Y1721875D01*
X5600Y1721708D01*
X5683Y1721375D01*
X5600Y1721042D01*
X5350Y1720833D01*
X5058Y1720708D01*
X4017D01*
G01X5058D02*
X5683Y1719500D01*
G01X7950D02*
Y1722000D01*
X7450Y1721500D01*
G01Y1719500D02*
X8450D01*
G01X10258Y1721583D02*
X10508Y1721833D01*
X10800Y1721958D01*
X11133Y1722000D01*
X11550Y1721917D01*
X11842Y1721708D01*
X11925Y1721458D01*
X11883Y1721208D01*
X11717Y1721000D01*
X10883Y1720583D01*
X10508Y1720292D01*
X10258Y1719875D01*
X10175Y1719500D01*
X11925D01*
G01X14150D02*
Y1722000D01*
X13650Y1721500D01*
G01Y1719500D02*
X14650D01*
G01X16400Y1722700D02*
Y1718700D01*
X23800D01*
G01X32000Y1720567D02*
X29500D01*
Y1721608D01*
X29625Y1721942D01*
X29792Y1722150D01*
X30125Y1722233D01*
X30458Y1722150D01*
X30667Y1721900D01*
X30792Y1721608D01*
Y1720567D01*
G01Y1721608D02*
X32000Y1722233D01*
G01X31500Y1723583D02*
X31792Y1723833D01*
X31958Y1724167D01*
X32000Y1724542D01*
X31958Y1724875D01*
X31750Y1725208D01*
X31500Y1725417D01*
X31250Y1725458D01*
X30958Y1725375D01*
X30750Y1725083D01*
X30667Y1724792D01*
Y1724417D01*
G01Y1724792D02*
X30542Y1725042D01*
X30333Y1725250D01*
X30083Y1725333D01*
X29833Y1725250D01*
X29625Y1725042D01*
X29500Y1724667D01*
X29542Y1724292D01*
X29708Y1723917D01*
G01X29917Y1726808D02*
X29667Y1727058D01*
X29542Y1727350D01*
X29500Y1727683D01*
X29583Y1728100D01*
X29792Y1728392D01*
X30042Y1728475D01*
X30292Y1728433D01*
X30500Y1728267D01*
X30917Y1727433D01*
X31208Y1727058D01*
X31625Y1726808D01*
X32000Y1726725D01*
Y1728475D01*
G01X27900Y1727100D02*
X23900D01*
Y1719700D01*
G01X17567Y1686000D02*
Y1688500D01*
X18608D01*
X18942Y1688375D01*
X19150Y1688208D01*
X19233Y1687875D01*
X19150Y1687542D01*
X18900Y1687333D01*
X18608Y1687208D01*
X17567D01*
G01X18608D02*
X19233Y1686000D01*
G01X20583Y1686500D02*
X20833Y1686208D01*
X21167Y1686042D01*
X21542Y1686000D01*
X21875Y1686042D01*
X22208Y1686250D01*
X22417Y1686500D01*
X22458Y1686750D01*
X22375Y1687042D01*
X22083Y1687250D01*
X21792Y1687333D01*
X21417D01*
G01X21792D02*
X22042Y1687458D01*
X22250Y1687667D01*
X22333Y1687917D01*
X22250Y1688167D01*
X22042Y1688375D01*
X21667Y1688500D01*
X21292Y1688458D01*
X20917Y1688292D01*
G01X24600Y1686000D02*
Y1688500D01*
X24100Y1688000D01*
G01Y1686000D02*
X25100D01*
G01X18200Y1694800D02*
Y1690800D01*
X25600D01*
G01X15000Y1709950D02*
X14958Y1709617D01*
X14792Y1709325D01*
X14542Y1709075D01*
X14250Y1708908D01*
X13917Y1708825D01*
X13583D01*
X13250Y1708908D01*
X12958Y1709075D01*
X12708Y1709325D01*
X12542Y1709617D01*
X12500Y1709950D01*
X12542Y1710283D01*
X12708Y1710575D01*
X12958Y1710825D01*
X13250Y1710992D01*
X13583Y1711075D01*
X13917D01*
X14250Y1710992D01*
X14542Y1710825D01*
X14792Y1710575D01*
X14958Y1710283D01*
X15000Y1709950D01*
G01X14333Y1710283D02*
X15000Y1710783D01*
G01Y1713050D02*
X14958Y1713342D01*
X14833Y1713675D01*
X14625Y1713883D01*
X14333Y1713967D01*
X14042Y1713883D01*
X13792Y1713633D01*
X13667Y1713258D01*
Y1712842D01*
X13583Y1712592D01*
X13375Y1712383D01*
X13083Y1712300D01*
X12792Y1712425D01*
X12583Y1712717D01*
X12500Y1713050D01*
X12583Y1713383D01*
X12792Y1713675D01*
X13083Y1713800D01*
X13375Y1713717D01*
X13583Y1713508D01*
X13667Y1713258D01*
Y1712842D01*
X13792Y1712467D01*
X14042Y1712217D01*
X14333Y1712133D01*
X14625Y1712217D01*
X14833Y1712425D01*
X14958Y1712758D01*
X15000Y1713050D01*
G01X29917Y1704118D02*
Y1718118D01*
G01X16917Y1704118D02*
X29917D01*
G01X16917Y1718118D02*
Y1704118D01*
G01X29917Y1718118D02*
X16917D01*
G01X10500Y1694017D02*
X8000D01*
Y1695058D01*
X8125Y1695392D01*
X8292Y1695600D01*
X8625Y1695683D01*
X8958Y1695600D01*
X9167Y1695350D01*
X9292Y1695058D01*
Y1694017D01*
G01Y1695058D02*
X10500Y1695683D01*
G01Y1697950D02*
X8000D01*
X8500Y1697450D01*
G01X10500D02*
Y1698450D01*
G01X8417Y1700258D02*
X8167Y1700508D01*
X8042Y1700800D01*
X8000Y1701133D01*
X8083Y1701550D01*
X8292Y1701842D01*
X8542Y1701925D01*
X8792Y1701883D01*
X9000Y1701717D01*
X9417Y1700883D01*
X9708Y1700508D01*
X10125Y1700258D01*
X10500Y1700175D01*
Y1701925D01*
G01Y1704067D02*
X9958Y1704150D01*
X9500Y1704275D01*
X9083Y1704442D01*
X8625Y1704650D01*
X8000Y1704983D01*
Y1703317D01*
G01X12500Y1695200D02*
Y1703200D01*
X30100D01*
Y1695200D01*
X12500D01*
G01X-9701Y1754538D02*
X5099D01*
Y1761838D01*
X34799D01*
Y1733438D01*
X5099D01*
Y1740738D01*
X-9701D01*
Y1754538D01*
G01X8083Y1780200D02*
Y1782700D01*
X8917D01*
X9250Y1782575D01*
X9500Y1782408D01*
X9708Y1782158D01*
X9875Y1781867D01*
X9917Y1781450D01*
X9875Y1781033D01*
X9708Y1780742D01*
X9500Y1780492D01*
X9250Y1780325D01*
X8917Y1780200D01*
X8083D01*
G01X12100D02*
Y1782700D01*
X11600Y1782200D01*
G01Y1780200D02*
X12600D01*
G01X15200D02*
Y1782700D01*
X14700Y1782200D01*
G01Y1780200D02*
X15700D01*
G01X17500Y1785000D02*
Y1777000D01*
G01D02*
X38500D01*
G01X21617Y1763700D02*
Y1766200D01*
X22658D01*
X22992Y1766075D01*
X23200Y1765908D01*
X23283Y1765575D01*
X23200Y1765242D01*
X22950Y1765033D01*
X22658Y1764908D01*
X21617D01*
G01X22658D02*
X23283Y1763700D01*
G01X25550D02*
Y1766200D01*
X25050Y1765700D01*
G01Y1763700D02*
X26050D01*
G01X28650Y1766200D02*
X28317Y1766117D01*
X28067Y1765908D01*
X27900Y1765658D01*
X27775Y1765325D01*
X27733Y1764950D01*
X27775Y1764575D01*
X27900Y1764242D01*
X28067Y1763992D01*
X28317Y1763783D01*
X28650Y1763700D01*
X28983Y1763783D01*
X29233Y1763992D01*
X29400Y1764242D01*
X29525Y1764575D01*
X29567Y1764950D01*
X29525Y1765325D01*
X29400Y1765658D01*
X29233Y1765908D01*
X28983Y1766117D01*
X28650Y1766200D01*
G01X31750D02*
X31417Y1766117D01*
X31167Y1765908D01*
X31000Y1765658D01*
X30875Y1765325D01*
X30833Y1764950D01*
X30875Y1764575D01*
X31000Y1764242D01*
X31167Y1763992D01*
X31417Y1763783D01*
X31750Y1763700D01*
X32083Y1763783D01*
X32333Y1763992D01*
X32500Y1764242D01*
X32625Y1764575D01*
X32667Y1764950D01*
X32625Y1765325D01*
X32500Y1765658D01*
X32333Y1765908D01*
X32083Y1766117D01*
X31750Y1766200D01*
G01X7867Y1773300D02*
Y1775800D01*
X8908D01*
X9242Y1775675D01*
X9450Y1775508D01*
X9533Y1775175D01*
X9450Y1774842D01*
X9200Y1774633D01*
X8908Y1774508D01*
X7867D01*
G01X8908D02*
X9533Y1773300D01*
G01X11092Y1773592D02*
X11383Y1773383D01*
X11717Y1773300D01*
X12050Y1773383D01*
X12342Y1773633D01*
X12550Y1774008D01*
X12633Y1774383D01*
Y1774842D01*
X12550Y1775217D01*
X12342Y1775550D01*
X12092Y1775717D01*
X11800Y1775800D01*
X11467Y1775717D01*
X11217Y1775550D01*
X11050Y1775300D01*
X10967Y1774967D01*
X11050Y1774675D01*
X11258Y1774383D01*
X11508Y1774217D01*
X11800Y1774175D01*
X12133Y1774258D01*
X12383Y1774467D01*
X12633Y1774842D01*
G01X13983Y1773675D02*
X14233Y1773467D01*
X14525Y1773342D01*
X14900Y1773300D01*
X15275Y1773383D01*
X15567Y1773550D01*
X15775Y1773842D01*
X15817Y1774175D01*
X15733Y1774508D01*
X15525Y1774717D01*
X15233Y1774883D01*
X14942Y1774925D01*
X14650Y1774883D01*
X14275Y1774717D01*
X14400Y1775800D01*
X15525D01*
G01X36100Y1772400D02*
Y1776400D01*
X28700D01*
G01X9017Y1763800D02*
Y1766300D01*
X10058D01*
X10392Y1766175D01*
X10600Y1766008D01*
X10683Y1765675D01*
X10600Y1765342D01*
X10350Y1765133D01*
X10058Y1765008D01*
X9017D01*
G01X10058D02*
X10683Y1763800D01*
G01X12950D02*
Y1766300D01*
X12450Y1765800D01*
G01Y1763800D02*
X13450D01*
G01X16050Y1766300D02*
X15717Y1766217D01*
X15467Y1766008D01*
X15300Y1765758D01*
X15175Y1765425D01*
X15133Y1765050D01*
X15175Y1764675D01*
X15300Y1764342D01*
X15467Y1764092D01*
X15717Y1763883D01*
X16050Y1763800D01*
X16383Y1763883D01*
X16633Y1764092D01*
X16800Y1764342D01*
X16925Y1764675D01*
X16967Y1765050D01*
X16925Y1765425D01*
X16800Y1765758D01*
X16633Y1766008D01*
X16383Y1766217D01*
X16050Y1766300D01*
G01X19650Y1763800D02*
Y1766300D01*
X18108Y1764508D01*
X20192D01*
G01X25300Y1767600D02*
Y1771600D01*
X17900D01*
G01X38500Y1785000D02*
X17500D01*
G01X40400Y1786200D02*
Y1790200D01*
X33000D01*
G01X13817Y1789492D02*
X13567Y1789617D01*
X13275Y1789700D01*
X12942D01*
X12567Y1789575D01*
X12275Y1789367D01*
X12067Y1789117D01*
X11900Y1788700D01*
X11858Y1788325D01*
X11942Y1787950D01*
X12067Y1787700D01*
X12317Y1787450D01*
X12608Y1787283D01*
X12900Y1787200D01*
X13192D01*
X13483Y1787283D01*
X13733Y1787408D01*
X13942Y1787575D01*
G01X16500Y1787200D02*
Y1789700D01*
X14958Y1787908D01*
X17042D01*
G01X18183Y1787575D02*
X18433Y1787367D01*
X18725Y1787242D01*
X19100Y1787200D01*
X19475Y1787283D01*
X19767Y1787450D01*
X19975Y1787742D01*
X20017Y1788075D01*
X19933Y1788408D01*
X19725Y1788617D01*
X19433Y1788783D01*
X19142Y1788825D01*
X18850Y1788783D01*
X18475Y1788617D01*
X18600Y1789700D01*
X19725D01*
G01X25134Y1831023D02*
Y1833523D01*
G01X26884D02*
Y1831023D01*
G01Y1832273D02*
X25134D01*
G01X28192Y1831398D02*
X28442Y1831190D01*
X28734Y1831065D01*
X29109Y1831023D01*
X29484Y1831106D01*
X29776Y1831273D01*
X29984Y1831565D01*
X30026Y1831898D01*
X29942Y1832231D01*
X29734Y1832440D01*
X29442Y1832606D01*
X29151Y1832648D01*
X28859Y1832606D01*
X28484Y1832440D01*
X28609Y1833523D01*
X29734D01*
G01X32708Y1910317D02*
X32583Y1910067D01*
X32500Y1909775D01*
Y1909442D01*
X32625Y1909067D01*
X32833Y1908775D01*
X33083Y1908567D01*
X33500Y1908400D01*
X33875Y1908358D01*
X34250Y1908442D01*
X34500Y1908567D01*
X34750Y1908817D01*
X34917Y1909108D01*
X35000Y1909400D01*
Y1909692D01*
X34917Y1909983D01*
X34792Y1910233D01*
X34625Y1910442D01*
G01X35000Y1911542D02*
X32500D01*
X35000Y1913458D01*
X32500D01*
G01X35000Y1915600D02*
X32500D01*
X33000Y1915100D01*
G01X35000D02*
Y1916100D01*
G01X48500Y80917D02*
X43500D01*
Y84083D01*
G01X45917Y82917D02*
Y80917D01*
G01X48500Y88100D02*
X43500D01*
X44500Y87100D01*
G01X48500D02*
Y89100D01*
G01X48667Y93700D02*
X48583Y93533D01*
X48417D01*
X48333Y93700D01*
X48417Y93867D01*
X48583D01*
X48667Y93700D01*
G01X46417D02*
X46333Y93533D01*
X46167D01*
X46083Y93700D01*
X46167Y93867D01*
X46333D01*
X46417Y93700D01*
G01X47500Y97467D02*
X48083Y97967D01*
X48417Y98633D01*
X48500Y99383D01*
X48417Y100050D01*
X48000Y100717D01*
X47500Y101133D01*
X47000Y101217D01*
X46417Y101050D01*
X46000Y100467D01*
X45833Y99883D01*
Y99133D01*
G01Y99883D02*
X45583Y100383D01*
X45167Y100800D01*
X44667Y100967D01*
X44167Y100800D01*
X43750Y100383D01*
X43500Y99633D01*
X43583Y98883D01*
X43917Y98133D01*
G01X48500Y102817D02*
X43500Y104900D01*
X48500Y106983D01*
G01X46750Y106233D02*
Y103567D01*
G01X48667Y109000D02*
X43500Y112000D01*
G01X48500Y116100D02*
X43500D01*
X44500Y115100D01*
G01X48500D02*
Y117100D01*
G01X47750Y119867D02*
X48167Y120367D01*
X48417Y120950D01*
X48500Y121700D01*
X48333Y122450D01*
X48000Y123033D01*
X47417Y123450D01*
X46750Y123533D01*
X46083Y123367D01*
X45667Y122950D01*
X45333Y122367D01*
X45250Y121783D01*
X45333Y121200D01*
X45667Y120450D01*
X43500Y120700D01*
Y122950D01*
G01Y125217D02*
X48500Y127300D01*
X43500Y129383D01*
G01X66200Y74700D02*
Y97700D01*
G01X105000Y74700D02*
X66200D01*
G01X95103Y58502D02*
X74103D01*
G01D02*
Y50502D01*
G01D02*
X95103D01*
G01X52617Y81800D02*
Y84300D01*
X53658D01*
X53992Y84175D01*
X54200Y84008D01*
X54283Y83675D01*
X54200Y83342D01*
X53950Y83133D01*
X53658Y83008D01*
X52617D01*
G01X53658D02*
X54283Y81800D01*
G01X56550D02*
Y84300D01*
X56050Y83800D01*
G01Y81800D02*
X57050D01*
G01X58858Y83883D02*
X59108Y84133D01*
X59400Y84258D01*
X59733Y84300D01*
X60150Y84217D01*
X60442Y84008D01*
X60525Y83758D01*
X60483Y83508D01*
X60317Y83300D01*
X59483Y82883D01*
X59108Y82592D01*
X58858Y82175D01*
X58775Y81800D01*
X60525D01*
G01X62750Y84300D02*
X62417Y84217D01*
X62167Y84008D01*
X62000Y83758D01*
X61875Y83425D01*
X61833Y83050D01*
X61875Y82675D01*
X62000Y82342D01*
X62167Y82092D01*
X62417Y81883D01*
X62750Y81800D01*
X63083Y81883D01*
X63333Y82092D01*
X63500Y82342D01*
X63625Y82675D01*
X63667Y83050D01*
X63625Y83425D01*
X63500Y83758D01*
X63333Y84008D01*
X63083Y84217D01*
X62750Y84300D01*
G01X52617Y90300D02*
Y92800D01*
X53658D01*
X53992Y92675D01*
X54200Y92508D01*
X54283Y92175D01*
X54200Y91842D01*
X53950Y91633D01*
X53658Y91508D01*
X52617D01*
G01X53658D02*
X54283Y90300D01*
G01X56550D02*
Y92800D01*
X56050Y92300D01*
G01Y90300D02*
X57050D01*
G01X59650D02*
Y92800D01*
X59150Y92300D01*
G01Y90300D02*
X60150D01*
G01X61958Y91342D02*
X62250Y91633D01*
X62500Y91800D01*
X62833Y91883D01*
X63125Y91800D01*
X63333Y91633D01*
X63500Y91383D01*
X63542Y91092D01*
X63500Y90842D01*
X63333Y90592D01*
X63083Y90383D01*
X62792Y90300D01*
X62458Y90383D01*
X62167Y90633D01*
X62000Y91008D01*
X61958Y91425D01*
X62042Y91967D01*
X62167Y92258D01*
X62375Y92550D01*
X62667Y92758D01*
X62958Y92800D01*
X63250Y92717D01*
X63458Y92508D01*
G01X52617Y85800D02*
Y88300D01*
X53658D01*
X53992Y88175D01*
X54200Y88008D01*
X54283Y87675D01*
X54200Y87342D01*
X53950Y87133D01*
X53658Y87008D01*
X52617D01*
G01X53658D02*
X54283Y85800D01*
G01X56550D02*
Y88300D01*
X56050Y87800D01*
G01Y85800D02*
X57050D01*
G01X59567D02*
X59650Y86342D01*
X59775Y86800D01*
X59942Y87217D01*
X60150Y87675D01*
X60483Y88300D01*
X58817D01*
G01X61958Y87883D02*
X62208Y88133D01*
X62500Y88258D01*
X62833Y88300D01*
X63250Y88217D01*
X63542Y88008D01*
X63625Y87758D01*
X63583Y87508D01*
X63417Y87300D01*
X62583Y86883D01*
X62208Y86592D01*
X61958Y86175D01*
X61875Y85800D01*
X63625D01*
G01X83800Y73500D02*
Y69500D01*
X91200D01*
G01X59000Y48567D02*
X56500D01*
Y49608D01*
X56625Y49942D01*
X56792Y50150D01*
X57125Y50233D01*
X57458Y50150D01*
X57667Y49900D01*
X57792Y49608D01*
Y48567D01*
G01Y49608D02*
X59000Y50233D01*
G01X57958Y51708D02*
X57667Y52000D01*
X57500Y52250D01*
X57417Y52583D01*
X57500Y52875D01*
X57667Y53083D01*
X57917Y53250D01*
X58208Y53292D01*
X58458Y53250D01*
X58708Y53083D01*
X58917Y52833D01*
X59000Y52542D01*
X58917Y52208D01*
X58667Y51917D01*
X58292Y51750D01*
X57875Y51708D01*
X57333Y51792D01*
X57042Y51917D01*
X56750Y52125D01*
X56542Y52417D01*
X56500Y52708D01*
X56583Y53000D01*
X56792Y53208D01*
G01X58708Y54892D02*
X58917Y55183D01*
X59000Y55517D01*
X58917Y55850D01*
X58667Y56142D01*
X58292Y56350D01*
X57917Y56433D01*
X57458D01*
X57083Y56350D01*
X56750Y56142D01*
X56583Y55892D01*
X56500Y55600D01*
X56583Y55267D01*
X56750Y55017D01*
X57000Y54850D01*
X57333Y54767D01*
X57625Y54850D01*
X57917Y55058D01*
X58083Y55308D01*
X58125Y55600D01*
X58042Y55933D01*
X57833Y56183D01*
X57458Y56433D01*
G01X65998Y51103D02*
X69998D01*
Y58503D01*
G01X59000Y66067D02*
X56500D01*
Y67108D01*
X56625Y67442D01*
X56792Y67650D01*
X57125Y67733D01*
X57458Y67650D01*
X57667Y67400D01*
X57792Y67108D01*
Y66067D01*
G01Y67108D02*
X59000Y67733D01*
G01X57958Y69208D02*
X57667Y69500D01*
X57500Y69750D01*
X57417Y70083D01*
X57500Y70375D01*
X57667Y70583D01*
X57917Y70750D01*
X58208Y70792D01*
X58458Y70750D01*
X58708Y70583D01*
X58917Y70333D01*
X59000Y70042D01*
X58917Y69708D01*
X58667Y69417D01*
X58292Y69250D01*
X57875Y69208D01*
X57333Y69292D01*
X57042Y69417D01*
X56750Y69625D01*
X56542Y69917D01*
X56500Y70208D01*
X56583Y70500D01*
X56792Y70708D01*
G01X59000Y73017D02*
X58458Y73100D01*
X58000Y73225D01*
X57583Y73392D01*
X57125Y73600D01*
X56500Y73933D01*
Y72267D01*
G01X65398Y65603D02*
X69398D01*
Y73003D01*
G01X56567Y60500D02*
Y63000D01*
X57608D01*
X57942Y62875D01*
X58150Y62708D01*
X58233Y62375D01*
X58150Y62042D01*
X57900Y61833D01*
X57608Y61708D01*
X56567D01*
G01X57608D02*
X58233Y60500D01*
G01X59708Y61542D02*
X60000Y61833D01*
X60250Y62000D01*
X60583Y62083D01*
X60875Y62000D01*
X61083Y61833D01*
X61250Y61583D01*
X61292Y61292D01*
X61250Y61042D01*
X61083Y60792D01*
X60833Y60583D01*
X60542Y60500D01*
X60208Y60583D01*
X59917Y60833D01*
X59750Y61208D01*
X59708Y61625D01*
X59792Y62167D01*
X59917Y62458D01*
X60125Y62750D01*
X60417Y62958D01*
X60708Y63000D01*
X61000Y62917D01*
X61208Y62708D01*
G01X62683Y60875D02*
X62933Y60667D01*
X63225Y60542D01*
X63600Y60500D01*
X63975Y60583D01*
X64267Y60750D01*
X64475Y61042D01*
X64517Y61375D01*
X64433Y61708D01*
X64225Y61917D01*
X63933Y62083D01*
X63642Y62125D01*
X63350Y62083D01*
X62975Y61917D01*
X63100Y63000D01*
X64225D01*
G01X72700Y61500D02*
Y65500D01*
X65300D01*
G01X61208Y50317D02*
X61083Y50067D01*
X61000Y49775D01*
Y49442D01*
X61125Y49067D01*
X61333Y48775D01*
X61583Y48567D01*
X62000Y48400D01*
X62375Y48358D01*
X62750Y48442D01*
X63000Y48567D01*
X63250Y48817D01*
X63417Y49108D01*
X63500Y49400D01*
Y49692D01*
X63417Y49983D01*
X63292Y50233D01*
X63125Y50442D01*
G01X61417Y51708D02*
X61167Y51958D01*
X61042Y52250D01*
X61000Y52583D01*
X61083Y53000D01*
X61292Y53292D01*
X61542Y53375D01*
X61792Y53333D01*
X62000Y53167D01*
X62417Y52333D01*
X62708Y51958D01*
X63125Y51708D01*
X63500Y51625D01*
Y53375D01*
G01X63208Y54892D02*
X63417Y55183D01*
X63500Y55517D01*
X63417Y55850D01*
X63167Y56142D01*
X62792Y56350D01*
X62417Y56433D01*
X61958D01*
X61583Y56350D01*
X61250Y56142D01*
X61083Y55892D01*
X61000Y55600D01*
X61083Y55267D01*
X61250Y55017D01*
X61500Y54850D01*
X61833Y54767D01*
X62125Y54850D01*
X62417Y55058D01*
X62583Y55308D01*
X62625Y55600D01*
X62542Y55933D01*
X62333Y56183D01*
X61958Y56433D01*
G01X61404Y67867D02*
X61279Y67617D01*
X61196Y67325D01*
Y66992D01*
X61321Y66617D01*
X61529Y66325D01*
X61779Y66117D01*
X62196Y65950D01*
X62571Y65908D01*
X62946Y65992D01*
X63196Y66117D01*
X63446Y66367D01*
X63613Y66658D01*
X63696Y66950D01*
Y67242D01*
X63613Y67533D01*
X63488Y67783D01*
X63321Y67992D01*
G01X61613Y69258D02*
X61363Y69508D01*
X61238Y69800D01*
X61196Y70133D01*
X61279Y70550D01*
X61488Y70842D01*
X61738Y70925D01*
X61988Y70883D01*
X62196Y70717D01*
X62613Y69883D01*
X62904Y69508D01*
X63321Y69258D01*
X63696Y69175D01*
Y70925D01*
G01Y73067D02*
X63154Y73150D01*
X62696Y73275D01*
X62279Y73442D01*
X61821Y73650D01*
X61196Y73983D01*
Y72317D01*
G01X66200Y97700D02*
X105000D01*
G01X57900Y140717D02*
X55400D01*
Y141758D01*
X55525Y142092D01*
X55692Y142300D01*
X56025Y142383D01*
X56358Y142300D01*
X56567Y142050D01*
X56692Y141758D01*
Y140717D01*
G01Y141758D02*
X57900Y142383D01*
G01X57400Y143733D02*
X57692Y143983D01*
X57858Y144317D01*
X57900Y144692D01*
X57858Y145025D01*
X57650Y145358D01*
X57400Y145567D01*
X57150Y145608D01*
X56858Y145525D01*
X56650Y145233D01*
X56567Y144942D01*
Y144567D01*
G01Y144942D02*
X56442Y145192D01*
X56233Y145400D01*
X55983Y145483D01*
X55733Y145400D01*
X55525Y145192D01*
X55400Y144817D01*
X55442Y144442D01*
X55608Y144067D01*
G01X56858Y146958D02*
X56567Y147250D01*
X56400Y147500D01*
X56317Y147833D01*
X56400Y148125D01*
X56567Y148333D01*
X56817Y148500D01*
X57108Y148542D01*
X57358Y148500D01*
X57608Y148333D01*
X57817Y148083D01*
X57900Y147792D01*
X57817Y147458D01*
X57567Y147167D01*
X57192Y147000D01*
X56775Y146958D01*
X56233Y147042D01*
X55942Y147167D01*
X55650Y147375D01*
X55442Y147667D01*
X55400Y147958D01*
X55483Y148250D01*
X55692Y148458D01*
G01X55400Y150850D02*
X55483Y150517D01*
X55692Y150267D01*
X55942Y150100D01*
X56275Y149975D01*
X56650Y149933D01*
X57025Y149975D01*
X57358Y150100D01*
X57608Y150267D01*
X57817Y150517D01*
X57900Y150850D01*
X57817Y151183D01*
X57608Y151433D01*
X57358Y151600D01*
X57025Y151725D01*
X56650Y151767D01*
X56275Y151725D01*
X55942Y151600D01*
X55692Y151433D01*
X55483Y151183D01*
X55400Y150850D01*
G01X52617Y98300D02*
Y100800D01*
X53658D01*
X53992Y100675D01*
X54200Y100508D01*
X54283Y100175D01*
X54200Y99842D01*
X53950Y99633D01*
X53658Y99508D01*
X52617D01*
G01X53658D02*
X54283Y98300D01*
G01X56550D02*
Y100800D01*
X56050Y100300D01*
G01Y98300D02*
X57050D01*
G01X59650D02*
Y100800D01*
X59150Y100300D01*
G01Y98300D02*
X60150D01*
G01X62750D02*
X63042Y98342D01*
X63375Y98467D01*
X63583Y98675D01*
X63667Y98967D01*
X63583Y99258D01*
X63333Y99508D01*
X62958Y99633D01*
X62542D01*
X62292Y99717D01*
X62083Y99925D01*
X62000Y100217D01*
X62125Y100508D01*
X62417Y100717D01*
X62750Y100800D01*
X63083Y100717D01*
X63375Y100508D01*
X63500Y100217D01*
X63417Y99925D01*
X63208Y99717D01*
X62958Y99633D01*
X62542D01*
X62167Y99508D01*
X61917Y99258D01*
X61833Y98967D01*
X61917Y98675D01*
X62125Y98467D01*
X62458Y98342D01*
X62750Y98300D01*
G01X52617Y106300D02*
Y108800D01*
X53658D01*
X53992Y108675D01*
X54200Y108508D01*
X54283Y108175D01*
X54200Y107842D01*
X53950Y107633D01*
X53658Y107508D01*
X52617D01*
G01X53658D02*
X54283Y106300D01*
G01X56550D02*
Y108800D01*
X56050Y108300D01*
G01Y106300D02*
X57050D01*
G01X59650D02*
Y108800D01*
X59150Y108300D01*
G01Y106300D02*
X60150D01*
G01X63250D02*
Y108800D01*
X61708Y107008D01*
X63792D01*
G01X61900Y140717D02*
X59400D01*
Y141758D01*
X59525Y142092D01*
X59692Y142300D01*
X60025Y142383D01*
X60358Y142300D01*
X60567Y142050D01*
X60692Y141758D01*
Y140717D01*
G01Y141758D02*
X61900Y142383D01*
G01X61400Y143733D02*
X61692Y143983D01*
X61858Y144317D01*
X61900Y144692D01*
X61858Y145025D01*
X61650Y145358D01*
X61400Y145567D01*
X61150Y145608D01*
X60858Y145525D01*
X60650Y145233D01*
X60567Y144942D01*
Y144567D01*
G01Y144942D02*
X60442Y145192D01*
X60233Y145400D01*
X59983Y145483D01*
X59733Y145400D01*
X59525Y145192D01*
X59400Y144817D01*
X59442Y144442D01*
X59608Y144067D01*
G01X61525Y146833D02*
X61733Y147083D01*
X61858Y147375D01*
X61900Y147750D01*
X61817Y148125D01*
X61650Y148417D01*
X61358Y148625D01*
X61025Y148667D01*
X60692Y148583D01*
X60483Y148375D01*
X60317Y148083D01*
X60275Y147792D01*
X60317Y147500D01*
X60483Y147125D01*
X59400Y147250D01*
Y148375D01*
G01X61900Y150767D02*
X61358Y150850D01*
X60900Y150975D01*
X60483Y151142D01*
X60025Y151350D01*
X59400Y151683D01*
Y150017D01*
G01X52617Y132300D02*
Y134800D01*
X53658D01*
X53992Y134675D01*
X54200Y134508D01*
X54283Y134175D01*
X54200Y133842D01*
X53950Y133633D01*
X53658Y133508D01*
X52617D01*
G01X53658D02*
X54283Y132300D01*
G01X56550D02*
Y134800D01*
X56050Y134300D01*
G01Y132300D02*
X57050D01*
G01X59567D02*
X59650Y132842D01*
X59775Y133300D01*
X59942Y133717D01*
X60150Y134175D01*
X60483Y134800D01*
X58817D01*
G01X61833Y132675D02*
X62083Y132467D01*
X62375Y132342D01*
X62750Y132300D01*
X63125Y132383D01*
X63417Y132550D01*
X63625Y132842D01*
X63667Y133175D01*
X63583Y133508D01*
X63375Y133717D01*
X63083Y133883D01*
X62792Y133925D01*
X62500Y133883D01*
X62125Y133717D01*
X62250Y134800D01*
X63375D01*
G01X52617Y110300D02*
Y112800D01*
X53658D01*
X53992Y112675D01*
X54200Y112508D01*
X54283Y112175D01*
X54200Y111842D01*
X53950Y111633D01*
X53658Y111508D01*
X52617D01*
G01X53658D02*
X54283Y110300D01*
G01X56550D02*
Y112800D01*
X56050Y112300D01*
G01Y110300D02*
X57050D01*
G01X59567D02*
X59650Y110842D01*
X59775Y111300D01*
X59942Y111717D01*
X60150Y112175D01*
X60483Y112800D01*
X58817D01*
G01X63250Y110300D02*
Y112800D01*
X61708Y111008D01*
X63792D01*
G01X52617Y94300D02*
Y96800D01*
X53658D01*
X53992Y96675D01*
X54200Y96508D01*
X54283Y96175D01*
X54200Y95842D01*
X53950Y95633D01*
X53658Y95508D01*
X52617D01*
G01X53658D02*
X54283Y94300D01*
G01X56550D02*
Y96800D01*
X56050Y96300D01*
G01Y94300D02*
X57050D01*
G01X59567D02*
X59650Y94842D01*
X59775Y95300D01*
X59942Y95717D01*
X60150Y96175D01*
X60483Y96800D01*
X58817D01*
G01X61833Y94800D02*
X62083Y94508D01*
X62417Y94342D01*
X62792Y94300D01*
X63125Y94342D01*
X63458Y94550D01*
X63667Y94800D01*
X63708Y95050D01*
X63625Y95342D01*
X63333Y95550D01*
X63042Y95633D01*
X62667D01*
G01X63042D02*
X63292Y95758D01*
X63500Y95967D01*
X63583Y96217D01*
X63500Y96467D01*
X63292Y96675D01*
X62917Y96800D01*
X62542Y96758D01*
X62167Y96592D01*
G01X52517Y102500D02*
Y105000D01*
X53558D01*
X53892Y104875D01*
X54100Y104708D01*
X54183Y104375D01*
X54100Y104042D01*
X53850Y103833D01*
X53558Y103708D01*
X52517D01*
G01X53558D02*
X54183Y102500D01*
G01X56450D02*
Y105000D01*
X55950Y104500D01*
G01Y102500D02*
X56950D01*
G01X59467D02*
X59550Y103042D01*
X59675Y103500D01*
X59842Y103917D01*
X60050Y104375D01*
X60383Y105000D01*
X58717D01*
G01X62650Y102500D02*
Y105000D01*
X62150Y104500D01*
G01Y102500D02*
X63150D01*
G01X61100Y118317D02*
X58600D01*
Y119358D01*
X58725Y119692D01*
X58892Y119900D01*
X59225Y119983D01*
X59558Y119900D01*
X59767Y119650D01*
X59892Y119358D01*
Y118317D01*
G01Y119358D02*
X61100Y119983D01*
G01Y122250D02*
X58600D01*
X59100Y121750D01*
G01X61100D02*
Y122750D01*
G01Y125350D02*
X61058Y125642D01*
X60933Y125975D01*
X60725Y126183D01*
X60433Y126267D01*
X60142Y126183D01*
X59892Y125933D01*
X59767Y125558D01*
Y125142D01*
X59683Y124892D01*
X59475Y124683D01*
X59183Y124600D01*
X58892Y124725D01*
X58683Y125017D01*
X58600Y125350D01*
X58683Y125683D01*
X58892Y125975D01*
X59183Y126100D01*
X59475Y126017D01*
X59683Y125808D01*
X59767Y125558D01*
Y125142D01*
X59892Y124767D01*
X60142Y124517D01*
X60433Y124433D01*
X60725Y124517D01*
X60933Y124725D01*
X61058Y125058D01*
X61100Y125350D01*
G01Y128950D02*
X58600D01*
X60392Y127408D01*
Y129492D01*
G01X57100Y118317D02*
X54600D01*
Y119358D01*
X54725Y119692D01*
X54892Y119900D01*
X55225Y119983D01*
X55558Y119900D01*
X55767Y119650D01*
X55892Y119358D01*
Y118317D01*
G01Y119358D02*
X57100Y119983D01*
G01Y122250D02*
X54600D01*
X55100Y121750D01*
G01X57100D02*
Y122750D01*
G01Y125350D02*
X57058Y125642D01*
X56933Y125975D01*
X56725Y126183D01*
X56433Y126267D01*
X56142Y126183D01*
X55892Y125933D01*
X55767Y125558D01*
Y125142D01*
X55683Y124892D01*
X55475Y124683D01*
X55183Y124600D01*
X54892Y124725D01*
X54683Y125017D01*
X54600Y125350D01*
X54683Y125683D01*
X54892Y125975D01*
X55183Y126100D01*
X55475Y126017D01*
X55683Y125808D01*
X55767Y125558D01*
Y125142D01*
X55892Y124767D01*
X56142Y124517D01*
X56433Y124433D01*
X56725Y124517D01*
X56933Y124725D01*
X57058Y125058D01*
X57100Y125350D01*
G01X56058Y127658D02*
X55767Y127950D01*
X55600Y128200D01*
X55517Y128533D01*
X55600Y128825D01*
X55767Y129033D01*
X56017Y129200D01*
X56308Y129242D01*
X56558Y129200D01*
X56808Y129033D01*
X57017Y128783D01*
X57100Y128492D01*
X57017Y128158D01*
X56767Y127867D01*
X56392Y127700D01*
X55975Y127658D01*
X55433Y127742D01*
X55142Y127867D01*
X54850Y128075D01*
X54642Y128367D01*
X54600Y128658D01*
X54683Y128950D01*
X54892Y129158D01*
G01X52617Y114300D02*
Y116800D01*
X53658D01*
X53992Y116675D01*
X54200Y116508D01*
X54283Y116175D01*
X54200Y115842D01*
X53950Y115633D01*
X53658Y115508D01*
X52617D01*
G01X53658D02*
X54283Y114300D01*
G01X56550D02*
Y116800D01*
X56050Y116300D01*
G01Y114300D02*
X57050D01*
G01X59650D02*
X59942Y114342D01*
X60275Y114467D01*
X60483Y114675D01*
X60567Y114967D01*
X60483Y115258D01*
X60233Y115508D01*
X59858Y115633D01*
X59442D01*
X59192Y115717D01*
X58983Y115925D01*
X58900Y116217D01*
X59025Y116508D01*
X59317Y116717D01*
X59650Y116800D01*
X59983Y116717D01*
X60275Y116508D01*
X60400Y116217D01*
X60317Y115925D01*
X60108Y115717D01*
X59858Y115633D01*
X59442D01*
X59067Y115508D01*
X58817Y115258D01*
X58733Y114967D01*
X58817Y114675D01*
X59025Y114467D01*
X59358Y114342D01*
X59650Y114300D01*
G01X61833Y114675D02*
X62083Y114467D01*
X62375Y114342D01*
X62750Y114300D01*
X63125Y114383D01*
X63417Y114550D01*
X63625Y114842D01*
X63667Y115175D01*
X63583Y115508D01*
X63375Y115717D01*
X63083Y115883D01*
X62792Y115925D01*
X62500Y115883D01*
X62125Y115717D01*
X62250Y116800D01*
X63375D01*
G01X66009Y340409D02*
X95409D01*
Y311909D01*
X125409D01*
Y136909D01*
X95409D01*
Y108409D01*
X66009D01*
Y340409D01*
G01X72800Y99000D02*
X90400D01*
G01X72800Y107000D02*
Y99000D01*
G01X90400Y107000D02*
X72800D01*
G01X54900Y157300D02*
Y153300D01*
X62300D01*
G01Y169300D02*
Y173300D01*
X54900D01*
G01Y165300D02*
Y161300D01*
X62300D01*
G01X54900Y181300D02*
Y177300D01*
X62300D01*
G01Y181300D02*
Y185300D01*
X54900D01*
G01X62300Y165300D02*
Y169300D01*
X54900D01*
G01Y161300D02*
Y157300D01*
X62300D01*
G01X54900Y177300D02*
Y173300D01*
X62300D01*
G01X58600Y189600D02*
X62600D01*
Y197000D01*
G01X58600D02*
X54600D01*
Y189600D01*
G01X62300Y185300D02*
Y189300D01*
X54900D01*
G01X59400Y213300D02*
X55400D01*
Y205900D01*
G01X52517Y229500D02*
Y232000D01*
X53558D01*
X53892Y231875D01*
X54100Y231708D01*
X54183Y231375D01*
X54100Y231042D01*
X53850Y230833D01*
X53558Y230708D01*
X52517D01*
G01X53558D02*
X54183Y229500D01*
G01X55533Y230000D02*
X55783Y229708D01*
X56117Y229542D01*
X56492Y229500D01*
X56825Y229542D01*
X57158Y229750D01*
X57367Y230000D01*
X57408Y230250D01*
X57325Y230542D01*
X57033Y230750D01*
X56742Y230833D01*
X56367D01*
G01X56742D02*
X56992Y230958D01*
X57200Y231167D01*
X57283Y231417D01*
X57200Y231667D01*
X56992Y231875D01*
X56617Y232000D01*
X56242Y231958D01*
X55867Y231792D01*
G01X58758Y230542D02*
X59050Y230833D01*
X59300Y231000D01*
X59633Y231083D01*
X59925Y231000D01*
X60133Y230833D01*
X60300Y230583D01*
X60342Y230292D01*
X60300Y230042D01*
X60133Y229792D01*
X59883Y229583D01*
X59592Y229500D01*
X59258Y229583D01*
X58967Y229833D01*
X58800Y230208D01*
X58758Y230625D01*
X58842Y231167D01*
X58967Y231458D01*
X59175Y231750D01*
X59467Y231958D01*
X59758Y232000D01*
X60050Y231917D01*
X60258Y231708D01*
G01X62650Y229500D02*
Y232000D01*
X62150Y231500D01*
G01Y229500D02*
X63150D01*
G01X63200Y219000D02*
Y223000D01*
X55800D01*
G01X46500Y222017D02*
X44000D01*
Y223058D01*
X44125Y223392D01*
X44292Y223600D01*
X44625Y223683D01*
X44958Y223600D01*
X45167Y223350D01*
X45292Y223058D01*
Y222017D01*
G01Y223058D02*
X46500Y223683D01*
G01X46000Y225033D02*
X46292Y225283D01*
X46458Y225617D01*
X46500Y225992D01*
X46458Y226325D01*
X46250Y226658D01*
X46000Y226867D01*
X45750Y226908D01*
X45458Y226825D01*
X45250Y226533D01*
X45167Y226242D01*
Y225867D01*
G01Y226242D02*
X45042Y226492D01*
X44833Y226700D01*
X44583Y226783D01*
X44333Y226700D01*
X44125Y226492D01*
X44000Y226117D01*
X44042Y225742D01*
X44208Y225367D01*
G01X45458Y228258D02*
X45167Y228550D01*
X45000Y228800D01*
X44917Y229133D01*
X45000Y229425D01*
X45167Y229633D01*
X45417Y229800D01*
X45708Y229842D01*
X45958Y229800D01*
X46208Y229633D01*
X46417Y229383D01*
X46500Y229092D01*
X46417Y228758D01*
X46167Y228467D01*
X45792Y228300D01*
X45375Y228258D01*
X44833Y228342D01*
X44542Y228467D01*
X44250Y228675D01*
X44042Y228967D01*
X44000Y229258D01*
X44083Y229550D01*
X44292Y229758D01*
G01X44417Y231358D02*
X44167Y231608D01*
X44042Y231900D01*
X44000Y232233D01*
X44083Y232650D01*
X44292Y232942D01*
X44542Y233025D01*
X44792Y232983D01*
X45000Y232817D01*
X45417Y231983D01*
X45708Y231608D01*
X46125Y231358D01*
X46500Y231275D01*
Y233025D01*
G01X58900Y242000D02*
X54900D01*
Y234600D01*
G01X36708Y234817D02*
X36583Y234567D01*
X36500Y234275D01*
Y233942D01*
X36625Y233567D01*
X36833Y233275D01*
X37083Y233067D01*
X37500Y232900D01*
X37875Y232858D01*
X38250Y232942D01*
X38500Y233067D01*
X38750Y233317D01*
X38917Y233608D01*
X39000Y233900D01*
Y234192D01*
X38917Y234483D01*
X38792Y234733D01*
X38625Y234942D01*
G01X38500Y236083D02*
X38792Y236333D01*
X38958Y236667D01*
X39000Y237042D01*
X38958Y237375D01*
X38750Y237708D01*
X38500Y237917D01*
X38250Y237958D01*
X37958Y237875D01*
X37750Y237583D01*
X37667Y237292D01*
Y236917D01*
G01Y237292D02*
X37542Y237542D01*
X37333Y237750D01*
X37083Y237833D01*
X36833Y237750D01*
X36625Y237542D01*
X36500Y237167D01*
X36542Y236792D01*
X36708Y236417D01*
G01X36917Y239308D02*
X36667Y239558D01*
X36542Y239850D01*
X36500Y240183D01*
X36583Y240600D01*
X36792Y240892D01*
X37042Y240975D01*
X37292Y240933D01*
X37500Y240767D01*
X37917Y239933D01*
X38208Y239558D01*
X38625Y239308D01*
X39000Y239225D01*
Y240975D01*
G01X40708Y235317D02*
X40583Y235067D01*
X40500Y234775D01*
Y234442D01*
X40625Y234067D01*
X40833Y233775D01*
X41083Y233567D01*
X41500Y233400D01*
X41875Y233358D01*
X42250Y233442D01*
X42500Y233567D01*
X42750Y233817D01*
X42917Y234108D01*
X43000Y234400D01*
Y234692D01*
X42917Y234983D01*
X42792Y235233D01*
X42625Y235442D01*
G01X42500Y236583D02*
X42792Y236833D01*
X42958Y237167D01*
X43000Y237542D01*
X42958Y237875D01*
X42750Y238208D01*
X42500Y238417D01*
X42250Y238458D01*
X41958Y238375D01*
X41750Y238083D01*
X41667Y237792D01*
Y237417D01*
G01Y237792D02*
X41542Y238042D01*
X41333Y238250D01*
X41083Y238333D01*
X40833Y238250D01*
X40625Y238042D01*
X40500Y237667D01*
X40542Y237292D01*
X40708Y236917D01*
G01X43000Y240600D02*
X40500D01*
X41000Y240100D01*
G01X43000D02*
Y241100D01*
G01X43867Y202400D02*
Y204900D01*
X44908D01*
X45242Y204775D01*
X45450Y204608D01*
X45533Y204275D01*
X45450Y203942D01*
X45200Y203733D01*
X44908Y203608D01*
X43867D01*
G01X44908D02*
X45533Y202400D01*
G01X47008Y203442D02*
X47300Y203733D01*
X47550Y203900D01*
X47883Y203983D01*
X48175Y203900D01*
X48383Y203733D01*
X48550Y203483D01*
X48592Y203192D01*
X48550Y202942D01*
X48383Y202692D01*
X48133Y202483D01*
X47842Y202400D01*
X47508Y202483D01*
X47217Y202733D01*
X47050Y203108D01*
X47008Y203525D01*
X47092Y204067D01*
X47217Y204358D01*
X47425Y204650D01*
X47717Y204858D01*
X48008Y204900D01*
X48300Y204817D01*
X48508Y204608D01*
G01X49983Y202900D02*
X50233Y202608D01*
X50567Y202442D01*
X50942Y202400D01*
X51275Y202442D01*
X51608Y202650D01*
X51817Y202900D01*
X51858Y203150D01*
X51775Y203442D01*
X51483Y203650D01*
X51192Y203733D01*
X50817D01*
G01X51192D02*
X51442Y203858D01*
X51650Y204067D01*
X51733Y204317D01*
X51650Y204567D01*
X51442Y204775D01*
X51067Y204900D01*
X50692Y204858D01*
X50317Y204692D01*
G01X51900Y215400D02*
Y219400D01*
X44500D01*
G01X43867Y197900D02*
Y200400D01*
X44908D01*
X45242Y200275D01*
X45450Y200108D01*
X45533Y199775D01*
X45450Y199442D01*
X45200Y199233D01*
X44908Y199108D01*
X43867D01*
G01X44908D02*
X45533Y197900D01*
G01X47008Y198942D02*
X47300Y199233D01*
X47550Y199400D01*
X47883Y199483D01*
X48175Y199400D01*
X48383Y199233D01*
X48550Y198983D01*
X48592Y198692D01*
X48550Y198442D01*
X48383Y198192D01*
X48133Y197983D01*
X47842Y197900D01*
X47508Y197983D01*
X47217Y198233D01*
X47050Y198608D01*
X47008Y199025D01*
X47092Y199567D01*
X47217Y199858D01*
X47425Y200150D01*
X47717Y200358D01*
X48008Y200400D01*
X48300Y200317D01*
X48508Y200108D01*
G01X50108Y199983D02*
X50358Y200233D01*
X50650Y200358D01*
X50983Y200400D01*
X51400Y200317D01*
X51692Y200108D01*
X51775Y199858D01*
X51733Y199608D01*
X51567Y199400D01*
X50733Y198983D01*
X50358Y198692D01*
X50108Y198275D01*
X50025Y197900D01*
X51775D01*
G01X44500Y215400D02*
Y211400D01*
X51900D01*
G01X58500Y243067D02*
X56000D01*
Y244108D01*
X56125Y244442D01*
X56292Y244650D01*
X56625Y244733D01*
X56958Y244650D01*
X57167Y244400D01*
X57292Y244108D01*
Y243067D01*
G01Y244108D02*
X58500Y244733D01*
G01X57458Y246208D02*
X57167Y246500D01*
X57000Y246750D01*
X56917Y247083D01*
X57000Y247375D01*
X57167Y247583D01*
X57417Y247750D01*
X57708Y247792D01*
X57958Y247750D01*
X58208Y247583D01*
X58417Y247333D01*
X58500Y247042D01*
X58417Y246708D01*
X58167Y246417D01*
X57792Y246250D01*
X57375Y246208D01*
X56833Y246292D01*
X56542Y246417D01*
X56250Y246625D01*
X56042Y246917D01*
X56000Y247208D01*
X56083Y247500D01*
X56292Y247708D01*
G01X58500Y250100D02*
X56000D01*
X56500Y249600D01*
G01X58500D02*
Y250600D01*
G01X60600Y243800D02*
X64600D01*
Y251200D01*
G01X50500Y222017D02*
X48000D01*
Y223058D01*
X48125Y223392D01*
X48292Y223600D01*
X48625Y223683D01*
X48958Y223600D01*
X49167Y223350D01*
X49292Y223058D01*
Y222017D01*
G01Y223058D02*
X50500Y223683D01*
G01X50000Y225033D02*
X50292Y225283D01*
X50458Y225617D01*
X50500Y225992D01*
X50458Y226325D01*
X50250Y226658D01*
X50000Y226867D01*
X49750Y226908D01*
X49458Y226825D01*
X49250Y226533D01*
X49167Y226242D01*
Y225867D01*
G01Y226242D02*
X49042Y226492D01*
X48833Y226700D01*
X48583Y226783D01*
X48333Y226700D01*
X48125Y226492D01*
X48000Y226117D01*
X48042Y225742D01*
X48208Y225367D01*
G01X50125Y228133D02*
X50333Y228383D01*
X50458Y228675D01*
X50500Y229050D01*
X50417Y229425D01*
X50250Y229717D01*
X49958Y229925D01*
X49625Y229967D01*
X49292Y229883D01*
X49083Y229675D01*
X48917Y229383D01*
X48875Y229092D01*
X48917Y228800D01*
X49083Y228425D01*
X48000Y228550D01*
Y229675D01*
G01X50208Y231442D02*
X50417Y231733D01*
X50500Y232067D01*
X50417Y232400D01*
X50167Y232692D01*
X49792Y232900D01*
X49417Y232983D01*
X48958D01*
X48583Y232900D01*
X48250Y232692D01*
X48083Y232442D01*
X48000Y232150D01*
X48083Y231817D01*
X48250Y231567D01*
X48500Y231400D01*
X48833Y231317D01*
X49125Y231400D01*
X49417Y231608D01*
X49583Y231858D01*
X49625Y232150D01*
X49542Y232483D01*
X49333Y232733D01*
X48958Y232983D01*
G01X59000Y234600D02*
X63000D01*
Y242000D01*
G01X52517Y225500D02*
Y228000D01*
X53558D01*
X53892Y227875D01*
X54100Y227708D01*
X54183Y227375D01*
X54100Y227042D01*
X53850Y226833D01*
X53558Y226708D01*
X52517D01*
G01X53558D02*
X54183Y225500D01*
G01X55533Y226000D02*
X55783Y225708D01*
X56117Y225542D01*
X56492Y225500D01*
X56825Y225542D01*
X57158Y225750D01*
X57367Y226000D01*
X57408Y226250D01*
X57325Y226542D01*
X57033Y226750D01*
X56742Y226833D01*
X56367D01*
G01X56742D02*
X56992Y226958D01*
X57200Y227167D01*
X57283Y227417D01*
X57200Y227667D01*
X56992Y227875D01*
X56617Y228000D01*
X56242Y227958D01*
X55867Y227792D01*
G01X58633Y225875D02*
X58883Y225667D01*
X59175Y225542D01*
X59550Y225500D01*
X59925Y225583D01*
X60217Y225750D01*
X60425Y226042D01*
X60467Y226375D01*
X60383Y226708D01*
X60175Y226917D01*
X59883Y227083D01*
X59592Y227125D01*
X59300Y227083D01*
X58925Y226917D01*
X59050Y228000D01*
X60175D01*
G01X62650Y225500D02*
X62942Y225542D01*
X63275Y225667D01*
X63483Y225875D01*
X63567Y226167D01*
X63483Y226458D01*
X63233Y226708D01*
X62858Y226833D01*
X62442D01*
X62192Y226917D01*
X61983Y227125D01*
X61900Y227417D01*
X62025Y227708D01*
X62317Y227917D01*
X62650Y228000D01*
X62983Y227917D01*
X63275Y227708D01*
X63400Y227417D01*
X63317Y227125D01*
X63108Y226917D01*
X62858Y226833D01*
X62442D01*
X62067Y226708D01*
X61817Y226458D01*
X61733Y226167D01*
X61817Y225875D01*
X62025Y225667D01*
X62358Y225542D01*
X62650Y225500D01*
G01X55800Y219000D02*
Y215000D01*
X63200D01*
G01X59600Y205900D02*
X63600D01*
Y213300D01*
G01X54900Y201300D02*
Y197300D01*
X62300D01*
G01X48500Y265517D02*
X46000D01*
Y266558D01*
X46125Y266892D01*
X46292Y267100D01*
X46625Y267183D01*
X46958Y267100D01*
X47167Y266850D01*
X47292Y266558D01*
Y265517D01*
G01Y266558D02*
X48500Y267183D01*
G01Y269450D02*
X46000D01*
X46500Y268950D01*
G01X48500D02*
Y269950D01*
G01X48125Y271633D02*
X48333Y271883D01*
X48458Y272175D01*
X48500Y272550D01*
X48417Y272925D01*
X48250Y273217D01*
X47958Y273425D01*
X47625Y273467D01*
X47292Y273383D01*
X47083Y273175D01*
X46917Y272883D01*
X46875Y272592D01*
X46917Y272300D01*
X47083Y271925D01*
X46000Y272050D01*
Y273175D01*
G01X48500Y275650D02*
X46000D01*
X46500Y275150D01*
G01X48500D02*
Y276150D01*
G01X52300Y257900D02*
X56300D01*
Y265300D01*
G01X52500Y265517D02*
X50000D01*
Y266558D01*
X50125Y266892D01*
X50292Y267100D01*
X50625Y267183D01*
X50958Y267100D01*
X51167Y266850D01*
X51292Y266558D01*
Y265517D01*
G01Y266558D02*
X52500Y267183D01*
G01Y269450D02*
X50000D01*
X50500Y268950D01*
G01X52500D02*
Y269950D01*
G01X52125Y271633D02*
X52333Y271883D01*
X52458Y272175D01*
X52500Y272550D01*
X52417Y272925D01*
X52250Y273217D01*
X51958Y273425D01*
X51625Y273467D01*
X51292Y273383D01*
X51083Y273175D01*
X50917Y272883D01*
X50875Y272592D01*
X50917Y272300D01*
X51083Y271925D01*
X50000Y272050D01*
Y273175D01*
G01Y275650D02*
X50083Y275317D01*
X50292Y275067D01*
X50542Y274900D01*
X50875Y274775D01*
X51250Y274733D01*
X51625Y274775D01*
X51958Y274900D01*
X52208Y275067D01*
X52417Y275317D01*
X52500Y275650D01*
X52417Y275983D01*
X52208Y276233D01*
X51958Y276400D01*
X51625Y276525D01*
X51250Y276567D01*
X50875Y276525D01*
X50542Y276400D01*
X50292Y276233D01*
X50083Y275983D01*
X50000Y275650D01*
G01X56300Y257900D02*
X60300D01*
Y265300D01*
G01X57817Y272792D02*
X57567Y272917D01*
X57275Y273000D01*
X56942D01*
X56567Y272875D01*
X56275Y272667D01*
X56067Y272417D01*
X55900Y272000D01*
X55858Y271625D01*
X55942Y271250D01*
X56067Y271000D01*
X56317Y270750D01*
X56608Y270583D01*
X56900Y270500D01*
X57192D01*
X57483Y270583D01*
X57733Y270708D01*
X57942Y270875D01*
G01X59083D02*
X59333Y270667D01*
X59625Y270542D01*
X60000Y270500D01*
X60375Y270583D01*
X60667Y270750D01*
X60875Y271042D01*
X60917Y271375D01*
X60833Y271708D01*
X60625Y271917D01*
X60333Y272083D01*
X60042Y272125D01*
X59750Y272083D01*
X59375Y271917D01*
X59500Y273000D01*
X60625D01*
G01X63017Y270500D02*
X63100Y271042D01*
X63225Y271500D01*
X63392Y271917D01*
X63600Y272375D01*
X63933Y273000D01*
X62267D01*
G01X43817Y258292D02*
X43567Y258417D01*
X43275Y258500D01*
X42942D01*
X42567Y258375D01*
X42275Y258167D01*
X42067Y257917D01*
X41900Y257500D01*
X41858Y257125D01*
X41942Y256750D01*
X42067Y256500D01*
X42317Y256250D01*
X42608Y256083D01*
X42900Y256000D01*
X43192D01*
X43483Y256083D01*
X43733Y256208D01*
X43942Y256375D01*
G01X45083D02*
X45333Y256167D01*
X45625Y256042D01*
X46000Y256000D01*
X46375Y256083D01*
X46667Y256250D01*
X46875Y256542D01*
X46917Y256875D01*
X46833Y257208D01*
X46625Y257417D01*
X46333Y257583D01*
X46042Y257625D01*
X45750Y257583D01*
X45375Y257417D01*
X45500Y258500D01*
X46625D01*
G01X48308Y257042D02*
X48600Y257333D01*
X48850Y257500D01*
X49183Y257583D01*
X49475Y257500D01*
X49683Y257333D01*
X49850Y257083D01*
X49892Y256792D01*
X49850Y256542D01*
X49683Y256292D01*
X49433Y256083D01*
X49142Y256000D01*
X48808Y256083D01*
X48517Y256333D01*
X48350Y256708D01*
X48308Y257125D01*
X48392Y257667D01*
X48517Y257958D01*
X48725Y258250D01*
X49017Y258458D01*
X49308Y258500D01*
X49600Y258417D01*
X49808Y258208D01*
G01X35200Y251500D02*
X39200D01*
Y258900D01*
G01X55567Y274500D02*
Y277000D01*
X56608D01*
X56942Y276875D01*
X57150Y276708D01*
X57233Y276375D01*
X57150Y276042D01*
X56900Y275833D01*
X56608Y275708D01*
X55567D01*
G01X56608D02*
X57233Y274500D01*
G01X58708Y275542D02*
X59000Y275833D01*
X59250Y276000D01*
X59583Y276083D01*
X59875Y276000D01*
X60083Y275833D01*
X60250Y275583D01*
X60292Y275292D01*
X60250Y275042D01*
X60083Y274792D01*
X59833Y274583D01*
X59542Y274500D01*
X59208Y274583D01*
X58917Y274833D01*
X58750Y275208D01*
X58708Y275625D01*
X58792Y276167D01*
X58917Y276458D01*
X59125Y276750D01*
X59417Y276958D01*
X59708Y277000D01*
X60000Y276917D01*
X60208Y276708D01*
G01X62600Y277000D02*
X62267Y276917D01*
X62017Y276708D01*
X61850Y276458D01*
X61725Y276125D01*
X61683Y275750D01*
X61725Y275375D01*
X61850Y275042D01*
X62017Y274792D01*
X62267Y274583D01*
X62600Y274500D01*
X62933Y274583D01*
X63183Y274792D01*
X63350Y275042D01*
X63475Y275375D01*
X63517Y275750D01*
X63475Y276125D01*
X63350Y276458D01*
X63183Y276708D01*
X62933Y276917D01*
X62600Y277000D01*
G01X65000Y269700D02*
X61000D01*
Y262300D01*
G01X52517Y284500D02*
Y287000D01*
X53558D01*
X53892Y286875D01*
X54100Y286708D01*
X54183Y286375D01*
X54100Y286042D01*
X53850Y285833D01*
X53558Y285708D01*
X52517D01*
G01X53558D02*
X54183Y284500D01*
G01X56450D02*
Y287000D01*
X55950Y286500D01*
G01Y284500D02*
X56950D01*
G01X58758Y285542D02*
X59050Y285833D01*
X59300Y286000D01*
X59633Y286083D01*
X59925Y286000D01*
X60133Y285833D01*
X60300Y285583D01*
X60342Y285292D01*
X60300Y285042D01*
X60133Y284792D01*
X59883Y284583D01*
X59592Y284500D01*
X59258Y284583D01*
X58967Y284833D01*
X58800Y285208D01*
X58758Y285625D01*
X58842Y286167D01*
X58967Y286458D01*
X59175Y286750D01*
X59467Y286958D01*
X59758Y287000D01*
X60050Y286917D01*
X60258Y286708D01*
G01X62567Y284500D02*
X62650Y285042D01*
X62775Y285500D01*
X62942Y285917D01*
X63150Y286375D01*
X63483Y287000D01*
X61817D01*
G01X62300Y278000D02*
Y282000D01*
X54900D01*
G01X37267Y336100D02*
Y338600D01*
X38308D01*
X38642Y338475D01*
X38850Y338308D01*
X38933Y337975D01*
X38850Y337642D01*
X38600Y337433D01*
X38308Y337308D01*
X37267D01*
G01X38308D02*
X38933Y336100D01*
G01X40283Y336600D02*
X40533Y336308D01*
X40867Y336142D01*
X41242Y336100D01*
X41575Y336142D01*
X41908Y336350D01*
X42117Y336600D01*
X42158Y336850D01*
X42075Y337142D01*
X41783Y337350D01*
X41492Y337433D01*
X41117D01*
G01X41492D02*
X41742Y337558D01*
X41950Y337767D01*
X42033Y338017D01*
X41950Y338267D01*
X41742Y338475D01*
X41367Y338600D01*
X40992Y338558D01*
X40617Y338392D01*
G01X44300Y338600D02*
X43967Y338517D01*
X43717Y338308D01*
X43550Y338058D01*
X43425Y337725D01*
X43383Y337350D01*
X43425Y336975D01*
X43550Y336642D01*
X43717Y336392D01*
X43967Y336183D01*
X44300Y336100D01*
X44633Y336183D01*
X44883Y336392D01*
X45050Y336642D01*
X45175Y336975D01*
X45217Y337350D01*
X45175Y337725D01*
X45050Y338058D01*
X44883Y338308D01*
X44633Y338517D01*
X44300Y338600D01*
G01X41200Y349200D02*
X37200D01*
Y341800D01*
G01X40000Y307450D02*
X39958Y307117D01*
X39792Y306825D01*
X39542Y306575D01*
X39250Y306408D01*
X38917Y306325D01*
X38583D01*
X38250Y306408D01*
X37958Y306575D01*
X37708Y306825D01*
X37542Y307117D01*
X37500Y307450D01*
X37542Y307783D01*
X37708Y308075D01*
X37958Y308325D01*
X38250Y308492D01*
X38583Y308575D01*
X38917D01*
X39250Y308492D01*
X39542Y308325D01*
X39792Y308075D01*
X39958Y307783D01*
X40000Y307450D01*
G01X39333Y307783D02*
X40000Y308283D01*
G01Y311050D02*
X37500D01*
X39292Y309508D01*
Y311592D01*
G01X35300Y302100D02*
Y316100D01*
G01X80317Y345292D02*
X80067Y345417D01*
X79775Y345500D01*
X79442D01*
X79067Y345375D01*
X78775Y345167D01*
X78567Y344917D01*
X78400Y344500D01*
X78358Y344125D01*
X78442Y343750D01*
X78567Y343500D01*
X78817Y343250D01*
X79108Y343083D01*
X79400Y343000D01*
X79692D01*
X79983Y343083D01*
X80233Y343208D01*
X80442Y343375D01*
G01X81542Y343000D02*
Y345500D01*
X83458Y343000D01*
Y345500D01*
G01X84892Y343292D02*
X85183Y343083D01*
X85517Y343000D01*
X85850Y343083D01*
X86142Y343333D01*
X86350Y343708D01*
X86433Y344083D01*
Y344542D01*
X86350Y344917D01*
X86142Y345250D01*
X85892Y345417D01*
X85600Y345500D01*
X85267Y345417D01*
X85017Y345250D01*
X84850Y345000D01*
X84767Y344667D01*
X84850Y344375D01*
X85058Y344083D01*
X85308Y343917D01*
X85600Y343875D01*
X85933Y343958D01*
X86183Y344167D01*
X86433Y344542D01*
G01X37500Y352017D02*
X40000D01*
Y353683D01*
G01Y356783D02*
Y355117D01*
X37500D01*
Y356783D01*
G01X38708Y356117D02*
Y355117D01*
G01X40000Y358133D02*
X37500D01*
Y358967D01*
X37625Y359300D01*
X37792Y359550D01*
X38042Y359758D01*
X38333Y359925D01*
X38750Y359967D01*
X39167Y359925D01*
X39458Y359758D01*
X39708Y359550D01*
X39875Y359300D01*
X40000Y358967D01*
Y358133D01*
G01X39625Y361233D02*
X39833Y361483D01*
X39958Y361775D01*
X40000Y362150D01*
X39917Y362525D01*
X39750Y362817D01*
X39458Y363025D01*
X39125Y363067D01*
X38792Y362983D01*
X38583Y362775D01*
X38417Y362483D01*
X38375Y362192D01*
X38417Y361900D01*
X38583Y361525D01*
X37500Y361650D01*
Y362775D01*
G01X74300Y389500D02*
X85500D01*
G01X74300Y407500D02*
Y389500D01*
G01X54500Y388800D02*
Y406800D01*
G01X43300Y388800D02*
X54500D01*
G01X71983Y376500D02*
Y379000D01*
X72817D01*
X73150Y378875D01*
X73400Y378708D01*
X73608Y378458D01*
X73775Y378167D01*
X73817Y377750D01*
X73775Y377333D01*
X73608Y377042D01*
X73400Y376792D01*
X73150Y376625D01*
X72817Y376500D01*
X71983D01*
G01X76000D02*
Y379000D01*
X75500Y378500D01*
G01Y376500D02*
X76500D01*
G01X78183Y376875D02*
X78433Y376667D01*
X78725Y376542D01*
X79100Y376500D01*
X79475Y376583D01*
X79767Y376750D01*
X79975Y377042D01*
X80017Y377375D01*
X79933Y377708D01*
X79725Y377917D01*
X79433Y378083D01*
X79142Y378125D01*
X78850Y378083D01*
X78475Y377917D01*
X78600Y379000D01*
X79725D01*
G01X64400Y374400D02*
X104600D01*
G01X64400Y349400D02*
Y374400D01*
G01X104600Y349400D02*
X64400D01*
G01X49467Y435000D02*
Y437500D01*
X50467D01*
X50800Y437375D01*
X51050Y437083D01*
X51133Y436750D01*
X51050Y436417D01*
X50842Y436167D01*
X50467Y436042D01*
X49467D01*
G01X52567Y435000D02*
Y437500D01*
X53608D01*
X53942Y437375D01*
X54150Y437208D01*
X54233Y436875D01*
X54150Y436542D01*
X53900Y436333D01*
X53608Y436208D01*
X52567D01*
G01X53608D02*
X54233Y435000D01*
G01X56500D02*
Y437500D01*
X56000Y437000D01*
G01Y435000D02*
X57000D01*
G01X59600D02*
Y437500D01*
X59100Y437000D01*
G01Y435000D02*
X60100D01*
G01X62700D02*
X62992Y435042D01*
X63325Y435167D01*
X63533Y435375D01*
X63617Y435667D01*
X63533Y435958D01*
X63283Y436208D01*
X62908Y436333D01*
X62492D01*
X62242Y436417D01*
X62033Y436625D01*
X61950Y436917D01*
X62075Y437208D01*
X62367Y437417D01*
X62700Y437500D01*
X63033Y437417D01*
X63325Y437208D01*
X63450Y436917D01*
X63367Y436625D01*
X63158Y436417D01*
X62908Y436333D01*
X62492D01*
X62117Y436208D01*
X61867Y435958D01*
X61783Y435667D01*
X61867Y435375D01*
X62075Y435167D01*
X62408Y435042D01*
X62700Y435000D01*
G01X68800Y433300D02*
Y429300D01*
X76200D01*
G01X53017Y443000D02*
Y445500D01*
X54017D01*
X54350Y445375D01*
X54600Y445083D01*
X54683Y444750D01*
X54600Y444417D01*
X54392Y444167D01*
X54017Y444042D01*
X53017D01*
G01X56950Y443000D02*
X56617Y443042D01*
X56325Y443208D01*
X56075Y443458D01*
X55908Y443750D01*
X55825Y444083D01*
Y444417D01*
X55908Y444750D01*
X56075Y445042D01*
X56325Y445292D01*
X56617Y445458D01*
X56950Y445500D01*
X57283Y445458D01*
X57575Y445292D01*
X57825Y445042D01*
X57992Y444750D01*
X58075Y444417D01*
Y444083D01*
X57992Y443750D01*
X57825Y443458D01*
X57575Y443208D01*
X57283Y443042D01*
X56950Y443000D01*
G01X57283Y443667D02*
X57783Y443000D01*
G01X60050D02*
Y445500D01*
X59550Y445000D01*
G01Y443000D02*
X60550D01*
G01X63150D02*
Y445500D01*
X62650Y445000D01*
G01Y443000D02*
X63650D01*
G01X65650Y435800D02*
X87350D01*
G01X65650Y465800D02*
Y435800D01*
G01X85500Y407500D02*
X74300D01*
G01Y410000D02*
X85500D01*
G01X74300Y428000D02*
Y410000D01*
G01X85500Y428000D02*
X74300D01*
G01X54500Y427300D02*
X43300D01*
G01X54500Y409300D02*
Y427300D01*
G01X43300Y409300D02*
X54500D01*
G01Y406800D02*
X43300D01*
G01X87350Y465800D02*
X65650D01*
G01X64250Y497500D02*
X79750D01*
Y467500D01*
X64250D01*
Y497500D01*
G01X85017Y502000D02*
Y504500D01*
X86017D01*
X86350Y504375D01*
X86600Y504083D01*
X86683Y503750D01*
X86600Y503417D01*
X86392Y503167D01*
X86017Y503042D01*
X85017D01*
G01X88117Y502000D02*
Y504500D01*
X89158D01*
X89492Y504375D01*
X89700Y504208D01*
X89783Y503875D01*
X89700Y503542D01*
X89450Y503333D01*
X89158Y503208D01*
X88117D01*
G01X89158D02*
X89783Y502000D01*
G01X91258Y503042D02*
X91550Y503333D01*
X91800Y503500D01*
X92133Y503583D01*
X92425Y503500D01*
X92633Y503333D01*
X92800Y503083D01*
X92842Y502792D01*
X92800Y502542D01*
X92633Y502292D01*
X92383Y502083D01*
X92092Y502000D01*
X91758Y502083D01*
X91467Y502333D01*
X91300Y502708D01*
X91258Y503125D01*
X91342Y503667D01*
X91467Y503958D01*
X91675Y504250D01*
X91967Y504458D01*
X92258Y504500D01*
X92550Y504417D01*
X92758Y504208D01*
G01X95150Y502000D02*
Y504500D01*
X94650Y504000D01*
G01Y502000D02*
X95650D01*
G01X82250Y497500D02*
X97750D01*
Y467500D01*
X82250D01*
Y497500D01*
G01X93300Y556900D02*
Y548900D01*
X80900D01*
Y556900D01*
X93300D01*
G01X83517Y519000D02*
Y521500D01*
X84517D01*
X84850Y521375D01*
X85100Y521083D01*
X85183Y520750D01*
X85100Y520417D01*
X84892Y520167D01*
X84517Y520042D01*
X83517D01*
G01X86617Y519000D02*
Y521500D01*
X87658D01*
X87992Y521375D01*
X88200Y521208D01*
X88283Y520875D01*
X88200Y520542D01*
X87950Y520333D01*
X87658Y520208D01*
X86617D01*
G01X87658D02*
X88283Y519000D01*
G01X89842Y519292D02*
X90133Y519083D01*
X90467Y519000D01*
X90800Y519083D01*
X91092Y519333D01*
X91300Y519708D01*
X91383Y520083D01*
Y520542D01*
X91300Y520917D01*
X91092Y521250D01*
X90842Y521417D01*
X90550Y521500D01*
X90217Y521417D01*
X89967Y521250D01*
X89800Y521000D01*
X89717Y520667D01*
X89800Y520375D01*
X90008Y520083D01*
X90258Y519917D01*
X90550Y519875D01*
X90883Y519958D01*
X91133Y520167D01*
X91383Y520542D01*
G01X93650Y519000D02*
X93942Y519042D01*
X94275Y519167D01*
X94483Y519375D01*
X94567Y519667D01*
X94483Y519958D01*
X94233Y520208D01*
X93858Y520333D01*
X93442D01*
X93192Y520417D01*
X92983Y520625D01*
X92900Y520917D01*
X93025Y521208D01*
X93317Y521417D01*
X93650Y521500D01*
X93983Y521417D01*
X94275Y521208D01*
X94400Y520917D01*
X94317Y520625D01*
X94108Y520417D01*
X93858Y520333D01*
X93442D01*
X93067Y520208D01*
X92817Y519958D01*
X92733Y519667D01*
X92817Y519375D01*
X93025Y519167D01*
X93358Y519042D01*
X93650Y519000D01*
G01X68000Y543350D02*
X70500D01*
G01X68000Y542392D02*
Y544308D01*
G01X70500Y545617D02*
X68000D01*
Y546617D01*
X68125Y546950D01*
X68417Y547200D01*
X68750Y547283D01*
X69083Y547200D01*
X69333Y546992D01*
X69458Y546617D01*
Y545617D01*
G01X68417Y548758D02*
X68167Y549008D01*
X68042Y549300D01*
X68000Y549633D01*
X68083Y550050D01*
X68292Y550342D01*
X68542Y550425D01*
X68792Y550383D01*
X69000Y550217D01*
X69417Y549383D01*
X69708Y549008D01*
X70125Y548758D01*
X70500Y548675D01*
Y550425D01*
G01X70000Y551733D02*
X70292Y551983D01*
X70458Y552317D01*
X70500Y552692D01*
X70458Y553025D01*
X70250Y553358D01*
X70000Y553567D01*
X69750Y553608D01*
X69458Y553525D01*
X69250Y553233D01*
X69167Y552942D01*
Y552567D01*
G01Y552942D02*
X69042Y553192D01*
X68833Y553400D01*
X68583Y553483D01*
X68333Y553400D01*
X68125Y553192D01*
X68000Y552817D01*
X68042Y552442D01*
X68208Y552067D01*
G01X48467Y551500D02*
Y554000D01*
X49467D01*
X49800Y553875D01*
X50050Y553583D01*
X50133Y553250D01*
X50050Y552917D01*
X49842Y552667D01*
X49467Y552542D01*
X48467D01*
G01X51567Y551500D02*
Y554000D01*
X52608D01*
X52942Y553875D01*
X53150Y553708D01*
X53233Y553375D01*
X53150Y553042D01*
X52900Y552833D01*
X52608Y552708D01*
X51567D01*
G01X52608D02*
X53233Y551500D01*
G01X55500D02*
Y554000D01*
X55000Y553500D01*
G01Y551500D02*
X56000D01*
G01X58600D02*
Y554000D01*
X58100Y553500D01*
G01Y551500D02*
X59100D01*
G01X61700Y554000D02*
X61367Y553917D01*
X61117Y553708D01*
X60950Y553458D01*
X60825Y553125D01*
X60783Y552750D01*
X60825Y552375D01*
X60950Y552042D01*
X61117Y551792D01*
X61367Y551583D01*
X61700Y551500D01*
X62033Y551583D01*
X62283Y551792D01*
X62450Y552042D01*
X62575Y552375D01*
X62617Y552750D01*
X62575Y553125D01*
X62450Y553458D01*
X62283Y553708D01*
X62033Y553917D01*
X61700Y554000D01*
G01X66500Y544967D02*
X64000D01*
Y545967D01*
X64125Y546300D01*
X64417Y546550D01*
X64750Y546633D01*
X65083Y546550D01*
X65333Y546342D01*
X65458Y545967D01*
Y544967D01*
G01X66500Y548067D02*
X64000D01*
Y549108D01*
X64125Y549442D01*
X64292Y549650D01*
X64625Y549733D01*
X64958Y549650D01*
X65167Y549400D01*
X65292Y549108D01*
Y548067D01*
G01Y549108D02*
X66500Y549733D01*
G01Y552000D02*
X64000D01*
X64500Y551500D01*
G01X66500D02*
Y552500D01*
G01X64000Y555100D02*
X64083Y554767D01*
X64292Y554517D01*
X64542Y554350D01*
X64875Y554225D01*
X65250Y554183D01*
X65625Y554225D01*
X65958Y554350D01*
X66208Y554517D01*
X66417Y554767D01*
X66500Y555100D01*
X66417Y555433D01*
X66208Y555683D01*
X65958Y555850D01*
X65625Y555975D01*
X65250Y556017D01*
X64875Y555975D01*
X64542Y555850D01*
X64292Y555683D01*
X64083Y555433D01*
X64000Y555100D01*
G01X65458Y557408D02*
X65167Y557700D01*
X65000Y557950D01*
X64917Y558283D01*
X65000Y558575D01*
X65167Y558783D01*
X65417Y558950D01*
X65708Y558992D01*
X65958Y558950D01*
X66208Y558783D01*
X66417Y558533D01*
X66500Y558242D01*
X66417Y557908D01*
X66167Y557617D01*
X65792Y557450D01*
X65375Y557408D01*
X64833Y557492D01*
X64542Y557617D01*
X64250Y557825D01*
X64042Y558117D01*
X64000Y558408D01*
X64083Y558700D01*
X64292Y558908D01*
G01X69500Y524467D02*
X67000D01*
Y525467D01*
X67125Y525800D01*
X67417Y526050D01*
X67750Y526133D01*
X68083Y526050D01*
X68333Y525842D01*
X68458Y525467D01*
Y524467D01*
G01X69500Y527567D02*
X67000D01*
Y528608D01*
X67125Y528942D01*
X67292Y529150D01*
X67625Y529233D01*
X67958Y529150D01*
X68167Y528900D01*
X68292Y528608D01*
Y527567D01*
G01Y528608D02*
X69500Y529233D01*
G01Y531500D02*
X67000D01*
X67500Y531000D01*
G01X69500D02*
Y532000D01*
G01X67000Y534600D02*
X67083Y534267D01*
X67292Y534017D01*
X67542Y533850D01*
X67875Y533725D01*
X68250Y533683D01*
X68625Y533725D01*
X68958Y533850D01*
X69208Y534017D01*
X69417Y534267D01*
X69500Y534600D01*
X69417Y534933D01*
X69208Y535183D01*
X68958Y535350D01*
X68625Y535475D01*
X68250Y535517D01*
X67875Y535475D01*
X67542Y535350D01*
X67292Y535183D01*
X67083Y534933D01*
X67000Y534600D01*
G01X69500Y538200D02*
X67000D01*
X68792Y536658D01*
Y538742D01*
G01X71700Y537900D02*
X75700D01*
Y545300D01*
G01X74000Y524017D02*
X71500D01*
Y525017D01*
X71625Y525350D01*
X71917Y525600D01*
X72250Y525683D01*
X72583Y525600D01*
X72833Y525392D01*
X72958Y525017D01*
Y524017D01*
G01X74000Y527117D02*
X71500D01*
Y528158D01*
X71625Y528492D01*
X71792Y528700D01*
X72125Y528783D01*
X72458Y528700D01*
X72667Y528450D01*
X72792Y528158D01*
Y527117D01*
G01Y528158D02*
X74000Y528783D01*
G01X73708Y530342D02*
X73917Y530633D01*
X74000Y530967D01*
X73917Y531300D01*
X73667Y531592D01*
X73292Y531800D01*
X72917Y531883D01*
X72458D01*
X72083Y531800D01*
X71750Y531592D01*
X71583Y531342D01*
X71500Y531050D01*
X71583Y530717D01*
X71750Y530467D01*
X72000Y530300D01*
X72333Y530217D01*
X72625Y530300D01*
X72917Y530508D01*
X73083Y530758D01*
X73125Y531050D01*
X73042Y531383D01*
X72833Y531633D01*
X72458Y531883D01*
G01X73625Y533233D02*
X73833Y533483D01*
X73958Y533775D01*
X74000Y534150D01*
X73917Y534525D01*
X73750Y534817D01*
X73458Y535025D01*
X73125Y535067D01*
X72792Y534983D01*
X72583Y534775D01*
X72417Y534483D01*
X72375Y534192D01*
X72417Y533900D01*
X72583Y533525D01*
X71500Y533650D01*
Y534775D01*
G01X83400Y535900D02*
X79400D01*
Y528500D01*
G01X83517Y523500D02*
Y526000D01*
X84517D01*
X84850Y525875D01*
X85100Y525583D01*
X85183Y525250D01*
X85100Y524917D01*
X84892Y524667D01*
X84517Y524542D01*
X83517D01*
G01X88367Y525792D02*
X88117Y525917D01*
X87825Y526000D01*
X87492D01*
X87117Y525875D01*
X86825Y525667D01*
X86617Y525417D01*
X86450Y525000D01*
X86408Y524625D01*
X86492Y524250D01*
X86617Y524000D01*
X86867Y523750D01*
X87158Y523583D01*
X87450Y523500D01*
X87742D01*
X88033Y523583D01*
X88283Y523708D01*
X88492Y523875D01*
G01X90550Y523500D02*
X90842Y523542D01*
X91175Y523667D01*
X91383Y523875D01*
X91467Y524167D01*
X91383Y524458D01*
X91133Y524708D01*
X90758Y524833D01*
X90342D01*
X90092Y524917D01*
X89883Y525125D01*
X89800Y525417D01*
X89925Y525708D01*
X90217Y525917D01*
X90550Y526000D01*
X90883Y525917D01*
X91175Y525708D01*
X91300Y525417D01*
X91217Y525125D01*
X91008Y524917D01*
X90758Y524833D01*
X90342D01*
X89967Y524708D01*
X89717Y524458D01*
X89633Y524167D01*
X89717Y523875D01*
X89925Y523667D01*
X90258Y523542D01*
X90550Y523500D01*
G01X93567D02*
X93650Y524042D01*
X93775Y524500D01*
X93942Y524917D01*
X94150Y525375D01*
X94483Y526000D01*
X92817D01*
G01X66017Y502500D02*
Y505000D01*
X67017D01*
X67350Y504875D01*
X67600Y504583D01*
X67683Y504250D01*
X67600Y503917D01*
X67392Y503667D01*
X67017Y503542D01*
X66017D01*
G01X69117Y502500D02*
Y505000D01*
X70158D01*
X70492Y504875D01*
X70700Y504708D01*
X70783Y504375D01*
X70700Y504042D01*
X70450Y503833D01*
X70158Y503708D01*
X69117D01*
G01X70158D02*
X70783Y502500D01*
G01X72258Y503542D02*
X72550Y503833D01*
X72800Y504000D01*
X73133Y504083D01*
X73425Y504000D01*
X73633Y503833D01*
X73800Y503583D01*
X73842Y503292D01*
X73800Y503042D01*
X73633Y502792D01*
X73383Y502583D01*
X73092Y502500D01*
X72758Y502583D01*
X72467Y502833D01*
X72300Y503208D01*
X72258Y503625D01*
X72342Y504167D01*
X72467Y504458D01*
X72675Y504750D01*
X72967Y504958D01*
X73258Y505000D01*
X73550Y504917D01*
X73758Y504708D01*
G01X76150Y505000D02*
X75817Y504917D01*
X75567Y504708D01*
X75400Y504458D01*
X75275Y504125D01*
X75233Y503750D01*
X75275Y503375D01*
X75400Y503042D01*
X75567Y502792D01*
X75817Y502583D01*
X76150Y502500D01*
X76483Y502583D01*
X76733Y502792D01*
X76900Y503042D01*
X77025Y503375D01*
X77067Y503750D01*
X77025Y504125D01*
X76900Y504458D01*
X76733Y504708D01*
X76483Y504917D01*
X76150Y505000D01*
G01X66967Y561200D02*
Y563700D01*
X67967D01*
X68300Y563575D01*
X68550Y563283D01*
X68633Y562950D01*
X68550Y562617D01*
X68342Y562367D01*
X67967Y562242D01*
X66967D01*
G01X69983Y563700D02*
Y561908D01*
X70150Y561533D01*
X70483Y561283D01*
X70900Y561200D01*
X71317Y561283D01*
X71650Y561533D01*
X71817Y561908D01*
Y563700D01*
G01X73208Y562242D02*
X73500Y562533D01*
X73750Y562700D01*
X74083Y562783D01*
X74375Y562700D01*
X74583Y562533D01*
X74750Y562283D01*
X74792Y561992D01*
X74750Y561742D01*
X74583Y561492D01*
X74333Y561283D01*
X74042Y561200D01*
X73708Y561283D01*
X73417Y561533D01*
X73250Y561908D01*
X73208Y562325D01*
X73292Y562867D01*
X73417Y563158D01*
X73625Y563450D01*
X73917Y563658D01*
X74208Y563700D01*
X74500Y563617D01*
X74708Y563408D01*
G01X84903Y600702D02*
X61903D01*
G01X84903Y639502D02*
Y600702D01*
G01X61903D02*
Y639502D01*
G01X56000Y572533D02*
X53500D01*
Y573367D01*
X53625Y573700D01*
X53792Y573950D01*
X54042Y574158D01*
X54333Y574325D01*
X54750Y574367D01*
X55167Y574325D01*
X55458Y574158D01*
X55708Y573950D01*
X55875Y573700D01*
X56000Y573367D01*
Y572533D01*
G01Y577050D02*
X53500D01*
X55292Y575508D01*
Y577592D01*
G01X54500Y580000D02*
X75500D01*
G01D02*
Y588000D01*
G01D02*
X54500D01*
G01D02*
Y580000D01*
G01X39500Y595533D02*
X37000D01*
Y596367D01*
X37125Y596700D01*
X37292Y596950D01*
X37542Y597158D01*
X37833Y597325D01*
X38250Y597367D01*
X38667Y597325D01*
X38958Y597158D01*
X39208Y596950D01*
X39375Y596700D01*
X39500Y596367D01*
Y595533D01*
G01X37417Y598758D02*
X37167Y599008D01*
X37042Y599300D01*
X37000Y599633D01*
X37083Y600050D01*
X37292Y600342D01*
X37542Y600425D01*
X37792Y600383D01*
X38000Y600217D01*
X38417Y599383D01*
X38708Y599008D01*
X39125Y598758D01*
X39500Y598675D01*
Y600425D01*
G01X62200Y597000D02*
X41200D01*
G01D02*
Y589000D01*
G01D02*
X62200D01*
G01D02*
Y597000D01*
G01X66567Y595000D02*
Y597500D01*
X67608D01*
X67942Y597375D01*
X68150Y597208D01*
X68233Y596875D01*
X68150Y596542D01*
X67900Y596333D01*
X67608Y596208D01*
X66567D01*
G01X67608D02*
X68233Y595000D01*
G01X70417D02*
X70500Y595542D01*
X70625Y596000D01*
X70792Y596417D01*
X71000Y596875D01*
X71333Y597500D01*
X69667D01*
G01X72808Y597083D02*
X73058Y597333D01*
X73350Y597458D01*
X73683Y597500D01*
X74100Y597417D01*
X74392Y597208D01*
X74475Y596958D01*
X74433Y596708D01*
X74267Y596500D01*
X73433Y596083D01*
X73058Y595792D01*
X72808Y595375D01*
X72725Y595000D01*
X74475D01*
G01X45000Y565567D02*
X42500D01*
Y566608D01*
X42625Y566942D01*
X42792Y567150D01*
X43125Y567233D01*
X43458Y567150D01*
X43667Y566900D01*
X43792Y566608D01*
Y565567D01*
G01Y566608D02*
X45000Y567233D01*
G01Y569417D02*
X44458Y569500D01*
X44000Y569625D01*
X43583Y569792D01*
X43125Y570000D01*
X42500Y570333D01*
Y568667D01*
G01Y572600D02*
X42583Y572267D01*
X42792Y572017D01*
X43042Y571850D01*
X43375Y571725D01*
X43750Y571683D01*
X44125Y571725D01*
X44458Y571850D01*
X44708Y572017D01*
X44917Y572267D01*
X45000Y572600D01*
X44917Y572933D01*
X44708Y573183D01*
X44458Y573350D01*
X44125Y573475D01*
X43750Y573517D01*
X43375Y573475D01*
X43042Y573350D01*
X42792Y573183D01*
X42583Y572933D01*
X42500Y572600D01*
G01X58500Y557017D02*
X56000D01*
Y558017D01*
X56125Y558350D01*
X56417Y558600D01*
X56750Y558683D01*
X57083Y558600D01*
X57333Y558392D01*
X57458Y558017D01*
Y557017D01*
G01X56208Y561867D02*
X56083Y561617D01*
X56000Y561325D01*
Y560992D01*
X56125Y560617D01*
X56333Y560325D01*
X56583Y560117D01*
X57000Y559950D01*
X57375Y559908D01*
X57750Y559992D01*
X58000Y560117D01*
X58250Y560367D01*
X58417Y560658D01*
X58500Y560950D01*
Y561242D01*
X58417Y561533D01*
X58292Y561783D01*
X58125Y561992D01*
G01X58208Y563342D02*
X58417Y563633D01*
X58500Y563967D01*
X58417Y564300D01*
X58167Y564592D01*
X57792Y564800D01*
X57417Y564883D01*
X56958D01*
X56583Y564800D01*
X56250Y564592D01*
X56083Y564342D01*
X56000Y564050D01*
X56083Y563717D01*
X56250Y563467D01*
X56500Y563300D01*
X56833Y563217D01*
X57125Y563300D01*
X57417Y563508D01*
X57583Y563758D01*
X57625Y564050D01*
X57542Y564383D01*
X57333Y564633D01*
X56958Y564883D01*
G01X58500Y567150D02*
X56000D01*
X56500Y566650D01*
G01X58500D02*
Y567650D01*
G01X62500Y555967D02*
X60000D01*
Y556967D01*
X60125Y557300D01*
X60417Y557550D01*
X60750Y557633D01*
X61083Y557550D01*
X61333Y557342D01*
X61458Y556967D01*
Y555967D01*
G01X62500Y559067D02*
X60000D01*
Y560108D01*
X60125Y560442D01*
X60292Y560650D01*
X60625Y560733D01*
X60958Y560650D01*
X61167Y560400D01*
X61292Y560108D01*
Y559067D01*
G01Y560108D02*
X62500Y560733D01*
G01Y563000D02*
X60000D01*
X60500Y562500D01*
G01X62500D02*
Y563500D01*
G01Y566100D02*
X60000D01*
X60500Y565600D01*
G01X62500D02*
Y566600D01*
G01Y569700D02*
X60000D01*
X61792Y568158D01*
Y570242D01*
G01X76600Y569100D02*
X80600D01*
Y576500D01*
G01X89100Y567900D02*
Y571900D01*
X81700D01*
G01X71900Y553400D02*
X75900D01*
Y560800D01*
G01X79600Y577467D02*
X77100D01*
Y578508D01*
X77225Y578842D01*
X77392Y579050D01*
X77725Y579133D01*
X78058Y579050D01*
X78267Y578800D01*
X78392Y578508D01*
Y577467D01*
G01Y578508D02*
X79600Y579133D01*
G01Y581317D02*
X79058Y581400D01*
X78600Y581525D01*
X78183Y581692D01*
X77725Y581900D01*
X77100Y582233D01*
Y580567D01*
G01X78558Y583708D02*
X78267Y584000D01*
X78100Y584250D01*
X78017Y584583D01*
X78100Y584875D01*
X78267Y585083D01*
X78517Y585250D01*
X78808Y585292D01*
X79058Y585250D01*
X79308Y585083D01*
X79517Y584833D01*
X79600Y584542D01*
X79517Y584208D01*
X79267Y583917D01*
X78892Y583750D01*
X78475Y583708D01*
X77933Y583792D01*
X77642Y583917D01*
X77350Y584125D01*
X77142Y584417D01*
X77100Y584708D01*
X77183Y585000D01*
X77392Y585208D01*
G01X80400Y593000D02*
X76400D01*
Y585600D01*
G01X84500Y590567D02*
X82000D01*
Y591608D01*
X82125Y591942D01*
X82292Y592150D01*
X82625Y592233D01*
X82958Y592150D01*
X83167Y591900D01*
X83292Y591608D01*
Y590567D01*
G01Y591608D02*
X84500Y592233D01*
G01Y594500D02*
X82000D01*
X82500Y594000D01*
G01X84500D02*
Y595000D01*
G01X82417Y596808D02*
X82167Y597058D01*
X82042Y597350D01*
X82000Y597683D01*
X82083Y598100D01*
X82292Y598392D01*
X82542Y598475D01*
X82792Y598433D01*
X83000Y598267D01*
X83417Y597433D01*
X83708Y597058D01*
X84125Y596808D01*
X84500Y596725D01*
Y598475D01*
G01X51500Y580067D02*
X49000D01*
Y581108D01*
X49125Y581442D01*
X49292Y581650D01*
X49625Y581733D01*
X49958Y581650D01*
X50167Y581400D01*
X50292Y581108D01*
Y580067D01*
G01Y581108D02*
X51500Y581733D01*
G01Y583917D02*
X50958Y584000D01*
X50500Y584125D01*
X50083Y584292D01*
X49625Y584500D01*
X49000Y584833D01*
Y583167D01*
G01X51500Y587600D02*
X49000D01*
X50792Y586058D01*
Y588142D01*
G01X51600Y578900D02*
X47600D01*
Y571500D01*
G01X46767Y564700D02*
Y567200D01*
X47808D01*
X48142Y567075D01*
X48350Y566908D01*
X48433Y566575D01*
X48350Y566242D01*
X48100Y566033D01*
X47808Y565908D01*
X46767D01*
G01X47808D02*
X48433Y564700D01*
G01X49908Y565742D02*
X50200Y566033D01*
X50450Y566200D01*
X50783Y566283D01*
X51075Y566200D01*
X51283Y566033D01*
X51450Y565783D01*
X51492Y565492D01*
X51450Y565242D01*
X51283Y564992D01*
X51033Y564783D01*
X50742Y564700D01*
X50408Y564783D01*
X50117Y565033D01*
X49950Y565408D01*
X49908Y565825D01*
X49992Y566367D01*
X50117Y566658D01*
X50325Y566950D01*
X50617Y567158D01*
X50908Y567200D01*
X51200Y567117D01*
X51408Y566908D01*
G01X53800Y564700D02*
X54092Y564742D01*
X54425Y564867D01*
X54633Y565075D01*
X54717Y565367D01*
X54633Y565658D01*
X54383Y565908D01*
X54008Y566033D01*
X53592D01*
X53342Y566117D01*
X53133Y566325D01*
X53050Y566617D01*
X53175Y566908D01*
X53467Y567117D01*
X53800Y567200D01*
X54133Y567117D01*
X54425Y566908D01*
X54550Y566617D01*
X54467Y566325D01*
X54258Y566117D01*
X54008Y566033D01*
X53592D01*
X53217Y565908D01*
X52967Y565658D01*
X52883Y565367D01*
X52967Y565075D01*
X53175Y564867D01*
X53508Y564742D01*
X53800Y564700D01*
G01X59000Y575200D02*
Y571200D01*
X66400D01*
G01X40000Y584567D02*
X37500D01*
Y585608D01*
X37625Y585942D01*
X37792Y586150D01*
X38125Y586233D01*
X38458Y586150D01*
X38667Y585900D01*
X38792Y585608D01*
Y584567D01*
G01Y585608D02*
X40000Y586233D01*
G01X38958Y587708D02*
X38667Y588000D01*
X38500Y588250D01*
X38417Y588583D01*
X38500Y588875D01*
X38667Y589083D01*
X38917Y589250D01*
X39208Y589292D01*
X39458Y589250D01*
X39708Y589083D01*
X39917Y588833D01*
X40000Y588542D01*
X39917Y588208D01*
X39667Y587917D01*
X39292Y587750D01*
X38875Y587708D01*
X38333Y587792D01*
X38042Y587917D01*
X37750Y588125D01*
X37542Y588417D01*
X37500Y588708D01*
X37583Y589000D01*
X37792Y589208D01*
G01X38958Y590808D02*
X38667Y591100D01*
X38500Y591350D01*
X38417Y591683D01*
X38500Y591975D01*
X38667Y592183D01*
X38917Y592350D01*
X39208Y592392D01*
X39458Y592350D01*
X39708Y592183D01*
X39917Y591933D01*
X40000Y591642D01*
X39917Y591308D01*
X39667Y591017D01*
X39292Y590850D01*
X38875Y590808D01*
X38333Y590892D01*
X38042Y591017D01*
X37750Y591225D01*
X37542Y591517D01*
X37500Y591808D01*
X37583Y592100D01*
X37792Y592308D01*
G01X37000Y575900D02*
X41000D01*
Y583300D01*
G01X47817Y559292D02*
X47567Y559417D01*
X47275Y559500D01*
X46942D01*
X46567Y559375D01*
X46275Y559167D01*
X46067Y558917D01*
X45900Y558500D01*
X45858Y558125D01*
X45942Y557750D01*
X46067Y557500D01*
X46317Y557250D01*
X46608Y557083D01*
X46900Y557000D01*
X47192D01*
X47483Y557083D01*
X47733Y557208D01*
X47942Y557375D01*
G01X49083Y557500D02*
X49333Y557208D01*
X49667Y557042D01*
X50042Y557000D01*
X50375Y557042D01*
X50708Y557250D01*
X50917Y557500D01*
X50958Y557750D01*
X50875Y558042D01*
X50583Y558250D01*
X50292Y558333D01*
X49917D01*
G01X50292D02*
X50542Y558458D01*
X50750Y558667D01*
X50833Y558917D01*
X50750Y559167D01*
X50542Y559375D01*
X50167Y559500D01*
X49792Y559458D01*
X49417Y559292D01*
G01X53100Y559500D02*
X52767Y559417D01*
X52517Y559208D01*
X52350Y558958D01*
X52225Y558625D01*
X52183Y558250D01*
X52225Y557875D01*
X52350Y557542D01*
X52517Y557292D01*
X52767Y557083D01*
X53100Y557000D01*
X53433Y557083D01*
X53683Y557292D01*
X53850Y557542D01*
X53975Y557875D01*
X54017Y558250D01*
X53975Y558625D01*
X53850Y558958D01*
X53683Y559208D01*
X53433Y559417D01*
X53100Y559500D01*
G01X54658Y633000D02*
Y635500D01*
X56242D01*
G01X55658Y634292D02*
X54658D01*
G01X57758Y635083D02*
X58008Y635333D01*
X58300Y635458D01*
X58633Y635500D01*
X59050Y635417D01*
X59342Y635208D01*
X59425Y634958D01*
X59383Y634708D01*
X59217Y634500D01*
X58383Y634083D01*
X58008Y633792D01*
X57758Y633375D01*
X57675Y633000D01*
X59425D01*
G01X61903Y639502D02*
X84903D01*
G01X51317Y653792D02*
X51067Y653917D01*
X50775Y654000D01*
X50442D01*
X50067Y653875D01*
X49775Y653667D01*
X49567Y653417D01*
X49400Y653000D01*
X49358Y652625D01*
X49442Y652250D01*
X49567Y652000D01*
X49817Y651750D01*
X50108Y651583D01*
X50400Y651500D01*
X50692D01*
X50983Y651583D01*
X51233Y651708D01*
X51442Y651875D01*
G01X52583Y652000D02*
X52833Y651708D01*
X53167Y651542D01*
X53542Y651500D01*
X53875Y651542D01*
X54208Y651750D01*
X54417Y652000D01*
X54458Y652250D01*
X54375Y652542D01*
X54083Y652750D01*
X53792Y652833D01*
X53417D01*
G01X53792D02*
X54042Y652958D01*
X54250Y653167D01*
X54333Y653417D01*
X54250Y653667D01*
X54042Y653875D01*
X53667Y654000D01*
X53292Y653958D01*
X52917Y653792D01*
G01X57100Y651500D02*
Y654000D01*
X55558Y652208D01*
X57642D01*
G01X51317Y649792D02*
X51067Y649917D01*
X50775Y650000D01*
X50442D01*
X50067Y649875D01*
X49775Y649667D01*
X49567Y649417D01*
X49400Y649000D01*
X49358Y648625D01*
X49442Y648250D01*
X49567Y648000D01*
X49817Y647750D01*
X50108Y647583D01*
X50400Y647500D01*
X50692D01*
X50983Y647583D01*
X51233Y647708D01*
X51442Y647875D01*
G01X52583Y648000D02*
X52833Y647708D01*
X53167Y647542D01*
X53542Y647500D01*
X53875Y647542D01*
X54208Y647750D01*
X54417Y648000D01*
X54458Y648250D01*
X54375Y648542D01*
X54083Y648750D01*
X53792Y648833D01*
X53417D01*
G01X53792D02*
X54042Y648958D01*
X54250Y649167D01*
X54333Y649417D01*
X54250Y649667D01*
X54042Y649875D01*
X53667Y650000D01*
X53292Y649958D01*
X52917Y649792D01*
G01X55683Y648000D02*
X55933Y647708D01*
X56267Y647542D01*
X56642Y647500D01*
X56975Y647542D01*
X57308Y647750D01*
X57517Y648000D01*
X57558Y648250D01*
X57475Y648542D01*
X57183Y648750D01*
X56892Y648833D01*
X56517D01*
G01X56892D02*
X57142Y648958D01*
X57350Y649167D01*
X57433Y649417D01*
X57350Y649667D01*
X57142Y649875D01*
X56767Y650000D01*
X56392Y649958D01*
X56017Y649792D01*
G01X83517Y651500D02*
Y654000D01*
X84558D01*
X84892Y653875D01*
X85100Y653708D01*
X85183Y653375D01*
X85100Y653042D01*
X84850Y652833D01*
X84558Y652708D01*
X83517D01*
G01X84558D02*
X85183Y651500D01*
G01X87450D02*
Y654000D01*
X86950Y653500D01*
G01Y651500D02*
X87950D01*
G01X89758Y652542D02*
X90050Y652833D01*
X90300Y653000D01*
X90633Y653083D01*
X90925Y653000D01*
X91133Y652833D01*
X91300Y652583D01*
X91342Y652292D01*
X91300Y652042D01*
X91133Y651792D01*
X90883Y651583D01*
X90592Y651500D01*
X90258Y651583D01*
X89967Y651833D01*
X89800Y652208D01*
X89758Y652625D01*
X89842Y653167D01*
X89967Y653458D01*
X90175Y653750D01*
X90467Y653958D01*
X90758Y654000D01*
X91050Y653917D01*
X91258Y653708D01*
G01X92733Y651875D02*
X92983Y651667D01*
X93275Y651542D01*
X93650Y651500D01*
X94025Y651583D01*
X94317Y651750D01*
X94525Y652042D01*
X94567Y652375D01*
X94483Y652708D01*
X94275Y652917D01*
X93983Y653083D01*
X93692Y653125D01*
X93400Y653083D01*
X93025Y652917D01*
X93150Y654000D01*
X94275D01*
G01X66017Y650500D02*
Y653000D01*
X67058D01*
X67392Y652875D01*
X67600Y652708D01*
X67683Y652375D01*
X67600Y652042D01*
X67350Y651833D01*
X67058Y651708D01*
X66017D01*
G01X67058D02*
X67683Y650500D01*
G01X69950D02*
Y653000D01*
X69450Y652500D01*
G01Y650500D02*
X70450D01*
G01X72258Y651542D02*
X72550Y651833D01*
X72800Y652000D01*
X73133Y652083D01*
X73425Y652000D01*
X73633Y651833D01*
X73800Y651583D01*
X73842Y651292D01*
X73800Y651042D01*
X73633Y650792D01*
X73383Y650583D01*
X73092Y650500D01*
X72758Y650583D01*
X72467Y650833D01*
X72300Y651208D01*
X72258Y651625D01*
X72342Y652167D01*
X72467Y652458D01*
X72675Y652750D01*
X72967Y652958D01*
X73258Y653000D01*
X73550Y652917D01*
X73758Y652708D01*
G01X76650Y650500D02*
Y653000D01*
X75108Y651208D01*
X77192D01*
G01X64000Y643017D02*
X61500D01*
Y644058D01*
X61625Y644392D01*
X61792Y644600D01*
X62125Y644683D01*
X62458Y644600D01*
X62667Y644350D01*
X62792Y644058D01*
Y643017D01*
G01Y644058D02*
X64000Y644683D01*
G01Y646950D02*
X61500D01*
X62000Y646450D01*
G01X64000D02*
Y647450D01*
G01X62958Y649258D02*
X62667Y649550D01*
X62500Y649800D01*
X62417Y650133D01*
X62500Y650425D01*
X62667Y650633D01*
X62917Y650800D01*
X63208Y650842D01*
X63458Y650800D01*
X63708Y650633D01*
X63917Y650383D01*
X64000Y650092D01*
X63917Y649758D01*
X63667Y649467D01*
X63292Y649300D01*
X62875Y649258D01*
X62333Y649342D01*
X62042Y649467D01*
X61750Y649675D01*
X61542Y649967D01*
X61500Y650258D01*
X61583Y650550D01*
X61792Y650758D01*
G01X63500Y652233D02*
X63792Y652483D01*
X63958Y652817D01*
X64000Y653192D01*
X63958Y653525D01*
X63750Y653858D01*
X63500Y654067D01*
X63250Y654108D01*
X62958Y654025D01*
X62750Y653733D01*
X62667Y653442D01*
Y653067D01*
G01Y653442D02*
X62542Y653692D01*
X62333Y653900D01*
X62083Y653983D01*
X61833Y653900D01*
X61625Y653692D01*
X61500Y653317D01*
X61542Y652942D01*
X61708Y652567D01*
G01X81500Y642517D02*
X79000D01*
Y643558D01*
X79125Y643892D01*
X79292Y644100D01*
X79625Y644183D01*
X79958Y644100D01*
X80167Y643850D01*
X80292Y643558D01*
Y642517D01*
G01Y643558D02*
X81500Y644183D01*
G01Y646450D02*
X79000D01*
X79500Y645950D01*
G01X81500D02*
Y646950D01*
G01X80458Y648758D02*
X80167Y649050D01*
X80000Y649300D01*
X79917Y649633D01*
X80000Y649925D01*
X80167Y650133D01*
X80417Y650300D01*
X80708Y650342D01*
X80958Y650300D01*
X81208Y650133D01*
X81417Y649883D01*
X81500Y649592D01*
X81417Y649258D01*
X81167Y648967D01*
X80792Y648800D01*
X80375Y648758D01*
X79833Y648842D01*
X79542Y648967D01*
X79250Y649175D01*
X79042Y649467D01*
X79000Y649758D01*
X79083Y650050D01*
X79292Y650258D01*
G01X79417Y651858D02*
X79167Y652108D01*
X79042Y652400D01*
X79000Y652733D01*
X79083Y653150D01*
X79292Y653442D01*
X79542Y653525D01*
X79792Y653483D01*
X80000Y653317D01*
X80417Y652483D01*
X80708Y652108D01*
X81125Y651858D01*
X81500Y651775D01*
Y653525D01*
G01X49500Y613517D02*
X47000D01*
Y614558D01*
X47125Y614892D01*
X47292Y615100D01*
X47625Y615183D01*
X47958Y615100D01*
X48167Y614850D01*
X48292Y614558D01*
Y613517D01*
G01Y614558D02*
X49500Y615183D01*
G01Y617450D02*
X47000D01*
X47500Y616950D01*
G01X49500D02*
Y617950D01*
G01Y620550D02*
X49458Y620842D01*
X49333Y621175D01*
X49125Y621383D01*
X48833Y621467D01*
X48542Y621383D01*
X48292Y621133D01*
X48167Y620758D01*
Y620342D01*
X48083Y620092D01*
X47875Y619883D01*
X47583Y619800D01*
X47292Y619925D01*
X47083Y620217D01*
X47000Y620550D01*
X47083Y620883D01*
X47292Y621175D01*
X47583Y621300D01*
X47875Y621217D01*
X48083Y621008D01*
X48167Y620758D01*
Y620342D01*
X48292Y619967D01*
X48542Y619717D01*
X48833Y619633D01*
X49125Y619717D01*
X49333Y619925D01*
X49458Y620258D01*
X49500Y620550D01*
G01Y623650D02*
X47000D01*
X47500Y623150D01*
G01X49500D02*
Y624150D01*
G01X60000Y610700D02*
Y628300D01*
G01X52000Y610700D02*
X60000D01*
G01X52000Y628300D02*
Y610700D01*
G01X60000Y628300D02*
X52000D01*
G01X50700Y676000D02*
X39500D01*
G01X50700Y658000D02*
Y676000D01*
G01X39500Y658000D02*
X50700D01*
G01X63000Y702567D02*
X60500D01*
Y703608D01*
X60625Y703942D01*
X60792Y704150D01*
X61125Y704233D01*
X61458Y704150D01*
X61667Y703900D01*
X61792Y703608D01*
Y702567D01*
G01Y703608D02*
X63000Y704233D01*
G01Y706500D02*
X62958Y706792D01*
X62833Y707125D01*
X62625Y707333D01*
X62333Y707417D01*
X62042Y707333D01*
X61792Y707083D01*
X61667Y706708D01*
Y706292D01*
X61583Y706042D01*
X61375Y705833D01*
X61083Y705750D01*
X60792Y705875D01*
X60583Y706167D01*
X60500Y706500D01*
X60583Y706833D01*
X60792Y707125D01*
X61083Y707250D01*
X61375Y707167D01*
X61583Y706958D01*
X61667Y706708D01*
Y706292D01*
X61792Y705917D01*
X62042Y705667D01*
X62333Y705583D01*
X62625Y705667D01*
X62833Y705875D01*
X62958Y706208D01*
X63000Y706500D01*
G01Y709517D02*
X62458Y709600D01*
X62000Y709725D01*
X61583Y709892D01*
X61125Y710100D01*
X60500Y710433D01*
Y708767D01*
G01X72500Y663533D02*
X74292D01*
X74667Y663700D01*
X74917Y664033D01*
X75000Y664450D01*
X74917Y664867D01*
X74667Y665200D01*
X74292Y665367D01*
X72500D01*
G01X74500Y666633D02*
X74792Y666883D01*
X74958Y667217D01*
X75000Y667592D01*
X74958Y667925D01*
X74750Y668258D01*
X74500Y668467D01*
X74250Y668508D01*
X73958Y668425D01*
X73750Y668133D01*
X73667Y667842D01*
Y667467D01*
G01Y667842D02*
X73542Y668092D01*
X73333Y668300D01*
X73083Y668383D01*
X72833Y668300D01*
X72625Y668092D01*
X72500Y667717D01*
X72542Y667342D01*
X72708Y666967D01*
G01X74435Y684556D02*
Y671156D01*
G01X64435Y684556D02*
X74435D01*
G01X64435Y671156D02*
Y684556D01*
G01X74435Y671156D02*
X64435D01*
G01X48983Y698500D02*
Y696708D01*
X49150Y696333D01*
X49483Y696083D01*
X49900Y696000D01*
X50317Y696083D01*
X50650Y696333D01*
X50817Y696708D01*
Y698500D01*
G01X53000Y696000D02*
Y698500D01*
X52500Y698000D01*
G01Y696000D02*
X53500D01*
G01X56100D02*
Y698500D01*
X55600Y698000D01*
G01Y696000D02*
X56600D01*
G01X61700Y683000D02*
X48300D01*
G01X61700Y693000D02*
Y683000D01*
G01X48300Y693000D02*
X61700D01*
G01X48300Y683000D02*
Y693000D01*
G01X46200D02*
Y683000D01*
G01X59867Y699792D02*
X59617Y699917D01*
X59325Y700000D01*
X58992D01*
X58617Y699875D01*
X58325Y699667D01*
X58117Y699417D01*
X57950Y699000D01*
X57908Y698625D01*
X57992Y698250D01*
X58117Y698000D01*
X58367Y697750D01*
X58658Y697583D01*
X58950Y697500D01*
X59242D01*
X59533Y697583D01*
X59783Y697708D01*
X59992Y697875D01*
G01X61342Y697792D02*
X61633Y697583D01*
X61967Y697500D01*
X62300Y697583D01*
X62592Y697833D01*
X62800Y698208D01*
X62883Y698583D01*
Y699042D01*
X62800Y699417D01*
X62592Y699750D01*
X62342Y699917D01*
X62050Y700000D01*
X61717Y699917D01*
X61467Y699750D01*
X61300Y699500D01*
X61217Y699167D01*
X61300Y698875D01*
X61508Y698583D01*
X61758Y698417D01*
X62050Y698375D01*
X62383Y698458D01*
X62633Y698667D01*
X62883Y699042D01*
G01X67317Y699792D02*
X67067Y699917D01*
X66775Y700000D01*
X66442D01*
X66067Y699875D01*
X65775Y699667D01*
X65567Y699417D01*
X65400Y699000D01*
X65358Y698625D01*
X65442Y698250D01*
X65567Y698000D01*
X65817Y697750D01*
X66108Y697583D01*
X66400Y697500D01*
X66692D01*
X66983Y697583D01*
X67233Y697708D01*
X67442Y697875D01*
G01X69500Y697500D02*
Y700000D01*
X69000Y699500D01*
G01Y697500D02*
X70000D01*
G01X72600Y700000D02*
X72267Y699917D01*
X72017Y699708D01*
X71850Y699458D01*
X71725Y699125D01*
X71683Y698750D01*
X71725Y698375D01*
X71850Y698042D01*
X72017Y697792D01*
X72267Y697583D01*
X72600Y697500D01*
X72933Y697583D01*
X73183Y697792D01*
X73350Y698042D01*
X73475Y698375D01*
X73517Y698750D01*
X73475Y699125D01*
X73350Y699458D01*
X73183Y699708D01*
X72933Y699917D01*
X72600Y700000D01*
G01X51708Y705817D02*
X51583Y705567D01*
X51500Y705275D01*
Y704942D01*
X51625Y704567D01*
X51833Y704275D01*
X52083Y704067D01*
X52500Y703900D01*
X52875Y703858D01*
X53250Y703942D01*
X53500Y704067D01*
X53750Y704317D01*
X53917Y704608D01*
X54000Y704900D01*
Y705192D01*
X53917Y705483D01*
X53792Y705733D01*
X53625Y705942D01*
G01Y707083D02*
X53833Y707333D01*
X53958Y707625D01*
X54000Y708000D01*
X53917Y708375D01*
X53750Y708667D01*
X53458Y708875D01*
X53125Y708917D01*
X52792Y708833D01*
X52583Y708625D01*
X52417Y708333D01*
X52375Y708042D01*
X52417Y707750D01*
X52583Y707375D01*
X51500Y707500D01*
Y708625D01*
G01X53625Y710183D02*
X53833Y710433D01*
X53958Y710725D01*
X54000Y711100D01*
X53917Y711475D01*
X53750Y711767D01*
X53458Y711975D01*
X53125Y712017D01*
X52792Y711933D01*
X52583Y711725D01*
X52417Y711433D01*
X52375Y711142D01*
X52417Y710850D01*
X52583Y710475D01*
X51500Y710600D01*
Y711725D01*
G01X47408Y705817D02*
X47283Y705567D01*
X47200Y705275D01*
Y704942D01*
X47325Y704567D01*
X47533Y704275D01*
X47783Y704067D01*
X48200Y703900D01*
X48575Y703858D01*
X48950Y703942D01*
X49200Y704067D01*
X49450Y704317D01*
X49617Y704608D01*
X49700Y704900D01*
Y705192D01*
X49617Y705483D01*
X49492Y705733D01*
X49325Y705942D01*
G01Y707083D02*
X49533Y707333D01*
X49658Y707625D01*
X49700Y708000D01*
X49617Y708375D01*
X49450Y708667D01*
X49158Y708875D01*
X48825Y708917D01*
X48492Y708833D01*
X48283Y708625D01*
X48117Y708333D01*
X48075Y708042D01*
X48117Y707750D01*
X48283Y707375D01*
X47200Y707500D01*
Y708625D01*
G01X49700Y711600D02*
X47200D01*
X48992Y710058D01*
Y712142D01*
G01X77067Y676500D02*
Y679000D01*
X78108D01*
X78442Y678875D01*
X78650Y678708D01*
X78733Y678375D01*
X78650Y678042D01*
X78400Y677833D01*
X78108Y677708D01*
X77067D01*
G01X78108D02*
X78733Y676500D01*
G01X80208Y678583D02*
X80458Y678833D01*
X80750Y678958D01*
X81083Y679000D01*
X81500Y678917D01*
X81792Y678708D01*
X81875Y678458D01*
X81833Y678208D01*
X81667Y678000D01*
X80833Y677583D01*
X80458Y677292D01*
X80208Y676875D01*
X80125Y676500D01*
X81875D01*
G01X84600D02*
Y679000D01*
X83058Y677208D01*
X85142D01*
G01X83944Y692635D02*
Y696635D01*
X76544D01*
G01X77067Y672500D02*
Y675000D01*
X78108D01*
X78442Y674875D01*
X78650Y674708D01*
X78733Y674375D01*
X78650Y674042D01*
X78400Y673833D01*
X78108Y673708D01*
X77067D01*
G01X78108D02*
X78733Y672500D01*
G01X80208Y674583D02*
X80458Y674833D01*
X80750Y674958D01*
X81083Y675000D01*
X81500Y674917D01*
X81792Y674708D01*
X81875Y674458D01*
X81833Y674208D01*
X81667Y674000D01*
X80833Y673583D01*
X80458Y673292D01*
X80208Y672875D01*
X80125Y672500D01*
X81875D01*
G01X83183Y673000D02*
X83433Y672708D01*
X83767Y672542D01*
X84142Y672500D01*
X84475Y672542D01*
X84808Y672750D01*
X85017Y673000D01*
X85058Y673250D01*
X84975Y673542D01*
X84683Y673750D01*
X84392Y673833D01*
X84017D01*
G01X84392D02*
X84642Y673958D01*
X84850Y674167D01*
X84933Y674417D01*
X84850Y674667D01*
X84642Y674875D01*
X84267Y675000D01*
X83892Y674958D01*
X83517Y674792D01*
G01X76556Y692465D02*
Y688465D01*
X83956D01*
G01X77067Y669000D02*
Y671500D01*
X78108D01*
X78442Y671375D01*
X78650Y671208D01*
X78733Y670875D01*
X78650Y670542D01*
X78400Y670333D01*
X78108Y670208D01*
X77067D01*
G01X78108D02*
X78733Y669000D01*
G01X80208Y671083D02*
X80458Y671333D01*
X80750Y671458D01*
X81083Y671500D01*
X81500Y671417D01*
X81792Y671208D01*
X81875Y670958D01*
X81833Y670708D01*
X81667Y670500D01*
X80833Y670083D01*
X80458Y669792D01*
X80208Y669375D01*
X80125Y669000D01*
X81875D01*
G01X83308Y671083D02*
X83558Y671333D01*
X83850Y671458D01*
X84183Y671500D01*
X84600Y671417D01*
X84892Y671208D01*
X84975Y670958D01*
X84933Y670708D01*
X84767Y670500D01*
X83933Y670083D01*
X83558Y669792D01*
X83308Y669375D01*
X83225Y669000D01*
X84975D01*
G01X78700Y688400D02*
Y684400D01*
X86100D01*
G01X80067Y661500D02*
Y664000D01*
X81108D01*
X81442Y663875D01*
X81650Y663708D01*
X81733Y663375D01*
X81650Y663042D01*
X81400Y662833D01*
X81108Y662708D01*
X80067D01*
G01X81108D02*
X81733Y661500D01*
G01X83208Y663583D02*
X83458Y663833D01*
X83750Y663958D01*
X84083Y664000D01*
X84500Y663917D01*
X84792Y663708D01*
X84875Y663458D01*
X84833Y663208D01*
X84667Y663000D01*
X83833Y662583D01*
X83458Y662292D01*
X83208Y661875D01*
X83125Y661500D01*
X84875D01*
G01X87100D02*
Y664000D01*
X86600Y663500D01*
G01Y661500D02*
X87600D01*
G01X80067Y658000D02*
Y660500D01*
X81108D01*
X81442Y660375D01*
X81650Y660208D01*
X81733Y659875D01*
X81650Y659542D01*
X81400Y659333D01*
X81108Y659208D01*
X80067D01*
G01X81108D02*
X81733Y658000D01*
G01X83208Y660083D02*
X83458Y660333D01*
X83750Y660458D01*
X84083Y660500D01*
X84500Y660417D01*
X84792Y660208D01*
X84875Y659958D01*
X84833Y659708D01*
X84667Y659500D01*
X83833Y659083D01*
X83458Y658792D01*
X83208Y658375D01*
X83125Y658000D01*
X84875D01*
G01X87100Y660500D02*
X86767Y660417D01*
X86517Y660208D01*
X86350Y659958D01*
X86225Y659625D01*
X86183Y659250D01*
X86225Y658875D01*
X86350Y658542D01*
X86517Y658292D01*
X86767Y658083D01*
X87100Y658000D01*
X87433Y658083D01*
X87683Y658292D01*
X87850Y658542D01*
X87975Y658875D01*
X88017Y659250D01*
X87975Y659625D01*
X87850Y659958D01*
X87683Y660208D01*
X87433Y660417D01*
X87100Y660500D01*
G01X58500Y702567D02*
X56000D01*
Y703608D01*
X56125Y703942D01*
X56292Y704150D01*
X56625Y704233D01*
X56958Y704150D01*
X57167Y703900D01*
X57292Y703608D01*
Y702567D01*
G01Y703608D02*
X58500Y704233D01*
G01X58208Y705792D02*
X58417Y706083D01*
X58500Y706417D01*
X58417Y706750D01*
X58167Y707042D01*
X57792Y707250D01*
X57417Y707333D01*
X56958D01*
X56583Y707250D01*
X56250Y707042D01*
X56083Y706792D01*
X56000Y706500D01*
X56083Y706167D01*
X56250Y705917D01*
X56500Y705750D01*
X56833Y705667D01*
X57125Y705750D01*
X57417Y705958D01*
X57583Y706208D01*
X57625Y706500D01*
X57542Y706833D01*
X57333Y707083D01*
X56958Y707333D01*
G01X58500Y709600D02*
X56000D01*
X56500Y709100D01*
G01X58500D02*
Y710100D01*
G01X75200Y700500D02*
X79200D01*
Y707900D01*
G01X61567Y666000D02*
Y668500D01*
X62608D01*
X62942Y668375D01*
X63150Y668208D01*
X63233Y667875D01*
X63150Y667542D01*
X62900Y667333D01*
X62608Y667208D01*
X61567D01*
G01X62608D02*
X63233Y666000D01*
G01X64583Y666375D02*
X64833Y666167D01*
X65125Y666042D01*
X65500Y666000D01*
X65875Y666083D01*
X66167Y666250D01*
X66375Y666542D01*
X66417Y666875D01*
X66333Y667208D01*
X66125Y667417D01*
X65833Y667583D01*
X65542Y667625D01*
X65250Y667583D01*
X64875Y667417D01*
X65000Y668500D01*
X66125D01*
G01X67808Y668083D02*
X68058Y668333D01*
X68350Y668458D01*
X68683Y668500D01*
X69100Y668417D01*
X69392Y668208D01*
X69475Y667958D01*
X69433Y667708D01*
X69267Y667500D01*
X68433Y667083D01*
X68058Y666792D01*
X67808Y666375D01*
X67725Y666000D01*
X69475D01*
G01X63400Y678800D02*
X59400D01*
Y671400D01*
G01X54500Y670567D02*
X52000D01*
Y671608D01*
X52125Y671942D01*
X52292Y672150D01*
X52625Y672233D01*
X52958Y672150D01*
X53167Y671900D01*
X53292Y671608D01*
Y670567D01*
G01Y671608D02*
X54500Y672233D01*
G01Y675000D02*
X52000D01*
X53792Y673458D01*
Y675542D01*
G01X54208Y676892D02*
X54417Y677183D01*
X54500Y677517D01*
X54417Y677850D01*
X54167Y678142D01*
X53792Y678350D01*
X53417Y678433D01*
X52958D01*
X52583Y678350D01*
X52250Y678142D01*
X52083Y677892D01*
X52000Y677600D01*
X52083Y677267D01*
X52250Y677017D01*
X52500Y676850D01*
X52833Y676767D01*
X53125Y676850D01*
X53417Y677058D01*
X53583Y677308D01*
X53625Y677600D01*
X53542Y677933D01*
X53333Y678183D01*
X52958Y678433D01*
G01X59400Y678800D02*
X55400D01*
Y671400D01*
G01X77017Y665500D02*
Y668000D01*
X78058D01*
X78392Y667875D01*
X78600Y667708D01*
X78683Y667375D01*
X78600Y667042D01*
X78350Y666833D01*
X78058Y666708D01*
X77017D01*
G01X78058D02*
X78683Y665500D01*
G01X80950D02*
Y668000D01*
X80450Y667500D01*
G01Y665500D02*
X81450D01*
G01X84050D02*
X84342Y665542D01*
X84675Y665667D01*
X84883Y665875D01*
X84967Y666167D01*
X84883Y666458D01*
X84633Y666708D01*
X84258Y666833D01*
X83842D01*
X83592Y666917D01*
X83383Y667125D01*
X83300Y667417D01*
X83425Y667708D01*
X83717Y667917D01*
X84050Y668000D01*
X84383Y667917D01*
X84675Y667708D01*
X84800Y667417D01*
X84717Y667125D01*
X84508Y666917D01*
X84258Y666833D01*
X83842D01*
X83467Y666708D01*
X83217Y666458D01*
X83133Y666167D01*
X83217Y665875D01*
X83425Y665667D01*
X83758Y665542D01*
X84050Y665500D01*
G01X86233Y666000D02*
X86483Y665708D01*
X86817Y665542D01*
X87192Y665500D01*
X87525Y665542D01*
X87858Y665750D01*
X88067Y666000D01*
X88108Y666250D01*
X88025Y666542D01*
X87733Y666750D01*
X87442Y666833D01*
X87067D01*
G01X87442D02*
X87692Y666958D01*
X87900Y667167D01*
X87983Y667417D01*
X87900Y667667D01*
X87692Y667875D01*
X87317Y668000D01*
X86942Y667958D01*
X86567Y667792D01*
G01X85400Y680200D02*
Y684200D01*
X78000D01*
G01X63500Y750658D02*
X61000D01*
Y752242D01*
G01X62208Y751658D02*
Y750658D01*
G01X63000Y753633D02*
X63292Y753883D01*
X63458Y754217D01*
X63500Y754592D01*
X63458Y754925D01*
X63250Y755258D01*
X63000Y755467D01*
X62750Y755508D01*
X62458Y755425D01*
X62250Y755133D01*
X62167Y754842D01*
Y754467D01*
G01Y754842D02*
X62042Y755092D01*
X61833Y755300D01*
X61583Y755383D01*
X61333Y755300D01*
X61125Y755092D01*
X61000Y754717D01*
X61042Y754342D01*
X61208Y753967D01*
G01X66602Y746397D02*
Y769397D01*
G01X105402Y746397D02*
X66602D01*
G01X99000Y719400D02*
X78000D01*
G01D02*
Y711400D01*
G01D02*
X99000D01*
G01X98500Y744400D02*
X77500D01*
G01D02*
Y736400D01*
G01D02*
X98500D01*
G01X87000Y722067D02*
X84500D01*
Y723108D01*
X84625Y723442D01*
X84792Y723650D01*
X85125Y723733D01*
X85458Y723650D01*
X85667Y723400D01*
X85792Y723108D01*
Y722067D01*
G01Y723108D02*
X87000Y723733D01*
G01Y726000D02*
X86958Y726292D01*
X86833Y726625D01*
X86625Y726833D01*
X86333Y726917D01*
X86042Y726833D01*
X85792Y726583D01*
X85667Y726208D01*
Y725792D01*
X85583Y725542D01*
X85375Y725333D01*
X85083Y725250D01*
X84792Y725375D01*
X84583Y725667D01*
X84500Y726000D01*
X84583Y726333D01*
X84792Y726625D01*
X85083Y726750D01*
X85375Y726667D01*
X85583Y726458D01*
X85667Y726208D01*
Y725792D01*
X85792Y725417D01*
X86042Y725167D01*
X86333Y725083D01*
X86625Y725167D01*
X86833Y725375D01*
X86958Y725708D01*
X87000Y726000D01*
G01X86708Y728392D02*
X86917Y728683D01*
X87000Y729017D01*
X86917Y729350D01*
X86667Y729642D01*
X86292Y729850D01*
X85917Y729933D01*
X85458D01*
X85083Y729850D01*
X84750Y729642D01*
X84583Y729392D01*
X84500Y729100D01*
X84583Y728767D01*
X84750Y728517D01*
X85000Y728350D01*
X85333Y728267D01*
X85625Y728350D01*
X85917Y728558D01*
X86083Y728808D01*
X86125Y729100D01*
X86042Y729433D01*
X85833Y729683D01*
X85458Y729933D01*
G01X75000Y725400D02*
X79000D01*
Y732800D01*
G01X91700Y731400D02*
Y735400D01*
X84300D01*
G01X53167Y728800D02*
Y731300D01*
X54208D01*
X54542Y731175D01*
X54750Y731008D01*
X54833Y730675D01*
X54750Y730342D01*
X54500Y730133D01*
X54208Y730008D01*
X53167D01*
G01X54208D02*
X54833Y728800D01*
G01X57017D02*
X57100Y729342D01*
X57225Y729800D01*
X57392Y730217D01*
X57600Y730675D01*
X57933Y731300D01*
X56267D01*
G01X59492Y729092D02*
X59783Y728883D01*
X60117Y728800D01*
X60450Y728883D01*
X60742Y729133D01*
X60950Y729508D01*
X61033Y729883D01*
Y730342D01*
X60950Y730717D01*
X60742Y731050D01*
X60492Y731217D01*
X60200Y731300D01*
X59867Y731217D01*
X59617Y731050D01*
X59450Y730800D01*
X59367Y730467D01*
X59450Y730175D01*
X59658Y729883D01*
X59908Y729717D01*
X60200Y729675D01*
X60533Y729758D01*
X60783Y729967D01*
X61033Y730342D01*
G01X70700Y728000D02*
Y732000D01*
X63300D01*
G01X70208Y737317D02*
X70083Y737067D01*
X70000Y736775D01*
Y736442D01*
X70125Y736067D01*
X70333Y735775D01*
X70583Y735567D01*
X71000Y735400D01*
X71375Y735358D01*
X71750Y735442D01*
X72000Y735567D01*
X72250Y735817D01*
X72417Y736108D01*
X72500Y736400D01*
Y736692D01*
X72417Y736983D01*
X72292Y737233D01*
X72125Y737442D01*
G01X72000Y738583D02*
X72292Y738833D01*
X72458Y739167D01*
X72500Y739542D01*
X72458Y739875D01*
X72250Y740208D01*
X72000Y740417D01*
X71750Y740458D01*
X71458Y740375D01*
X71250Y740083D01*
X71167Y739792D01*
Y739417D01*
G01Y739792D02*
X71042Y740042D01*
X70833Y740250D01*
X70583Y740333D01*
X70333Y740250D01*
X70125Y740042D01*
X70000Y739667D01*
X70042Y739292D01*
X70208Y738917D01*
G01X72500Y742517D02*
X71958Y742600D01*
X71500Y742725D01*
X71083Y742892D01*
X70625Y743100D01*
X70000Y743433D01*
Y741767D01*
G01X74317Y724292D02*
X74067Y724417D01*
X73775Y724500D01*
X73442D01*
X73067Y724375D01*
X72775Y724167D01*
X72567Y723917D01*
X72400Y723500D01*
X72358Y723125D01*
X72442Y722750D01*
X72567Y722500D01*
X72817Y722250D01*
X73108Y722083D01*
X73400Y722000D01*
X73692D01*
X73983Y722083D01*
X74233Y722208D01*
X74442Y722375D01*
G01X75583Y722500D02*
X75833Y722208D01*
X76167Y722042D01*
X76542Y722000D01*
X76875Y722042D01*
X77208Y722250D01*
X77417Y722500D01*
X77458Y722750D01*
X77375Y723042D01*
X77083Y723250D01*
X76792Y723333D01*
X76417D01*
G01X76792D02*
X77042Y723458D01*
X77250Y723667D01*
X77333Y723917D01*
X77250Y724167D01*
X77042Y724375D01*
X76667Y724500D01*
X76292Y724458D01*
X75917Y724292D01*
G01X78808Y723042D02*
X79100Y723333D01*
X79350Y723500D01*
X79683Y723583D01*
X79975Y723500D01*
X80183Y723333D01*
X80350Y723083D01*
X80392Y722792D01*
X80350Y722542D01*
X80183Y722292D01*
X79933Y722083D01*
X79642Y722000D01*
X79308Y722083D01*
X79017Y722333D01*
X78850Y722708D01*
X78808Y723125D01*
X78892Y723667D01*
X79017Y723958D01*
X79225Y724250D01*
X79517Y724458D01*
X79808Y724500D01*
X80100Y724417D01*
X80308Y724208D01*
G01X66602Y769397D02*
X105402D01*
G01X61500Y793350D02*
X64000D01*
G01X61500Y792392D02*
Y794308D01*
G01X61708Y797367D02*
X61583Y797117D01*
X61500Y796825D01*
Y796492D01*
X61625Y796117D01*
X61833Y795825D01*
X62083Y795617D01*
X62500Y795450D01*
X62875Y795408D01*
X63250Y795492D01*
X63500Y795617D01*
X63750Y795867D01*
X63917Y796158D01*
X64000Y796450D01*
Y796742D01*
X63917Y797033D01*
X63792Y797283D01*
X63625Y797492D01*
G01X64000Y799550D02*
X61500D01*
X62000Y799050D01*
G01X64000D02*
Y800050D01*
G01X63625Y801733D02*
X63833Y801983D01*
X63958Y802275D01*
X64000Y802650D01*
X63917Y803025D01*
X63750Y803317D01*
X63458Y803525D01*
X63125Y803567D01*
X62792Y803483D01*
X62583Y803275D01*
X62417Y802983D01*
X62375Y802692D01*
X62417Y802400D01*
X62583Y802025D01*
X61500Y802150D01*
Y803275D01*
G01X66800Y807400D02*
X78000D01*
G01X66800Y789400D02*
Y807400D01*
G01X78000Y789400D02*
X66800D01*
G01X77400Y772700D02*
X95000D01*
G01X77400Y780700D02*
Y772700D01*
G01X95000Y780700D02*
X77400D01*
G01X69017Y847000D02*
Y849500D01*
X70058D01*
X70392Y849375D01*
X70600Y849208D01*
X70683Y848875D01*
X70600Y848542D01*
X70350Y848333D01*
X70058Y848208D01*
X69017D01*
G01X70058D02*
X70683Y847000D01*
G01X72950D02*
Y849500D01*
X72450Y849000D01*
G01Y847000D02*
X73450D01*
G01X75133Y847500D02*
X75383Y847208D01*
X75717Y847042D01*
X76092Y847000D01*
X76425Y847042D01*
X76758Y847250D01*
X76967Y847500D01*
X77008Y847750D01*
X76925Y848042D01*
X76633Y848250D01*
X76342Y848333D01*
X75967D01*
G01X76342D02*
X76592Y848458D01*
X76800Y848667D01*
X76883Y848917D01*
X76800Y849167D01*
X76592Y849375D01*
X76217Y849500D01*
X75842Y849458D01*
X75467Y849292D01*
G01X79150Y847000D02*
Y849500D01*
X78650Y849000D01*
G01Y847000D02*
X79650D01*
G01X81996Y850500D02*
Y846500D01*
X89396D01*
G01X69017Y843000D02*
Y845500D01*
X70058D01*
X70392Y845375D01*
X70600Y845208D01*
X70683Y844875D01*
X70600Y844542D01*
X70350Y844333D01*
X70058Y844208D01*
X69017D01*
G01X70058D02*
X70683Y843000D01*
G01X72950D02*
Y845500D01*
X72450Y845000D01*
G01Y843000D02*
X73450D01*
G01X75133Y843500D02*
X75383Y843208D01*
X75717Y843042D01*
X76092Y843000D01*
X76425Y843042D01*
X76758Y843250D01*
X76967Y843500D01*
X77008Y843750D01*
X76925Y844042D01*
X76633Y844250D01*
X76342Y844333D01*
X75967D01*
G01X76342D02*
X76592Y844458D01*
X76800Y844667D01*
X76883Y844917D01*
X76800Y845167D01*
X76592Y845375D01*
X76217Y845500D01*
X75842Y845458D01*
X75467Y845292D01*
G01X79150Y845500D02*
X78817Y845417D01*
X78567Y845208D01*
X78400Y844958D01*
X78275Y844625D01*
X78233Y844250D01*
X78275Y843875D01*
X78400Y843542D01*
X78567Y843292D01*
X78817Y843083D01*
X79150Y843000D01*
X79483Y843083D01*
X79733Y843292D01*
X79900Y843542D01*
X80025Y843875D01*
X80067Y844250D01*
X80025Y844625D01*
X79900Y844958D01*
X79733Y845208D01*
X79483Y845417D01*
X79150Y845500D01*
G01X81996Y846100D02*
Y842100D01*
X89396D01*
G01X69017Y851000D02*
Y853500D01*
X70058D01*
X70392Y853375D01*
X70600Y853208D01*
X70683Y852875D01*
X70600Y852542D01*
X70350Y852333D01*
X70058Y852208D01*
X69017D01*
G01X70058D02*
X70683Y851000D01*
G01X72950D02*
Y853500D01*
X72450Y853000D01*
G01Y851000D02*
X73450D01*
G01X75133Y851500D02*
X75383Y851208D01*
X75717Y851042D01*
X76092Y851000D01*
X76425Y851042D01*
X76758Y851250D01*
X76967Y851500D01*
X77008Y851750D01*
X76925Y852042D01*
X76633Y852250D01*
X76342Y852333D01*
X75967D01*
G01X76342D02*
X76592Y852458D01*
X76800Y852667D01*
X76883Y852917D01*
X76800Y853167D01*
X76592Y853375D01*
X76217Y853500D01*
X75842Y853458D01*
X75467Y853292D01*
G01X78358Y853083D02*
X78608Y853333D01*
X78900Y853458D01*
X79233Y853500D01*
X79650Y853417D01*
X79942Y853208D01*
X80025Y852958D01*
X79983Y852708D01*
X79817Y852500D01*
X78983Y852083D01*
X78608Y851792D01*
X78358Y851375D01*
X78275Y851000D01*
X80025D01*
G01X81996Y854900D02*
Y850900D01*
X89396D01*
G01X69017Y855000D02*
Y857500D01*
X70058D01*
X70392Y857375D01*
X70600Y857208D01*
X70683Y856875D01*
X70600Y856542D01*
X70350Y856333D01*
X70058Y856208D01*
X69017D01*
G01X70058D02*
X70683Y855000D01*
G01X72950D02*
Y857500D01*
X72450Y857000D01*
G01Y855000D02*
X73450D01*
G01X75133Y855500D02*
X75383Y855208D01*
X75717Y855042D01*
X76092Y855000D01*
X76425Y855042D01*
X76758Y855250D01*
X76967Y855500D01*
X77008Y855750D01*
X76925Y856042D01*
X76633Y856250D01*
X76342Y856333D01*
X75967D01*
G01X76342D02*
X76592Y856458D01*
X76800Y856667D01*
X76883Y856917D01*
X76800Y857167D01*
X76592Y857375D01*
X76217Y857500D01*
X75842Y857458D01*
X75467Y857292D01*
G01X78233Y855500D02*
X78483Y855208D01*
X78817Y855042D01*
X79192Y855000D01*
X79525Y855042D01*
X79858Y855250D01*
X80067Y855500D01*
X80108Y855750D01*
X80025Y856042D01*
X79733Y856250D01*
X79442Y856333D01*
X79067D01*
G01X79442D02*
X79692Y856458D01*
X79900Y856667D01*
X79983Y856917D01*
X79900Y857167D01*
X79692Y857375D01*
X79317Y857500D01*
X78942Y857458D01*
X78567Y857292D01*
G01X82000Y859200D02*
Y855200D01*
X89400D01*
G01X69017Y859000D02*
Y861500D01*
X70058D01*
X70392Y861375D01*
X70600Y861208D01*
X70683Y860875D01*
X70600Y860542D01*
X70350Y860333D01*
X70058Y860208D01*
X69017D01*
G01X70058D02*
X70683Y859000D01*
G01X72950D02*
Y861500D01*
X72450Y861000D01*
G01Y859000D02*
X73450D01*
G01X75133Y859500D02*
X75383Y859208D01*
X75717Y859042D01*
X76092Y859000D01*
X76425Y859042D01*
X76758Y859250D01*
X76967Y859500D01*
X77008Y859750D01*
X76925Y860042D01*
X76633Y860250D01*
X76342Y860333D01*
X75967D01*
G01X76342D02*
X76592Y860458D01*
X76800Y860667D01*
X76883Y860917D01*
X76800Y861167D01*
X76592Y861375D01*
X76217Y861500D01*
X75842Y861458D01*
X75467Y861292D01*
G01X79650Y859000D02*
Y861500D01*
X78108Y859708D01*
X80192D01*
G01X69017Y863000D02*
Y865500D01*
X70058D01*
X70392Y865375D01*
X70600Y865208D01*
X70683Y864875D01*
X70600Y864542D01*
X70350Y864333D01*
X70058Y864208D01*
X69017D01*
G01X70058D02*
X70683Y863000D01*
G01X72950D02*
Y865500D01*
X72450Y865000D01*
G01Y863000D02*
X73450D01*
G01X75133Y863500D02*
X75383Y863208D01*
X75717Y863042D01*
X76092Y863000D01*
X76425Y863042D01*
X76758Y863250D01*
X76967Y863500D01*
X77008Y863750D01*
X76925Y864042D01*
X76633Y864250D01*
X76342Y864333D01*
X75967D01*
G01X76342D02*
X76592Y864458D01*
X76800Y864667D01*
X76883Y864917D01*
X76800Y865167D01*
X76592Y865375D01*
X76217Y865500D01*
X75842Y865458D01*
X75467Y865292D01*
G01X78233Y863375D02*
X78483Y863167D01*
X78775Y863042D01*
X79150Y863000D01*
X79525Y863083D01*
X79817Y863250D01*
X80025Y863542D01*
X80067Y863875D01*
X79983Y864208D01*
X79775Y864417D01*
X79483Y864583D01*
X79192Y864625D01*
X78900Y864583D01*
X78525Y864417D01*
X78650Y865500D01*
X79775D01*
G01X82000Y867700D02*
Y863700D01*
X89400D01*
G01X82000Y863500D02*
Y859500D01*
X89400D01*
G01X70500Y906117D02*
X68000D01*
Y907158D01*
X68125Y907492D01*
X68292Y907700D01*
X68625Y907783D01*
X68958Y907700D01*
X69167Y907450D01*
X69292Y907158D01*
Y906117D01*
G01Y907158D02*
X70500Y907783D01*
G01Y910050D02*
X68000D01*
X68500Y909550D01*
G01X70500D02*
Y910550D01*
G01Y913150D02*
X68000D01*
X68500Y912650D01*
G01X70500D02*
Y913650D01*
G01X70125Y915333D02*
X70333Y915583D01*
X70458Y915875D01*
X70500Y916250D01*
X70417Y916625D01*
X70250Y916917D01*
X69958Y917125D01*
X69625Y917167D01*
X69292Y917083D01*
X69083Y916875D01*
X68917Y916583D01*
X68875Y916292D01*
X68917Y916000D01*
X69083Y915625D01*
X68000Y915750D01*
Y916875D01*
G01X66100Y914800D02*
X62100D01*
Y907400D01*
G01X41400Y890700D02*
X45400D01*
Y898100D01*
G01X46000Y905450D02*
X45958Y905117D01*
X45792Y904825D01*
X45542Y904575D01*
X45250Y904408D01*
X44917Y904325D01*
X44583D01*
X44250Y904408D01*
X43958Y904575D01*
X43708Y904825D01*
X43542Y905117D01*
X43500Y905450D01*
X43542Y905783D01*
X43708Y906075D01*
X43958Y906325D01*
X44250Y906492D01*
X44583Y906575D01*
X44917D01*
X45250Y906492D01*
X45542Y906325D01*
X45792Y906075D01*
X45958Y905783D01*
X46000Y905450D01*
G01X45333Y905783D02*
X46000Y906283D01*
G01X45625Y907633D02*
X45833Y907883D01*
X45958Y908175D01*
X46000Y908550D01*
X45917Y908925D01*
X45750Y909217D01*
X45458Y909425D01*
X45125Y909467D01*
X44792Y909383D01*
X44583Y909175D01*
X44417Y908883D01*
X44375Y908592D01*
X44417Y908300D01*
X44583Y907925D01*
X43500Y908050D01*
Y909175D01*
G01X61317Y899118D02*
Y913118D01*
G01X48317Y899118D02*
X61317D01*
G01X48317Y913118D02*
Y899118D01*
G01X53900Y880500D02*
X45900D01*
Y898100D01*
X53900D01*
Y880500D01*
G01X43567Y919500D02*
Y922000D01*
X44608D01*
X44942Y921875D01*
X45150Y921708D01*
X45233Y921375D01*
X45150Y921042D01*
X44900Y920833D01*
X44608Y920708D01*
X43567D01*
G01X44608D02*
X45233Y919500D01*
G01X46583Y920000D02*
X46833Y919708D01*
X47167Y919542D01*
X47542Y919500D01*
X47875Y919542D01*
X48208Y919750D01*
X48417Y920000D01*
X48458Y920250D01*
X48375Y920542D01*
X48083Y920750D01*
X47792Y920833D01*
X47417D01*
G01X47792D02*
X48042Y920958D01*
X48250Y921167D01*
X48333Y921417D01*
X48250Y921667D01*
X48042Y921875D01*
X47667Y922000D01*
X47292Y921958D01*
X46917Y921792D01*
G01X51100Y919500D02*
Y922000D01*
X49558Y920208D01*
X51642D01*
G01X43400Y918400D02*
Y914400D01*
X50800D01*
G01X61317Y913118D02*
X48317D01*
G01X70567Y931000D02*
Y933500D01*
X71567D01*
X71900Y933375D01*
X72150Y933083D01*
X72233Y932750D01*
X72150Y932417D01*
X71942Y932167D01*
X71567Y932042D01*
X70567D01*
G01X73667Y933500D02*
Y931000D01*
X75333D01*
G01X77517D02*
X77600Y931542D01*
X77725Y932000D01*
X77892Y932417D01*
X78100Y932875D01*
X78433Y933500D01*
X76767D01*
G01X90650Y943036D02*
X84014Y936400D01*
X66586D01*
X59950Y943036D01*
Y956164D01*
X66586Y962800D01*
X84014D01*
X90650Y956164D01*
Y943036D01*
G01X83500Y1012033D02*
X81000D01*
Y1012867D01*
X81125Y1013200D01*
X81292Y1013450D01*
X81542Y1013658D01*
X81833Y1013825D01*
X82250Y1013867D01*
X82667Y1013825D01*
X82958Y1013658D01*
X83208Y1013450D01*
X83375Y1013200D01*
X83500Y1012867D01*
Y1012033D01*
G01Y1015967D02*
X82958Y1016050D01*
X82500Y1016175D01*
X82083Y1016342D01*
X81625Y1016550D01*
X81000Y1016883D01*
Y1015217D01*
G01X56300Y1015800D02*
Y1007800D01*
G01D02*
X77300D01*
G01D02*
Y1015800D01*
G01X83033Y990500D02*
Y988708D01*
X83200Y988333D01*
X83533Y988083D01*
X83950Y988000D01*
X84367Y988083D01*
X84700Y988333D01*
X84867Y988708D01*
Y990500D01*
G01X87550Y988000D02*
Y990500D01*
X86008Y988708D01*
X88092D01*
G01X82700Y970150D02*
X84300Y968550D01*
G01X81100D02*
X82700Y970150D01*
G01X80400Y968550D02*
X85000D01*
G01X80400Y983050D02*
Y968550D01*
G01X85000Y983050D02*
X80400D01*
G01X85000Y968550D02*
Y983050D01*
G01X70017Y991000D02*
Y993500D01*
X71017D01*
X71350Y993375D01*
X71600Y993083D01*
X71683Y992750D01*
X71600Y992417D01*
X71392Y992167D01*
X71017Y992042D01*
X70017D01*
G01X73117Y991000D02*
Y993500D01*
X74158D01*
X74492Y993375D01*
X74700Y993208D01*
X74783Y992875D01*
X74700Y992542D01*
X74450Y992333D01*
X74158Y992208D01*
X73117D01*
G01X74158D02*
X74783Y991000D01*
G01X76133Y991375D02*
X76383Y991167D01*
X76675Y991042D01*
X77050Y991000D01*
X77425Y991083D01*
X77717Y991250D01*
X77925Y991542D01*
X77967Y991875D01*
X77883Y992208D01*
X77675Y992417D01*
X77383Y992583D01*
X77092Y992625D01*
X76800Y992583D01*
X76425Y992417D01*
X76550Y993500D01*
X77675D01*
G01X79233Y991500D02*
X79483Y991208D01*
X79817Y991042D01*
X80192Y991000D01*
X80525Y991042D01*
X80858Y991250D01*
X81067Y991500D01*
X81108Y991750D01*
X81025Y992042D01*
X80733Y992250D01*
X80442Y992333D01*
X80067D01*
G01X80442D02*
X80692Y992458D01*
X80900Y992667D01*
X80983Y992917D01*
X80900Y993167D01*
X80692Y993375D01*
X80317Y993500D01*
X79942Y993458D01*
X79567Y993292D01*
G01X53500Y977017D02*
X51000D01*
Y978017D01*
X51125Y978350D01*
X51417Y978600D01*
X51750Y978683D01*
X52083Y978600D01*
X52333Y978392D01*
X52458Y978017D01*
Y977017D01*
G01X53500Y980117D02*
X51000D01*
Y981158D01*
X51125Y981492D01*
X51292Y981700D01*
X51625Y981783D01*
X51958Y981700D01*
X52167Y981450D01*
X52292Y981158D01*
Y980117D01*
G01Y981158D02*
X53500Y981783D01*
G01X53125Y983133D02*
X53333Y983383D01*
X53458Y983675D01*
X53500Y984050D01*
X53417Y984425D01*
X53250Y984717D01*
X52958Y984925D01*
X52625Y984967D01*
X52292Y984883D01*
X52083Y984675D01*
X51917Y984383D01*
X51875Y984092D01*
X51917Y983800D01*
X52083Y983425D01*
X51000Y983550D01*
Y984675D01*
G01X51417Y986358D02*
X51167Y986608D01*
X51042Y986900D01*
X51000Y987233D01*
X51083Y987650D01*
X51292Y987942D01*
X51542Y988025D01*
X51792Y987983D01*
X52000Y987817D01*
X52417Y986983D01*
X52708Y986608D01*
X53125Y986358D01*
X53500Y986275D01*
Y988025D01*
G01X60000Y997567D02*
X57500D01*
Y998608D01*
X57625Y998942D01*
X57792Y999150D01*
X58125Y999233D01*
X58458Y999150D01*
X58667Y998900D01*
X58792Y998608D01*
Y997567D01*
G01Y998608D02*
X60000Y999233D01*
G01Y1001500D02*
X59958Y1001792D01*
X59833Y1002125D01*
X59625Y1002333D01*
X59333Y1002417D01*
X59042Y1002333D01*
X58792Y1002083D01*
X58667Y1001708D01*
Y1001292D01*
X58583Y1001042D01*
X58375Y1000833D01*
X58083Y1000750D01*
X57792Y1000875D01*
X57583Y1001167D01*
X57500Y1001500D01*
X57583Y1001833D01*
X57792Y1002125D01*
X58083Y1002250D01*
X58375Y1002167D01*
X58583Y1001958D01*
X58667Y1001708D01*
Y1001292D01*
X58792Y1000917D01*
X59042Y1000667D01*
X59333Y1000583D01*
X59625Y1000667D01*
X59833Y1000875D01*
X59958Y1001208D01*
X60000Y1001500D01*
G01X58958Y1003808D02*
X58667Y1004100D01*
X58500Y1004350D01*
X58417Y1004683D01*
X58500Y1004975D01*
X58667Y1005183D01*
X58917Y1005350D01*
X59208Y1005392D01*
X59458Y1005350D01*
X59708Y1005183D01*
X59917Y1004933D01*
X60000Y1004642D01*
X59917Y1004308D01*
X59667Y1004017D01*
X59292Y1003850D01*
X58875Y1003808D01*
X58333Y1003892D01*
X58042Y1004017D01*
X57750Y1004225D01*
X57542Y1004517D01*
X57500Y1004808D01*
X57583Y1005100D01*
X57792Y1005308D01*
G01X49300Y977117D02*
X46800D01*
Y978117D01*
X46925Y978450D01*
X47217Y978700D01*
X47550Y978783D01*
X47883Y978700D01*
X48133Y978492D01*
X48258Y978117D01*
Y977117D01*
G01X47008Y981967D02*
X46883Y981717D01*
X46800Y981425D01*
Y981092D01*
X46925Y980717D01*
X47133Y980425D01*
X47383Y980217D01*
X47800Y980050D01*
X48175Y980008D01*
X48550Y980092D01*
X48800Y980217D01*
X49050Y980467D01*
X49217Y980758D01*
X49300Y981050D01*
Y981342D01*
X49217Y981633D01*
X49092Y981883D01*
X48925Y982092D01*
G01X49300Y984650D02*
X46800D01*
X48592Y983108D01*
Y985192D01*
G01X46800Y987250D02*
X46883Y986917D01*
X47092Y986667D01*
X47342Y986500D01*
X47675Y986375D01*
X48050Y986333D01*
X48425Y986375D01*
X48758Y986500D01*
X49008Y986667D01*
X49217Y986917D01*
X49300Y987250D01*
X49217Y987583D01*
X49008Y987833D01*
X48758Y988000D01*
X48425Y988125D01*
X48050Y988167D01*
X47675Y988125D01*
X47342Y988000D01*
X47092Y987833D01*
X46883Y987583D01*
X46800Y987250D01*
G01X59800Y984400D02*
Y989900D01*
X67800D01*
Y984300D01*
G01X59800Y972300D02*
Y977800D01*
G01Y972300D02*
X67800D01*
Y977800D01*
G01X75467Y998300D02*
Y1000800D01*
X76508D01*
X76842Y1000675D01*
X77050Y1000508D01*
X77133Y1000175D01*
X77050Y999842D01*
X76800Y999633D01*
X76508Y999508D01*
X75467D01*
G01X76508D02*
X77133Y998300D01*
G01X78692Y998592D02*
X78983Y998383D01*
X79317Y998300D01*
X79650Y998383D01*
X79942Y998633D01*
X80150Y999008D01*
X80233Y999383D01*
Y999842D01*
X80150Y1000217D01*
X79942Y1000550D01*
X79692Y1000717D01*
X79400Y1000800D01*
X79067Y1000717D01*
X78817Y1000550D01*
X78650Y1000300D01*
X78567Y999967D01*
X78650Y999675D01*
X78858Y999383D01*
X79108Y999217D01*
X79400Y999175D01*
X79733Y999258D01*
X79983Y999467D01*
X80233Y999842D01*
G01X82500Y1000800D02*
X82167Y1000717D01*
X81917Y1000508D01*
X81750Y1000258D01*
X81625Y999925D01*
X81583Y999550D01*
X81625Y999175D01*
X81750Y998842D01*
X81917Y998592D01*
X82167Y998383D01*
X82500Y998300D01*
X82833Y998383D01*
X83083Y998592D01*
X83250Y998842D01*
X83375Y999175D01*
X83417Y999550D01*
X83375Y999925D01*
X83250Y1000258D01*
X83083Y1000508D01*
X82833Y1000717D01*
X82500Y1000800D01*
G01X66700Y1001800D02*
Y997800D01*
X74100D01*
G01X75467Y1002800D02*
Y1005300D01*
X76508D01*
X76842Y1005175D01*
X77050Y1005008D01*
X77133Y1004675D01*
X77050Y1004342D01*
X76800Y1004133D01*
X76508Y1004008D01*
X75467D01*
G01X76508D02*
X77133Y1002800D01*
G01X79400D02*
X79692Y1002842D01*
X80025Y1002967D01*
X80233Y1003175D01*
X80317Y1003467D01*
X80233Y1003758D01*
X79983Y1004008D01*
X79608Y1004133D01*
X79192D01*
X78942Y1004217D01*
X78733Y1004425D01*
X78650Y1004717D01*
X78775Y1005008D01*
X79067Y1005217D01*
X79400Y1005300D01*
X79733Y1005217D01*
X80025Y1005008D01*
X80150Y1004717D01*
X80067Y1004425D01*
X79858Y1004217D01*
X79608Y1004133D01*
X79192D01*
X78817Y1004008D01*
X78567Y1003758D01*
X78483Y1003467D01*
X78567Y1003175D01*
X78775Y1002967D01*
X79108Y1002842D01*
X79400Y1002800D01*
G01X81708Y1004883D02*
X81958Y1005133D01*
X82250Y1005258D01*
X82583Y1005300D01*
X83000Y1005217D01*
X83292Y1005008D01*
X83375Y1004758D01*
X83333Y1004508D01*
X83167Y1004300D01*
X82333Y1003883D01*
X81958Y1003592D01*
X81708Y1003175D01*
X81625Y1002800D01*
X83375D01*
G01X74100Y1002300D02*
Y1006300D01*
X66700D01*
G01X46017Y964000D02*
Y966500D01*
X47017D01*
X47350Y966375D01*
X47600Y966083D01*
X47683Y965750D01*
X47600Y965417D01*
X47392Y965167D01*
X47017Y965042D01*
X46017D01*
G01X50867Y966292D02*
X50617Y966417D01*
X50325Y966500D01*
X49992D01*
X49617Y966375D01*
X49325Y966167D01*
X49117Y965917D01*
X48950Y965500D01*
X48908Y965125D01*
X48992Y964750D01*
X49117Y964500D01*
X49367Y964250D01*
X49658Y964083D01*
X49950Y964000D01*
X50242D01*
X50533Y964083D01*
X50783Y964208D01*
X50992Y964375D01*
G01X53550Y964000D02*
Y966500D01*
X52008Y964708D01*
X54092D01*
G01X56150Y964000D02*
Y966500D01*
X55650Y966000D01*
G01Y964000D02*
X56650D01*
G01X48208Y1008817D02*
X48083Y1008567D01*
X48000Y1008275D01*
Y1007942D01*
X48125Y1007567D01*
X48333Y1007275D01*
X48583Y1007067D01*
X49000Y1006900D01*
X49375Y1006858D01*
X49750Y1006942D01*
X50000Y1007067D01*
X50250Y1007317D01*
X50417Y1007608D01*
X50500Y1007900D01*
Y1008192D01*
X50417Y1008483D01*
X50292Y1008733D01*
X50125Y1008942D01*
G01X50000Y1010083D02*
X50292Y1010333D01*
X50458Y1010667D01*
X50500Y1011042D01*
X50458Y1011375D01*
X50250Y1011708D01*
X50000Y1011917D01*
X49750Y1011958D01*
X49458Y1011875D01*
X49250Y1011583D01*
X49167Y1011292D01*
Y1010917D01*
G01Y1011292D02*
X49042Y1011542D01*
X48833Y1011750D01*
X48583Y1011833D01*
X48333Y1011750D01*
X48125Y1011542D01*
X48000Y1011167D01*
X48042Y1010792D01*
X48208Y1010417D01*
G01X50500Y1014100D02*
X50458Y1014392D01*
X50333Y1014725D01*
X50125Y1014933D01*
X49833Y1015017D01*
X49542Y1014933D01*
X49292Y1014683D01*
X49167Y1014308D01*
Y1013892D01*
X49083Y1013642D01*
X48875Y1013433D01*
X48583Y1013350D01*
X48292Y1013475D01*
X48083Y1013767D01*
X48000Y1014100D01*
X48083Y1014433D01*
X48292Y1014725D01*
X48583Y1014850D01*
X48875Y1014767D01*
X49083Y1014558D01*
X49167Y1014308D01*
Y1013892D01*
X49292Y1013517D01*
X49542Y1013267D01*
X49833Y1013183D01*
X50125Y1013267D01*
X50333Y1013475D01*
X50458Y1013808D01*
X50500Y1014100D01*
G01X58000Y984517D02*
X55500D01*
Y985517D01*
X55625Y985850D01*
X55917Y986100D01*
X56250Y986183D01*
X56583Y986100D01*
X56833Y985892D01*
X56958Y985517D01*
Y984517D01*
G01X58000Y987617D02*
X55500D01*
Y988658D01*
X55625Y988992D01*
X55792Y989200D01*
X56125Y989283D01*
X56458Y989200D01*
X56667Y988950D01*
X56792Y988658D01*
Y987617D01*
G01Y988658D02*
X58000Y989283D01*
G01X57625Y990633D02*
X57833Y990883D01*
X57958Y991175D01*
X58000Y991550D01*
X57917Y991925D01*
X57750Y992217D01*
X57458Y992425D01*
X57125Y992467D01*
X56792Y992383D01*
X56583Y992175D01*
X56417Y991883D01*
X56375Y991592D01*
X56417Y991300D01*
X56583Y990925D01*
X55500Y991050D01*
Y992175D01*
G01X58000Y994567D02*
X57458Y994650D01*
X57000Y994775D01*
X56583Y994942D01*
X56125Y995150D01*
X55500Y995483D01*
Y993817D01*
G01X59700Y982500D02*
X54500D01*
Y971700D01*
G01X55500Y1044158D02*
X53000D01*
Y1045742D01*
G01X54208Y1045158D02*
Y1044158D01*
G01X55500Y1048550D02*
X53000D01*
X54792Y1047008D01*
Y1049092D01*
G01X57700Y1038600D02*
Y1061600D01*
G01X96500Y1038600D02*
X57700D01*
G01Y1061600D02*
X96500D01*
G01X77300Y1015800D02*
X56300D01*
G01X81600Y1036100D02*
X60600D01*
G01D02*
Y1028100D01*
G01D02*
X81600D01*
G01D02*
Y1036100D01*
G01X49067Y1024500D02*
Y1027000D01*
X50108D01*
X50442Y1026875D01*
X50650Y1026708D01*
X50733Y1026375D01*
X50650Y1026042D01*
X50400Y1025833D01*
X50108Y1025708D01*
X49067D01*
G01X50108D02*
X50733Y1024500D01*
G01X53000D02*
X53292Y1024542D01*
X53625Y1024667D01*
X53833Y1024875D01*
X53917Y1025167D01*
X53833Y1025458D01*
X53583Y1025708D01*
X53208Y1025833D01*
X52792D01*
X52542Y1025917D01*
X52333Y1026125D01*
X52250Y1026417D01*
X52375Y1026708D01*
X52667Y1026917D01*
X53000Y1027000D01*
X53333Y1026917D01*
X53625Y1026708D01*
X53750Y1026417D01*
X53667Y1026125D01*
X53458Y1025917D01*
X53208Y1025833D01*
X52792D01*
X52417Y1025708D01*
X52167Y1025458D01*
X52083Y1025167D01*
X52167Y1024875D01*
X52375Y1024667D01*
X52708Y1024542D01*
X53000Y1024500D01*
G01X56600D02*
Y1027000D01*
X55058Y1025208D01*
X57142D01*
G01X48567Y1019000D02*
Y1021500D01*
X49608D01*
X49942Y1021375D01*
X50150Y1021208D01*
X50233Y1020875D01*
X50150Y1020542D01*
X49900Y1020333D01*
X49608Y1020208D01*
X48567D01*
G01X49608D02*
X50233Y1019000D01*
G01X52500D02*
X52792Y1019042D01*
X53125Y1019167D01*
X53333Y1019375D01*
X53417Y1019667D01*
X53333Y1019958D01*
X53083Y1020208D01*
X52708Y1020333D01*
X52292D01*
X52042Y1020417D01*
X51833Y1020625D01*
X51750Y1020917D01*
X51875Y1021208D01*
X52167Y1021417D01*
X52500Y1021500D01*
X52833Y1021417D01*
X53125Y1021208D01*
X53250Y1020917D01*
X53167Y1020625D01*
X52958Y1020417D01*
X52708Y1020333D01*
X52292D01*
X51917Y1020208D01*
X51667Y1019958D01*
X51583Y1019667D01*
X51667Y1019375D01*
X51875Y1019167D01*
X52208Y1019042D01*
X52500Y1019000D01*
G01X55600D02*
X55892Y1019042D01*
X56225Y1019167D01*
X56433Y1019375D01*
X56517Y1019667D01*
X56433Y1019958D01*
X56183Y1020208D01*
X55808Y1020333D01*
X55392D01*
X55142Y1020417D01*
X54933Y1020625D01*
X54850Y1020917D01*
X54975Y1021208D01*
X55267Y1021417D01*
X55600Y1021500D01*
X55933Y1021417D01*
X56225Y1021208D01*
X56350Y1020917D01*
X56267Y1020625D01*
X56058Y1020417D01*
X55808Y1020333D01*
X55392D01*
X55017Y1020208D01*
X54767Y1019958D01*
X54683Y1019667D01*
X54767Y1019375D01*
X54975Y1019167D01*
X55308Y1019042D01*
X55600Y1019000D01*
G01X65000Y1018600D02*
Y1022600D01*
X57600D01*
G01X80067Y1023500D02*
Y1026000D01*
X81108D01*
X81442Y1025875D01*
X81650Y1025708D01*
X81733Y1025375D01*
X81650Y1025042D01*
X81400Y1024833D01*
X81108Y1024708D01*
X80067D01*
G01X81108D02*
X81733Y1023500D01*
G01X84000D02*
X84292Y1023542D01*
X84625Y1023667D01*
X84833Y1023875D01*
X84917Y1024167D01*
X84833Y1024458D01*
X84583Y1024708D01*
X84208Y1024833D01*
X83792D01*
X83542Y1024917D01*
X83333Y1025125D01*
X83250Y1025417D01*
X83375Y1025708D01*
X83667Y1025917D01*
X84000Y1026000D01*
X84333Y1025917D01*
X84625Y1025708D01*
X84750Y1025417D01*
X84667Y1025125D01*
X84458Y1024917D01*
X84208Y1024833D01*
X83792D01*
X83417Y1024708D01*
X83167Y1024458D01*
X83083Y1024167D01*
X83167Y1023875D01*
X83375Y1023667D01*
X83708Y1023542D01*
X84000Y1023500D01*
G01X87100Y1026000D02*
X86767Y1025917D01*
X86517Y1025708D01*
X86350Y1025458D01*
X86225Y1025125D01*
X86183Y1024750D01*
X86225Y1024375D01*
X86350Y1024042D01*
X86517Y1023792D01*
X86767Y1023583D01*
X87100Y1023500D01*
X87433Y1023583D01*
X87683Y1023792D01*
X87850Y1024042D01*
X87975Y1024375D01*
X88017Y1024750D01*
X87975Y1025125D01*
X87850Y1025458D01*
X87683Y1025708D01*
X87433Y1025917D01*
X87100Y1026000D01*
G01X77700Y1023400D02*
Y1027400D01*
X70300D01*
G01X80567Y1019000D02*
Y1021500D01*
X81608D01*
X81942Y1021375D01*
X82150Y1021208D01*
X82233Y1020875D01*
X82150Y1020542D01*
X81900Y1020333D01*
X81608Y1020208D01*
X80567D01*
G01X81608D02*
X82233Y1019000D01*
G01X84417D02*
X84500Y1019542D01*
X84625Y1020000D01*
X84792Y1020417D01*
X85000Y1020875D01*
X85333Y1021500D01*
X83667D01*
G01X87600Y1019000D02*
X87892Y1019042D01*
X88225Y1019167D01*
X88433Y1019375D01*
X88517Y1019667D01*
X88433Y1019958D01*
X88183Y1020208D01*
X87808Y1020333D01*
X87392D01*
X87142Y1020417D01*
X86933Y1020625D01*
X86850Y1020917D01*
X86975Y1021208D01*
X87267Y1021417D01*
X87600Y1021500D01*
X87933Y1021417D01*
X88225Y1021208D01*
X88350Y1020917D01*
X88267Y1020625D01*
X88058Y1020417D01*
X87808Y1020333D01*
X87392D01*
X87017Y1020208D01*
X86767Y1019958D01*
X86683Y1019667D01*
X86767Y1019375D01*
X86975Y1019167D01*
X87308Y1019042D01*
X87600Y1019000D01*
G01X77800Y1018900D02*
Y1022900D01*
X70400D01*
G01X52708Y1030817D02*
X52583Y1030567D01*
X52500Y1030275D01*
Y1029942D01*
X52625Y1029567D01*
X52833Y1029275D01*
X53083Y1029067D01*
X53500Y1028900D01*
X53875Y1028858D01*
X54250Y1028942D01*
X54500Y1029067D01*
X54750Y1029317D01*
X54917Y1029608D01*
X55000Y1029900D01*
Y1030192D01*
X54917Y1030483D01*
X54792Y1030733D01*
X54625Y1030942D01*
G01X54500Y1032083D02*
X54792Y1032333D01*
X54958Y1032667D01*
X55000Y1033042D01*
X54958Y1033375D01*
X54750Y1033708D01*
X54500Y1033917D01*
X54250Y1033958D01*
X53958Y1033875D01*
X53750Y1033583D01*
X53667Y1033292D01*
Y1032917D01*
G01Y1033292D02*
X53542Y1033542D01*
X53333Y1033750D01*
X53083Y1033833D01*
X52833Y1033750D01*
X52625Y1033542D01*
X52500Y1033167D01*
X52542Y1032792D01*
X52708Y1032417D01*
G01X54625Y1035183D02*
X54833Y1035433D01*
X54958Y1035725D01*
X55000Y1036100D01*
X54917Y1036475D01*
X54750Y1036767D01*
X54458Y1036975D01*
X54125Y1037017D01*
X53792Y1036933D01*
X53583Y1036725D01*
X53417Y1036433D01*
X53375Y1036142D01*
X53417Y1035850D01*
X53583Y1035475D01*
X52500Y1035600D01*
Y1036725D01*
G01X43000Y1019200D02*
X35000D01*
Y1036800D01*
X43000D01*
Y1019200D01*
G01X68033Y1115500D02*
Y1118000D01*
X68867D01*
X69200Y1117875D01*
X69450Y1117708D01*
X69658Y1117458D01*
X69825Y1117167D01*
X69867Y1116750D01*
X69825Y1116333D01*
X69658Y1116042D01*
X69450Y1115792D01*
X69200Y1115625D01*
X68867Y1115500D01*
X68033D01*
G01X71342Y1115792D02*
X71633Y1115583D01*
X71967Y1115500D01*
X72300Y1115583D01*
X72592Y1115833D01*
X72800Y1116208D01*
X72883Y1116583D01*
Y1117042D01*
X72800Y1117417D01*
X72592Y1117750D01*
X72342Y1117917D01*
X72050Y1118000D01*
X71717Y1117917D01*
X71467Y1117750D01*
X71300Y1117500D01*
X71217Y1117167D01*
X71300Y1116875D01*
X71508Y1116583D01*
X71758Y1116417D01*
X72050Y1116375D01*
X72383Y1116458D01*
X72633Y1116667D01*
X72883Y1117042D01*
G01X84483Y1113000D02*
Y1115500D01*
X85317D01*
X85650Y1115375D01*
X85900Y1115208D01*
X86108Y1114958D01*
X86275Y1114667D01*
X86317Y1114250D01*
X86275Y1113833D01*
X86108Y1113542D01*
X85900Y1113292D01*
X85650Y1113125D01*
X85317Y1113000D01*
X84483D01*
G01X88500D02*
Y1115500D01*
X88000Y1115000D01*
G01Y1113000D02*
X89000D01*
G01X91600Y1115500D02*
X91267Y1115417D01*
X91017Y1115208D01*
X90850Y1114958D01*
X90725Y1114625D01*
X90683Y1114250D01*
X90725Y1113875D01*
X90850Y1113542D01*
X91017Y1113292D01*
X91267Y1113083D01*
X91600Y1113000D01*
X91933Y1113083D01*
X92183Y1113292D01*
X92350Y1113542D01*
X92475Y1113875D01*
X92517Y1114250D01*
X92475Y1114625D01*
X92350Y1114958D01*
X92183Y1115208D01*
X91933Y1115417D01*
X91600Y1115500D01*
G01X74350Y1105000D02*
Y1102500D01*
G01X73392Y1105000D02*
X75308D01*
G01X78367Y1104792D02*
X78117Y1104917D01*
X77825Y1105000D01*
X77492D01*
X77117Y1104875D01*
X76825Y1104667D01*
X76617Y1104417D01*
X76450Y1104000D01*
X76408Y1103625D01*
X76492Y1103250D01*
X76617Y1103000D01*
X76867Y1102750D01*
X77158Y1102583D01*
X77450Y1102500D01*
X77742D01*
X78033Y1102583D01*
X78283Y1102708D01*
X78492Y1102875D01*
G01X80550Y1102500D02*
Y1105000D01*
X80050Y1104500D01*
G01Y1102500D02*
X81050D01*
G01X82858Y1103542D02*
X83150Y1103833D01*
X83400Y1104000D01*
X83733Y1104083D01*
X84025Y1104000D01*
X84233Y1103833D01*
X84400Y1103583D01*
X84442Y1103292D01*
X84400Y1103042D01*
X84233Y1102792D01*
X83983Y1102583D01*
X83692Y1102500D01*
X83358Y1102583D01*
X83067Y1102833D01*
X82900Y1103208D01*
X82858Y1103625D01*
X82942Y1104167D01*
X83067Y1104458D01*
X83275Y1104750D01*
X83567Y1104958D01*
X83858Y1105000D01*
X84150Y1104917D01*
X84358Y1104708D01*
G01X95300Y1099600D02*
X84100D01*
G01Y1081600D02*
X95300D01*
G01X56900Y1099600D02*
X68100D01*
G01X56900Y1081600D02*
Y1099600D01*
G01X68100Y1081600D02*
X56900D01*
G01X36517Y1099500D02*
Y1102000D01*
X37558D01*
X37892Y1101875D01*
X38100Y1101708D01*
X38183Y1101375D01*
X38100Y1101042D01*
X37850Y1100833D01*
X37558Y1100708D01*
X36517D01*
G01X37558D02*
X38183Y1099500D01*
G01X40450D02*
Y1102000D01*
X39950Y1101500D01*
G01Y1099500D02*
X40950D01*
G01X43550D02*
Y1102000D01*
X43050Y1101500D01*
G01Y1099500D02*
X44050D01*
G01X46567D02*
X46650Y1100042D01*
X46775Y1100500D01*
X46942Y1100917D01*
X47150Y1101375D01*
X47483Y1102000D01*
X45817D01*
G01X43400Y1094000D02*
Y1098000D01*
X36000D01*
G01X37067Y1082000D02*
Y1084500D01*
X38108D01*
X38442Y1084375D01*
X38650Y1084208D01*
X38733Y1083875D01*
X38650Y1083542D01*
X38400Y1083333D01*
X38108Y1083208D01*
X37067D01*
G01X38108D02*
X38733Y1082000D01*
G01X40083Y1082500D02*
X40333Y1082208D01*
X40667Y1082042D01*
X41042Y1082000D01*
X41375Y1082042D01*
X41708Y1082250D01*
X41917Y1082500D01*
X41958Y1082750D01*
X41875Y1083042D01*
X41583Y1083250D01*
X41292Y1083333D01*
X40917D01*
G01X41292D02*
X41542Y1083458D01*
X41750Y1083667D01*
X41833Y1083917D01*
X41750Y1084167D01*
X41542Y1084375D01*
X41167Y1084500D01*
X40792Y1084458D01*
X40417Y1084292D01*
G01X44100Y1082000D02*
X44392Y1082042D01*
X44725Y1082167D01*
X44933Y1082375D01*
X45017Y1082667D01*
X44933Y1082958D01*
X44683Y1083208D01*
X44308Y1083333D01*
X43892D01*
X43642Y1083417D01*
X43433Y1083625D01*
X43350Y1083917D01*
X43475Y1084208D01*
X43767Y1084417D01*
X44100Y1084500D01*
X44433Y1084417D01*
X44725Y1084208D01*
X44850Y1083917D01*
X44767Y1083625D01*
X44558Y1083417D01*
X44308Y1083333D01*
X43892D01*
X43517Y1083208D01*
X43267Y1082958D01*
X43183Y1082667D01*
X43267Y1082375D01*
X43475Y1082167D01*
X43808Y1082042D01*
X44100Y1082000D01*
G01X35118Y1086583D02*
Y1099583D01*
G01X83617Y1067800D02*
Y1070300D01*
X84658D01*
X84992Y1070175D01*
X85200Y1070008D01*
X85283Y1069675D01*
X85200Y1069342D01*
X84950Y1069133D01*
X84658Y1069008D01*
X83617D01*
G01X84658D02*
X85283Y1067800D01*
G01X87550D02*
Y1070300D01*
X87050Y1069800D01*
G01Y1067800D02*
X88050D01*
G01X90567D02*
X90650Y1068342D01*
X90775Y1068800D01*
X90942Y1069217D01*
X91150Y1069675D01*
X91483Y1070300D01*
X89817D01*
G01X93042Y1068092D02*
X93333Y1067883D01*
X93667Y1067800D01*
X94000Y1067883D01*
X94292Y1068133D01*
X94500Y1068508D01*
X94583Y1068883D01*
Y1069342D01*
X94500Y1069717D01*
X94292Y1070050D01*
X94042Y1070217D01*
X93750Y1070300D01*
X93417Y1070217D01*
X93167Y1070050D01*
X93000Y1069800D01*
X92917Y1069467D01*
X93000Y1069175D01*
X93208Y1068883D01*
X93458Y1068717D01*
X93750Y1068675D01*
X94083Y1068758D01*
X94333Y1068967D01*
X94583Y1069342D01*
G01X63200Y1065700D02*
X80800D01*
G01X63200Y1073700D02*
Y1065700D01*
G01X80800Y1073700D02*
X63200D01*
G01X80800Y1065700D02*
Y1073700D01*
G01X74202Y1121197D02*
Y1142197D01*
G01D02*
X66202D01*
G01D02*
Y1121197D01*
G01D02*
X74202D01*
G01X92502Y1140097D02*
X84502D01*
G01D02*
Y1119097D01*
G01D02*
X92502D01*
G01X81000Y1143567D02*
X78500D01*
Y1144608D01*
X78625Y1144942D01*
X78792Y1145150D01*
X79125Y1145233D01*
X79458Y1145150D01*
X79667Y1144900D01*
X79792Y1144608D01*
Y1143567D01*
G01Y1144608D02*
X81000Y1145233D01*
G01X80708Y1146792D02*
X80917Y1147083D01*
X81000Y1147417D01*
X80917Y1147750D01*
X80667Y1148042D01*
X80292Y1148250D01*
X79917Y1148333D01*
X79458D01*
X79083Y1148250D01*
X78750Y1148042D01*
X78583Y1147792D01*
X78500Y1147500D01*
X78583Y1147167D01*
X78750Y1146917D01*
X79000Y1146750D01*
X79333Y1146667D01*
X79625Y1146750D01*
X79917Y1146958D01*
X80083Y1147208D01*
X80125Y1147500D01*
X80042Y1147833D01*
X79833Y1148083D01*
X79458Y1148333D01*
G01X80708Y1149892D02*
X80917Y1150183D01*
X81000Y1150517D01*
X80917Y1150850D01*
X80667Y1151142D01*
X80292Y1151350D01*
X79917Y1151433D01*
X79458D01*
X79083Y1151350D01*
X78750Y1151142D01*
X78583Y1150892D01*
X78500Y1150600D01*
X78583Y1150267D01*
X78750Y1150017D01*
X79000Y1149850D01*
X79333Y1149767D01*
X79625Y1149850D01*
X79917Y1150058D01*
X80083Y1150308D01*
X80125Y1150600D01*
X80042Y1150933D01*
X79833Y1151183D01*
X79458Y1151433D01*
G01X59500Y1128567D02*
X57000D01*
Y1129608D01*
X57125Y1129942D01*
X57292Y1130150D01*
X57625Y1130233D01*
X57958Y1130150D01*
X58167Y1129900D01*
X58292Y1129608D01*
Y1128567D01*
G01Y1129608D02*
X59500Y1130233D01*
G01X59208Y1131792D02*
X59417Y1132083D01*
X59500Y1132417D01*
X59417Y1132750D01*
X59167Y1133042D01*
X58792Y1133250D01*
X58417Y1133333D01*
X57958D01*
X57583Y1133250D01*
X57250Y1133042D01*
X57083Y1132792D01*
X57000Y1132500D01*
X57083Y1132167D01*
X57250Y1131917D01*
X57500Y1131750D01*
X57833Y1131667D01*
X58125Y1131750D01*
X58417Y1131958D01*
X58583Y1132208D01*
X58625Y1132500D01*
X58542Y1132833D01*
X58333Y1133083D01*
X57958Y1133333D01*
G01X59500Y1135600D02*
X59458Y1135892D01*
X59333Y1136225D01*
X59125Y1136433D01*
X58833Y1136517D01*
X58542Y1136433D01*
X58292Y1136183D01*
X58167Y1135808D01*
Y1135392D01*
X58083Y1135142D01*
X57875Y1134933D01*
X57583Y1134850D01*
X57292Y1134975D01*
X57083Y1135267D01*
X57000Y1135600D01*
X57083Y1135933D01*
X57292Y1136225D01*
X57583Y1136350D01*
X57875Y1136267D01*
X58083Y1136058D01*
X58167Y1135808D01*
Y1135392D01*
X58292Y1135017D01*
X58542Y1134767D01*
X58833Y1134683D01*
X59125Y1134767D01*
X59333Y1134975D01*
X59458Y1135308D01*
X59500Y1135600D01*
G01X78500Y1120567D02*
X76000D01*
Y1121608D01*
X76125Y1121942D01*
X76292Y1122150D01*
X76625Y1122233D01*
X76958Y1122150D01*
X77167Y1121900D01*
X77292Y1121608D01*
Y1120567D01*
G01Y1121608D02*
X78500Y1122233D01*
G01X78208Y1123792D02*
X78417Y1124083D01*
X78500Y1124417D01*
X78417Y1124750D01*
X78167Y1125042D01*
X77792Y1125250D01*
X77417Y1125333D01*
X76958D01*
X76583Y1125250D01*
X76250Y1125042D01*
X76083Y1124792D01*
X76000Y1124500D01*
X76083Y1124167D01*
X76250Y1123917D01*
X76500Y1123750D01*
X76833Y1123667D01*
X77125Y1123750D01*
X77417Y1123958D01*
X77583Y1124208D01*
X77625Y1124500D01*
X77542Y1124833D01*
X77333Y1125083D01*
X76958Y1125333D01*
G01X78500Y1128100D02*
X76000D01*
X77792Y1126558D01*
Y1128642D01*
G01X79398Y1120703D02*
X83398D01*
Y1128103D01*
G01X59500Y1118567D02*
X57000D01*
Y1119608D01*
X57125Y1119942D01*
X57292Y1120150D01*
X57625Y1120233D01*
X57958Y1120150D01*
X58167Y1119900D01*
X58292Y1119608D01*
Y1118567D01*
G01Y1119608D02*
X59500Y1120233D01*
G01X59208Y1121792D02*
X59417Y1122083D01*
X59500Y1122417D01*
X59417Y1122750D01*
X59167Y1123042D01*
X58792Y1123250D01*
X58417Y1123333D01*
X57958D01*
X57583Y1123250D01*
X57250Y1123042D01*
X57083Y1122792D01*
X57000Y1122500D01*
X57083Y1122167D01*
X57250Y1121917D01*
X57500Y1121750D01*
X57833Y1121667D01*
X58125Y1121750D01*
X58417Y1121958D01*
X58583Y1122208D01*
X58625Y1122500D01*
X58542Y1122833D01*
X58333Y1123083D01*
X57958Y1123333D01*
G01X59000Y1124683D02*
X59292Y1124933D01*
X59458Y1125267D01*
X59500Y1125642D01*
X59458Y1125975D01*
X59250Y1126308D01*
X59000Y1126517D01*
X58750Y1126558D01*
X58458Y1126475D01*
X58250Y1126183D01*
X58167Y1125892D01*
Y1125517D01*
G01Y1125892D02*
X58042Y1126142D01*
X57833Y1126350D01*
X57583Y1126433D01*
X57333Y1126350D01*
X57125Y1126142D01*
X57000Y1125767D01*
X57042Y1125392D01*
X57208Y1125017D01*
G01X61498Y1118403D02*
X65498D01*
Y1125803D01*
G01X77000Y1143517D02*
X74500D01*
Y1144558D01*
X74625Y1144892D01*
X74792Y1145100D01*
X75125Y1145183D01*
X75458Y1145100D01*
X75667Y1144850D01*
X75792Y1144558D01*
Y1143517D01*
G01Y1144558D02*
X77000Y1145183D01*
G01Y1147450D02*
X74500D01*
X75000Y1146950D01*
G01X77000D02*
Y1147950D01*
G01X74500Y1150550D02*
X74583Y1150217D01*
X74792Y1149967D01*
X75042Y1149800D01*
X75375Y1149675D01*
X75750Y1149633D01*
X76125Y1149675D01*
X76458Y1149800D01*
X76708Y1149967D01*
X76917Y1150217D01*
X77000Y1150550D01*
X76917Y1150883D01*
X76708Y1151133D01*
X76458Y1151300D01*
X76125Y1151425D01*
X75750Y1151467D01*
X75375Y1151425D01*
X75042Y1151300D01*
X74792Y1151133D01*
X74583Y1150883D01*
X74500Y1150550D01*
G01X76500Y1152733D02*
X76792Y1152983D01*
X76958Y1153317D01*
X77000Y1153692D01*
X76958Y1154025D01*
X76750Y1154358D01*
X76500Y1154567D01*
X76250Y1154608D01*
X75958Y1154525D01*
X75750Y1154233D01*
X75667Y1153942D01*
Y1153567D01*
G01Y1153942D02*
X75542Y1154192D01*
X75333Y1154400D01*
X75083Y1154483D01*
X74833Y1154400D01*
X74625Y1154192D01*
X74500Y1153817D01*
X74542Y1153442D01*
X74708Y1153067D01*
G01X79002Y1139897D02*
X75002D01*
Y1132497D01*
G01X59500Y1138517D02*
X57000D01*
Y1139558D01*
X57125Y1139892D01*
X57292Y1140100D01*
X57625Y1140183D01*
X57958Y1140100D01*
X58167Y1139850D01*
X58292Y1139558D01*
Y1138517D01*
G01Y1139558D02*
X59500Y1140183D01*
G01Y1142450D02*
X57000D01*
X57500Y1141950D01*
G01X59500D02*
Y1142950D01*
G01X57000Y1145550D02*
X57083Y1145217D01*
X57292Y1144967D01*
X57542Y1144800D01*
X57875Y1144675D01*
X58250Y1144633D01*
X58625Y1144675D01*
X58958Y1144800D01*
X59208Y1144967D01*
X59417Y1145217D01*
X59500Y1145550D01*
X59417Y1145883D01*
X59208Y1146133D01*
X58958Y1146300D01*
X58625Y1146425D01*
X58250Y1146467D01*
X57875Y1146425D01*
X57542Y1146300D01*
X57292Y1146133D01*
X57083Y1145883D01*
X57000Y1145550D01*
G01X57417Y1147858D02*
X57167Y1148108D01*
X57042Y1148400D01*
X57000Y1148733D01*
X57083Y1149150D01*
X57292Y1149442D01*
X57542Y1149525D01*
X57792Y1149483D01*
X58000Y1149317D01*
X58417Y1148483D01*
X58708Y1148108D01*
X59125Y1147858D01*
X59500Y1147775D01*
Y1149525D01*
G01X61198Y1136603D02*
X65198D01*
Y1144003D01*
G01X86417Y1148492D02*
X86167Y1148617D01*
X85875Y1148700D01*
X85542D01*
X85167Y1148575D01*
X84875Y1148367D01*
X84667Y1148117D01*
X84500Y1147700D01*
X84458Y1147325D01*
X84542Y1146950D01*
X84667Y1146700D01*
X84917Y1146450D01*
X85208Y1146283D01*
X85500Y1146200D01*
X85792D01*
X86083Y1146283D01*
X86333Y1146408D01*
X86542Y1146575D01*
G01X89100Y1146200D02*
Y1148700D01*
X87558Y1146908D01*
X89642D01*
G01X92200Y1146200D02*
Y1148700D01*
X90658Y1146908D01*
X92742D01*
G01X66317Y1149792D02*
X66067Y1149917D01*
X65775Y1150000D01*
X65442D01*
X65067Y1149875D01*
X64775Y1149667D01*
X64567Y1149417D01*
X64400Y1149000D01*
X64358Y1148625D01*
X64442Y1148250D01*
X64567Y1148000D01*
X64817Y1147750D01*
X65108Y1147583D01*
X65400Y1147500D01*
X65692D01*
X65983Y1147583D01*
X66233Y1147708D01*
X66442Y1147875D01*
G01X69000Y1147500D02*
Y1150000D01*
X67458Y1148208D01*
X69542D01*
G01X70683Y1148000D02*
X70933Y1147708D01*
X71267Y1147542D01*
X71642Y1147500D01*
X71975Y1147542D01*
X72308Y1147750D01*
X72517Y1148000D01*
X72558Y1148250D01*
X72475Y1148542D01*
X72183Y1148750D01*
X71892Y1148833D01*
X71517D01*
G01X71892D02*
X72142Y1148958D01*
X72350Y1149167D01*
X72433Y1149417D01*
X72350Y1149667D01*
X72142Y1149875D01*
X71767Y1150000D01*
X71392Y1149958D01*
X71017Y1149792D01*
G01X76567Y1174000D02*
Y1176500D01*
X77608D01*
X77942Y1176375D01*
X78150Y1176208D01*
X78233Y1175875D01*
X78150Y1175542D01*
X77900Y1175333D01*
X77608Y1175208D01*
X76567D01*
G01X77608D02*
X78233Y1174000D01*
G01X79792Y1174292D02*
X80083Y1174083D01*
X80417Y1174000D01*
X80750Y1174083D01*
X81042Y1174333D01*
X81250Y1174708D01*
X81333Y1175083D01*
Y1175542D01*
X81250Y1175917D01*
X81042Y1176250D01*
X80792Y1176417D01*
X80500Y1176500D01*
X80167Y1176417D01*
X79917Y1176250D01*
X79750Y1176000D01*
X79667Y1175667D01*
X79750Y1175375D01*
X79958Y1175083D01*
X80208Y1174917D01*
X80500Y1174875D01*
X80833Y1174958D01*
X81083Y1175167D01*
X81333Y1175542D01*
G01X82808Y1176083D02*
X83058Y1176333D01*
X83350Y1176458D01*
X83683Y1176500D01*
X84100Y1176417D01*
X84392Y1176208D01*
X84475Y1175958D01*
X84433Y1175708D01*
X84267Y1175500D01*
X83433Y1175083D01*
X83058Y1174792D01*
X82808Y1174375D01*
X82725Y1174000D01*
X84475D01*
G01X74200Y1173100D02*
Y1177100D01*
X66800D01*
G01X75000Y1279800D02*
X70000D01*
X73583Y1276717D01*
Y1280883D01*
G01X75000Y1284400D02*
X74917Y1284983D01*
X74667Y1285650D01*
X74250Y1286067D01*
X73667Y1286233D01*
X73083Y1286067D01*
X72583Y1285567D01*
X72333Y1284817D01*
Y1283983D01*
X72167Y1283483D01*
X71750Y1283067D01*
X71167Y1282900D01*
X70583Y1283150D01*
X70167Y1283733D01*
X70000Y1284400D01*
X70167Y1285067D01*
X70583Y1285650D01*
X71167Y1285900D01*
X71750Y1285733D01*
X72167Y1285317D01*
X72333Y1284817D01*
Y1283983D01*
X72583Y1283233D01*
X73083Y1282733D01*
X73667Y1282567D01*
X74250Y1282733D01*
X74667Y1283150D01*
X74917Y1283817D01*
X75000Y1284400D01*
G01X75167Y1290000D02*
X75083Y1289833D01*
X74917D01*
X74833Y1290000D01*
X74917Y1290167D01*
X75083D01*
X75167Y1290000D01*
G01X72917Y1294017D02*
X72333Y1294600D01*
X72000Y1295100D01*
X71833Y1295767D01*
X72000Y1296350D01*
X72333Y1296767D01*
X72833Y1297100D01*
X73417Y1297183D01*
X73917Y1297100D01*
X74417Y1296767D01*
X74833Y1296267D01*
X75000Y1295683D01*
X74833Y1295017D01*
X74333Y1294433D01*
X73583Y1294100D01*
X72750Y1294017D01*
X71667Y1294183D01*
X71083Y1294433D01*
X70500Y1294850D01*
X70083Y1295433D01*
X70000Y1296017D01*
X70167Y1296600D01*
X70583Y1297017D01*
G01X75000Y1302200D02*
X70000D01*
X73583Y1299117D01*
Y1303283D01*
G01X70000Y1304300D02*
X75000Y1305467D01*
X70000Y1306800D01*
X75000Y1308133D01*
X70000Y1309300D01*
G01Y1312400D02*
X70167Y1311733D01*
X70583Y1311233D01*
X71083Y1310900D01*
X71750Y1310650D01*
X72500Y1310567D01*
X73250Y1310650D01*
X73917Y1310900D01*
X74417Y1311233D01*
X74833Y1311733D01*
X75000Y1312400D01*
X74833Y1313067D01*
X74417Y1313567D01*
X73917Y1313900D01*
X73250Y1314150D01*
X72500Y1314233D01*
X71750Y1314150D01*
X71083Y1313900D01*
X70583Y1313567D01*
X70167Y1313067D01*
X70000Y1312400D01*
G01X75000Y1319000D02*
X70000D01*
X73583Y1315917D01*
Y1320083D01*
G01X75167Y1323600D02*
X75083Y1323433D01*
X74917D01*
X74833Y1323600D01*
X74917Y1323767D01*
X75083D01*
X75167Y1323600D01*
G01X70000Y1329200D02*
X70167Y1328533D01*
X70583Y1328033D01*
X71083Y1327700D01*
X71750Y1327450D01*
X72500Y1327367D01*
X73250Y1327450D01*
X73917Y1327700D01*
X74417Y1328033D01*
X74833Y1328533D01*
X75000Y1329200D01*
X74833Y1329867D01*
X74417Y1330367D01*
X73917Y1330700D01*
X73250Y1330950D01*
X72500Y1331033D01*
X71750Y1330950D01*
X71083Y1330700D01*
X70583Y1330367D01*
X70167Y1329867D01*
X70000Y1329200D01*
G01X70833Y1333217D02*
X70333Y1333717D01*
X70083Y1334300D01*
X70000Y1334967D01*
X70167Y1335800D01*
X70583Y1336383D01*
X71083Y1336550D01*
X71583Y1336467D01*
X72000Y1336133D01*
X72833Y1334467D01*
X73417Y1333717D01*
X74250Y1333217D01*
X75000Y1333050D01*
Y1336550D01*
G01Y1338317D02*
X70000Y1340400D01*
X75000Y1342483D01*
G01X73250Y1341733D02*
Y1339067D01*
G01X86000Y1277633D02*
X81000D01*
X85167Y1279800D01*
X81000Y1281967D01*
X86000D01*
G01Y1283317D02*
X81000Y1285400D01*
X86000Y1287483D01*
G01X84250Y1286733D02*
Y1284067D01*
G01X86000Y1289167D02*
X81000D01*
Y1290833D01*
X81250Y1291500D01*
X81583Y1292000D01*
X82083Y1292417D01*
X82667Y1292750D01*
X83500Y1292833D01*
X84333Y1292750D01*
X84917Y1292417D01*
X85417Y1292000D01*
X85750Y1291500D01*
X86000Y1290833D01*
Y1289167D01*
G01Y1298267D02*
Y1294933D01*
X81000D01*
Y1298267D01*
G01X83417Y1296933D02*
Y1294933D01*
G01X81000Y1306800D02*
Y1308800D01*
G01Y1307800D02*
X86000D01*
G01Y1306800D02*
Y1308800D01*
G01Y1311483D02*
X81000D01*
X86000Y1315317D01*
X81000D01*
G01Y1324600D02*
X86000D01*
G01X81000Y1322683D02*
Y1326517D01*
G01X86000Y1328117D02*
X81000Y1330200D01*
X86000Y1332283D01*
G01X84250Y1331533D02*
Y1328867D01*
G01X81000Y1334800D02*
Y1336800D01*
G01Y1335800D02*
X86000D01*
G01Y1334800D02*
Y1336800D01*
G01X81000Y1338900D02*
X86000Y1340067D01*
X81000Y1341400D01*
X86000Y1342733D01*
X81000Y1343900D01*
G01X86000Y1344917D02*
X81000Y1347000D01*
X86000Y1349083D01*
G01X84250Y1348333D02*
Y1345667D01*
G01X86000Y1350683D02*
X81000D01*
X86000Y1354517D01*
X81000D01*
G01X52500Y1277467D02*
X47500D01*
G01Y1280633D02*
X50583Y1277467D01*
G01X52500Y1281133D02*
X49167Y1278883D01*
G01X52500Y1282983D02*
X47500D01*
X52500Y1286817D01*
X47500D01*
G01X52500Y1290500D02*
X52417Y1289833D01*
X52083Y1289250D01*
X51583Y1288750D01*
X51000Y1288417D01*
X50333Y1288250D01*
X49667D01*
X49000Y1288417D01*
X48417Y1288750D01*
X47917Y1289250D01*
X47583Y1289833D01*
X47500Y1290500D01*
X47583Y1291167D01*
X47917Y1291750D01*
X48417Y1292250D01*
X49000Y1292583D01*
X49667Y1292750D01*
X50333D01*
X51000Y1292583D01*
X51583Y1292250D01*
X52083Y1291750D01*
X52417Y1291167D01*
X52500Y1290500D01*
G01Y1294350D02*
X47500Y1297850D01*
G01Y1294350D02*
X52500Y1297850D01*
G01X54167Y1299200D02*
Y1304200D01*
G01X52500Y1305717D02*
X47500D01*
Y1308883D01*
G01X49917Y1307717D02*
Y1305717D01*
G01X52500Y1310817D02*
X47500Y1312900D01*
X52500Y1314983D01*
G01X50750Y1314233D02*
Y1311567D01*
G01X52500Y1316583D02*
X47500D01*
X52500Y1320417D01*
X47500D01*
G01X47917Y1331533D02*
X47667Y1331033D01*
X47500Y1330450D01*
Y1329783D01*
X47750Y1329033D01*
X48167Y1328450D01*
X48667Y1328033D01*
X49500Y1327700D01*
X50250Y1327617D01*
X51000Y1327783D01*
X51500Y1328033D01*
X52000Y1328533D01*
X52333Y1329117D01*
X52500Y1329700D01*
Y1330283D01*
X52333Y1330867D01*
X52083Y1331367D01*
X51750Y1331783D01*
G01X52500Y1335300D02*
X52417Y1334633D01*
X52083Y1334050D01*
X51583Y1333550D01*
X51000Y1333217D01*
X50333Y1333050D01*
X49667D01*
X49000Y1333217D01*
X48417Y1333550D01*
X47917Y1334050D01*
X47583Y1334633D01*
X47500Y1335300D01*
X47583Y1335967D01*
X47917Y1336550D01*
X48417Y1337050D01*
X49000Y1337383D01*
X49667Y1337550D01*
X50333D01*
X51000Y1337383D01*
X51583Y1337050D01*
X52083Y1336550D01*
X52417Y1335967D01*
X52500Y1335300D01*
G01Y1338983D02*
X47500D01*
X52500Y1342817D01*
X47500D01*
G01Y1346500D02*
X52500D01*
G01X47500Y1344583D02*
Y1348417D01*
G01X52500Y1350433D02*
X47500D01*
Y1352517D01*
X47750Y1353183D01*
X48083Y1353600D01*
X48750Y1353767D01*
X49417Y1353600D01*
X49833Y1353100D01*
X50083Y1352517D01*
Y1350433D01*
G01Y1352517D02*
X52500Y1353767D01*
G01Y1357700D02*
X52417Y1357033D01*
X52083Y1356450D01*
X51583Y1355950D01*
X51000Y1355617D01*
X50333Y1355450D01*
X49667D01*
X49000Y1355617D01*
X48417Y1355950D01*
X47917Y1356450D01*
X47583Y1357033D01*
X47500Y1357700D01*
X47583Y1358367D01*
X47917Y1358950D01*
X48417Y1359450D01*
X49000Y1359783D01*
X49667Y1359950D01*
X50333D01*
X51000Y1359783D01*
X51583Y1359450D01*
X52083Y1358950D01*
X52417Y1358367D01*
X52500Y1357700D01*
G01X47500Y1361633D02*
X52500D01*
Y1364967D01*
G01X49833Y1375167D02*
X49583Y1375500D01*
X49167Y1375750D01*
X48583Y1375917D01*
X48083Y1375750D01*
X47750Y1375417D01*
X47500Y1374833D01*
Y1372583D01*
X52500D01*
Y1375333D01*
X52167Y1375917D01*
X51667Y1376250D01*
X51083Y1376417D01*
X50500Y1376250D01*
X50000Y1375750D01*
X49833Y1375167D01*
Y1372583D01*
G01X52500Y1380100D02*
X52417Y1379433D01*
X52083Y1378850D01*
X51583Y1378350D01*
X51000Y1378017D01*
X50333Y1377850D01*
X49667D01*
X49000Y1378017D01*
X48417Y1378350D01*
X47917Y1378850D01*
X47583Y1379433D01*
X47500Y1380100D01*
X47583Y1380767D01*
X47917Y1381350D01*
X48417Y1381850D01*
X49000Y1382183D01*
X49667Y1382350D01*
X50333D01*
X51000Y1382183D01*
X51583Y1381850D01*
X52083Y1381350D01*
X52417Y1380767D01*
X52500Y1380100D01*
G01Y1383617D02*
X47500Y1385700D01*
X52500Y1387783D01*
G01X50750Y1387033D02*
Y1384367D01*
G01X52500Y1389633D02*
X47500D01*
Y1391717D01*
X47750Y1392383D01*
X48083Y1392800D01*
X48750Y1392967D01*
X49417Y1392800D01*
X49833Y1392300D01*
X50083Y1391717D01*
Y1389633D01*
G01Y1391717D02*
X52500Y1392967D01*
G01Y1395067D02*
X47500D01*
Y1396733D01*
X47750Y1397400D01*
X48083Y1397900D01*
X48583Y1398317D01*
X49167Y1398650D01*
X50000Y1398733D01*
X50833Y1398650D01*
X51417Y1398317D01*
X51917Y1397900D01*
X52250Y1397400D01*
X52500Y1396733D01*
Y1395067D01*
G01X64500Y1278300D02*
X59500D01*
X60500Y1277300D01*
G01X64500D02*
Y1279300D01*
G01X60333Y1282317D02*
X59833Y1282817D01*
X59583Y1283400D01*
X59500Y1284067D01*
X59667Y1284900D01*
X60083Y1285483D01*
X60583Y1285650D01*
X61083Y1285567D01*
X61500Y1285233D01*
X62333Y1283567D01*
X62917Y1282817D01*
X63750Y1282317D01*
X64500Y1282150D01*
Y1285650D01*
G01Y1290500D02*
X59500D01*
X63083Y1287417D01*
Y1291583D01*
G01X63500Y1293267D02*
X64083Y1293767D01*
X64417Y1294433D01*
X64500Y1295183D01*
X64417Y1295850D01*
X64000Y1296517D01*
X63500Y1296933D01*
X63000Y1297017D01*
X62417Y1296850D01*
X62000Y1296267D01*
X61833Y1295683D01*
Y1294933D01*
G01Y1295683D02*
X61583Y1296183D01*
X61167Y1296600D01*
X60667Y1296767D01*
X60167Y1296600D01*
X59750Y1296183D01*
X59500Y1295433D01*
X59583Y1294683D01*
X59917Y1293933D01*
G01X63500Y1298867D02*
X64083Y1299367D01*
X64417Y1300033D01*
X64500Y1300783D01*
X64417Y1301450D01*
X64000Y1302117D01*
X63500Y1302533D01*
X63000Y1302617D01*
X62417Y1302450D01*
X62000Y1301867D01*
X61833Y1301283D01*
Y1300533D01*
G01Y1301283D02*
X61583Y1301783D01*
X61167Y1302200D01*
X60667Y1302367D01*
X60167Y1302200D01*
X59750Y1301783D01*
X59500Y1301033D01*
X59583Y1300283D01*
X59917Y1299533D01*
G01X62833Y1305217D02*
Y1307383D01*
G01X60333Y1310317D02*
X59833Y1310817D01*
X59583Y1311400D01*
X59500Y1312067D01*
X59667Y1312900D01*
X60083Y1313483D01*
X60583Y1313650D01*
X61083Y1313567D01*
X61500Y1313233D01*
X62333Y1311567D01*
X62917Y1310817D01*
X63750Y1310317D01*
X64500Y1310150D01*
Y1313650D01*
G01Y1315417D02*
X59500Y1317500D01*
X64500Y1319583D01*
G01X62750Y1318833D02*
Y1316167D01*
G01X83500Y1414567D02*
X81000D01*
Y1415567D01*
X81125Y1415900D01*
X81417Y1416150D01*
X81750Y1416233D01*
X82083Y1416150D01*
X82333Y1415942D01*
X82458Y1415567D01*
Y1414567D01*
G01X83500Y1417667D02*
X81000D01*
Y1418708D01*
X81125Y1419042D01*
X81292Y1419250D01*
X81625Y1419333D01*
X81958Y1419250D01*
X82167Y1419000D01*
X82292Y1418708D01*
Y1417667D01*
G01Y1418708D02*
X83500Y1419333D01*
G01X83208Y1420892D02*
X83417Y1421183D01*
X83500Y1421517D01*
X83417Y1421850D01*
X83167Y1422142D01*
X82792Y1422350D01*
X82417Y1422433D01*
X81958D01*
X81583Y1422350D01*
X81250Y1422142D01*
X81083Y1421892D01*
X81000Y1421600D01*
X81083Y1421267D01*
X81250Y1421017D01*
X81500Y1420850D01*
X81833Y1420767D01*
X82125Y1420850D01*
X82417Y1421058D01*
X82583Y1421308D01*
X82625Y1421600D01*
X82542Y1421933D01*
X82333Y1422183D01*
X81958Y1422433D01*
G01X75500Y1414567D02*
X73000D01*
Y1415567D01*
X73125Y1415900D01*
X73417Y1416150D01*
X73750Y1416233D01*
X74083Y1416150D01*
X74333Y1415942D01*
X74458Y1415567D01*
Y1414567D01*
G01X75500Y1417667D02*
X73000D01*
Y1418708D01*
X73125Y1419042D01*
X73292Y1419250D01*
X73625Y1419333D01*
X73958Y1419250D01*
X74167Y1419000D01*
X74292Y1418708D01*
Y1417667D01*
G01Y1418708D02*
X75500Y1419333D01*
G01X75125Y1420683D02*
X75333Y1420933D01*
X75458Y1421225D01*
X75500Y1421600D01*
X75417Y1421975D01*
X75250Y1422267D01*
X74958Y1422475D01*
X74625Y1422517D01*
X74292Y1422433D01*
X74083Y1422225D01*
X73917Y1421933D01*
X73875Y1421642D01*
X73917Y1421350D01*
X74083Y1420975D01*
X73000Y1421100D01*
Y1422225D01*
G01X87500Y1414567D02*
X85000D01*
Y1415567D01*
X85125Y1415900D01*
X85417Y1416150D01*
X85750Y1416233D01*
X86083Y1416150D01*
X86333Y1415942D01*
X86458Y1415567D01*
Y1414567D01*
G01X87500Y1417667D02*
X85000D01*
Y1418708D01*
X85125Y1419042D01*
X85292Y1419250D01*
X85625Y1419333D01*
X85958Y1419250D01*
X86167Y1419000D01*
X86292Y1418708D01*
Y1417667D01*
G01Y1418708D02*
X87500Y1419333D01*
G01Y1421600D02*
X85000D01*
X85500Y1421100D01*
G01X87500D02*
Y1422100D01*
G01Y1424700D02*
X85000D01*
X85500Y1424200D01*
G01X87500D02*
Y1425200D01*
G01X86458Y1427008D02*
X86167Y1427300D01*
X86000Y1427550D01*
X85917Y1427883D01*
X86000Y1428175D01*
X86167Y1428383D01*
X86417Y1428550D01*
X86708Y1428592D01*
X86958Y1428550D01*
X87208Y1428383D01*
X87417Y1428133D01*
X87500Y1427842D01*
X87417Y1427508D01*
X87167Y1427217D01*
X86792Y1427050D01*
X86375Y1427008D01*
X85833Y1427092D01*
X85542Y1427217D01*
X85250Y1427425D01*
X85042Y1427717D01*
X85000Y1428008D01*
X85083Y1428300D01*
X85292Y1428508D01*
G01X79500Y1414567D02*
X77000D01*
Y1415567D01*
X77125Y1415900D01*
X77417Y1416150D01*
X77750Y1416233D01*
X78083Y1416150D01*
X78333Y1415942D01*
X78458Y1415567D01*
Y1414567D01*
G01X79500Y1417667D02*
X77000D01*
Y1418708D01*
X77125Y1419042D01*
X77292Y1419250D01*
X77625Y1419333D01*
X77958Y1419250D01*
X78167Y1419000D01*
X78292Y1418708D01*
Y1417667D01*
G01Y1418708D02*
X79500Y1419333D01*
G01Y1421600D02*
X77000D01*
X77500Y1421100D01*
G01X79500D02*
Y1422100D01*
G01Y1424700D02*
X77000D01*
X77500Y1424200D01*
G01X79500D02*
Y1425200D01*
G01X71817Y1407200D02*
Y1409700D01*
X72858D01*
X73192Y1409575D01*
X73400Y1409408D01*
X73483Y1409075D01*
X73400Y1408742D01*
X73150Y1408533D01*
X72858Y1408408D01*
X71817D01*
G01X72858D02*
X73483Y1407200D01*
G01X74833Y1407700D02*
X75083Y1407408D01*
X75417Y1407242D01*
X75792Y1407200D01*
X76125Y1407242D01*
X76458Y1407450D01*
X76667Y1407700D01*
X76708Y1407950D01*
X76625Y1408242D01*
X76333Y1408450D01*
X76042Y1408533D01*
X75667D01*
G01X76042D02*
X76292Y1408658D01*
X76500Y1408867D01*
X76583Y1409117D01*
X76500Y1409367D01*
X76292Y1409575D01*
X75917Y1409700D01*
X75542Y1409658D01*
X75167Y1409492D01*
G01X78058Y1408242D02*
X78350Y1408533D01*
X78600Y1408700D01*
X78933Y1408783D01*
X79225Y1408700D01*
X79433Y1408533D01*
X79600Y1408283D01*
X79642Y1407992D01*
X79600Y1407742D01*
X79433Y1407492D01*
X79183Y1407283D01*
X78892Y1407200D01*
X78558Y1407283D01*
X78267Y1407533D01*
X78100Y1407908D01*
X78058Y1408325D01*
X78142Y1408867D01*
X78267Y1409158D01*
X78475Y1409450D01*
X78767Y1409658D01*
X79058Y1409700D01*
X79350Y1409617D01*
X79558Y1409408D01*
G01X81867Y1407200D02*
X81950Y1407742D01*
X82075Y1408200D01*
X82242Y1408617D01*
X82450Y1409075D01*
X82783Y1409700D01*
X81117D01*
G01X84817Y1407200D02*
Y1409700D01*
X85858D01*
X86192Y1409575D01*
X86400Y1409408D01*
X86483Y1409075D01*
X86400Y1408742D01*
X86150Y1408533D01*
X85858Y1408408D01*
X84817D01*
G01X85858D02*
X86483Y1407200D01*
G01X87833Y1407700D02*
X88083Y1407408D01*
X88417Y1407242D01*
X88792Y1407200D01*
X89125Y1407242D01*
X89458Y1407450D01*
X89667Y1407700D01*
X89708Y1407950D01*
X89625Y1408242D01*
X89333Y1408450D01*
X89042Y1408533D01*
X88667D01*
G01X89042D02*
X89292Y1408658D01*
X89500Y1408867D01*
X89583Y1409117D01*
X89500Y1409367D01*
X89292Y1409575D01*
X88917Y1409700D01*
X88542Y1409658D01*
X88167Y1409492D01*
G01X91058Y1408242D02*
X91350Y1408533D01*
X91600Y1408700D01*
X91933Y1408783D01*
X92225Y1408700D01*
X92433Y1408533D01*
X92600Y1408283D01*
X92642Y1407992D01*
X92600Y1407742D01*
X92433Y1407492D01*
X92183Y1407283D01*
X91892Y1407200D01*
X91558Y1407283D01*
X91267Y1407533D01*
X91100Y1407908D01*
X91058Y1408325D01*
X91142Y1408867D01*
X91267Y1409158D01*
X91475Y1409450D01*
X91767Y1409658D01*
X92058Y1409700D01*
X92350Y1409617D01*
X92558Y1409408D01*
G01X94158Y1408242D02*
X94450Y1408533D01*
X94700Y1408700D01*
X95033Y1408783D01*
X95325Y1408700D01*
X95533Y1408533D01*
X95700Y1408283D01*
X95742Y1407992D01*
X95700Y1407742D01*
X95533Y1407492D01*
X95283Y1407283D01*
X94992Y1407200D01*
X94658Y1407283D01*
X94367Y1407533D01*
X94200Y1407908D01*
X94158Y1408325D01*
X94242Y1408867D01*
X94367Y1409158D01*
X94575Y1409450D01*
X94867Y1409658D01*
X95158Y1409700D01*
X95450Y1409617D01*
X95658Y1409408D01*
G01X78100Y1458967D02*
X75600D01*
Y1459967D01*
X75725Y1460300D01*
X76017Y1460550D01*
X76350Y1460633D01*
X76683Y1460550D01*
X76933Y1460342D01*
X77058Y1459967D01*
Y1458967D01*
G01X75808Y1463817D02*
X75683Y1463567D01*
X75600Y1463275D01*
Y1462942D01*
X75725Y1462567D01*
X75933Y1462275D01*
X76183Y1462067D01*
X76600Y1461900D01*
X76975Y1461858D01*
X77350Y1461942D01*
X77600Y1462067D01*
X77850Y1462317D01*
X78017Y1462608D01*
X78100Y1462900D01*
Y1463192D01*
X78017Y1463483D01*
X77892Y1463733D01*
X77725Y1463942D01*
G01X77808Y1465292D02*
X78017Y1465583D01*
X78100Y1465917D01*
X78017Y1466250D01*
X77767Y1466542D01*
X77392Y1466750D01*
X77017Y1466833D01*
X76558D01*
X76183Y1466750D01*
X75850Y1466542D01*
X75683Y1466292D01*
X75600Y1466000D01*
X75683Y1465667D01*
X75850Y1465417D01*
X76100Y1465250D01*
X76433Y1465167D01*
X76725Y1465250D01*
X77017Y1465458D01*
X77183Y1465708D01*
X77225Y1466000D01*
X77142Y1466333D01*
X76933Y1466583D01*
X76558Y1466833D01*
G01X72567Y1453900D02*
Y1456400D01*
X73567D01*
X73900Y1456275D01*
X74150Y1455983D01*
X74233Y1455650D01*
X74150Y1455317D01*
X73942Y1455067D01*
X73567Y1454942D01*
X72567D01*
G01X77417Y1456192D02*
X77167Y1456317D01*
X76875Y1456400D01*
X76542D01*
X76167Y1456275D01*
X75875Y1456067D01*
X75667Y1455817D01*
X75500Y1455400D01*
X75458Y1455025D01*
X75542Y1454650D01*
X75667Y1454400D01*
X75917Y1454150D01*
X76208Y1453983D01*
X76500Y1453900D01*
X76792D01*
X77083Y1453983D01*
X77333Y1454108D01*
X77542Y1454275D01*
G01X80100Y1453900D02*
Y1456400D01*
X78558Y1454608D01*
X80642D01*
G01X72017Y1449400D02*
Y1451900D01*
X73017D01*
X73350Y1451775D01*
X73600Y1451483D01*
X73683Y1451150D01*
X73600Y1450817D01*
X73392Y1450567D01*
X73017Y1450442D01*
X72017D01*
G01X75117Y1449400D02*
Y1451900D01*
X76158D01*
X76492Y1451775D01*
X76700Y1451608D01*
X76783Y1451275D01*
X76700Y1450942D01*
X76450Y1450733D01*
X76158Y1450608D01*
X75117D01*
G01X76158D02*
X76783Y1449400D01*
G01X78133Y1449900D02*
X78383Y1449608D01*
X78717Y1449442D01*
X79092Y1449400D01*
X79425Y1449442D01*
X79758Y1449650D01*
X79967Y1449900D01*
X80008Y1450150D01*
X79925Y1450442D01*
X79633Y1450650D01*
X79342Y1450733D01*
X78967D01*
G01X79342D02*
X79592Y1450858D01*
X79800Y1451067D01*
X79883Y1451317D01*
X79800Y1451567D01*
X79592Y1451775D01*
X79217Y1451900D01*
X78842Y1451858D01*
X78467Y1451692D01*
G01X81233Y1449775D02*
X81483Y1449567D01*
X81775Y1449442D01*
X82150Y1449400D01*
X82525Y1449483D01*
X82817Y1449650D01*
X83025Y1449942D01*
X83067Y1450275D01*
X82983Y1450608D01*
X82775Y1450817D01*
X82483Y1450983D01*
X82192Y1451025D01*
X81900Y1450983D01*
X81525Y1450817D01*
X81650Y1451900D01*
X82775D01*
G01X74200Y1458917D02*
X71700D01*
Y1459917D01*
X71825Y1460250D01*
X72117Y1460500D01*
X72450Y1460583D01*
X72783Y1460500D01*
X73033Y1460292D01*
X73158Y1459917D01*
Y1458917D01*
G01X74200Y1462017D02*
X71700D01*
Y1463058D01*
X71825Y1463392D01*
X71992Y1463600D01*
X72325Y1463683D01*
X72658Y1463600D01*
X72867Y1463350D01*
X72992Y1463058D01*
Y1462017D01*
G01Y1463058D02*
X74200Y1463683D01*
G01X73700Y1465033D02*
X73992Y1465283D01*
X74158Y1465617D01*
X74200Y1465992D01*
X74158Y1466325D01*
X73950Y1466658D01*
X73700Y1466867D01*
X73450Y1466908D01*
X73158Y1466825D01*
X72950Y1466533D01*
X72867Y1466242D01*
Y1465867D01*
G01Y1466242D02*
X72742Y1466492D01*
X72533Y1466700D01*
X72283Y1466783D01*
X72033Y1466700D01*
X71825Y1466492D01*
X71700Y1466117D01*
X71742Y1465742D01*
X71908Y1465367D01*
G01X73700Y1468133D02*
X73992Y1468383D01*
X74158Y1468717D01*
X74200Y1469092D01*
X74158Y1469425D01*
X73950Y1469758D01*
X73700Y1469967D01*
X73450Y1470008D01*
X73158Y1469925D01*
X72950Y1469633D01*
X72867Y1469342D01*
Y1468967D01*
G01Y1469342D02*
X72742Y1469592D01*
X72533Y1469800D01*
X72283Y1469883D01*
X72033Y1469800D01*
X71825Y1469592D01*
X71700Y1469217D01*
X71742Y1468842D01*
X71908Y1468467D01*
G01X85500Y1467200D02*
X81500D01*
Y1459800D01*
G01X75267Y1444800D02*
Y1447300D01*
X76267D01*
X76600Y1447175D01*
X76850Y1446883D01*
X76933Y1446550D01*
X76850Y1446217D01*
X76642Y1445967D01*
X76267Y1445842D01*
X75267D01*
G01X78367Y1444800D02*
Y1447300D01*
X79408D01*
X79742Y1447175D01*
X79950Y1447008D01*
X80033Y1446675D01*
X79950Y1446342D01*
X79700Y1446133D01*
X79408Y1446008D01*
X78367D01*
G01X79408D02*
X80033Y1444800D01*
G01X81383Y1445300D02*
X81633Y1445008D01*
X81967Y1444842D01*
X82342Y1444800D01*
X82675Y1444842D01*
X83008Y1445050D01*
X83217Y1445300D01*
X83258Y1445550D01*
X83175Y1445842D01*
X82883Y1446050D01*
X82592Y1446133D01*
X82217D01*
G01X82592D02*
X82842Y1446258D01*
X83050Y1446467D01*
X83133Y1446717D01*
X83050Y1446967D01*
X82842Y1447175D01*
X82467Y1447300D01*
X82092Y1447258D01*
X81717Y1447092D01*
G01X75267Y1437300D02*
Y1439800D01*
X76267D01*
X76600Y1439675D01*
X76850Y1439383D01*
X76933Y1439050D01*
X76850Y1438717D01*
X76642Y1438467D01*
X76267Y1438342D01*
X75267D01*
G01X78367Y1437300D02*
Y1439800D01*
X79408D01*
X79742Y1439675D01*
X79950Y1439508D01*
X80033Y1439175D01*
X79950Y1438842D01*
X79700Y1438633D01*
X79408Y1438508D01*
X78367D01*
G01X79408D02*
X80033Y1437300D01*
G01X82300D02*
Y1439800D01*
X81800Y1439300D01*
G01Y1437300D02*
X82800D01*
G01X75467Y1429700D02*
Y1432200D01*
X76467D01*
X76800Y1432075D01*
X77050Y1431783D01*
X77133Y1431450D01*
X77050Y1431117D01*
X76842Y1430867D01*
X76467Y1430742D01*
X75467D01*
G01X80317Y1431992D02*
X80067Y1432117D01*
X79775Y1432200D01*
X79442D01*
X79067Y1432075D01*
X78775Y1431867D01*
X78567Y1431617D01*
X78400Y1431200D01*
X78358Y1430825D01*
X78442Y1430450D01*
X78567Y1430200D01*
X78817Y1429950D01*
X79108Y1429783D01*
X79400Y1429700D01*
X79692D01*
X79983Y1429783D01*
X80233Y1429908D01*
X80442Y1430075D01*
G01X81583D02*
X81833Y1429867D01*
X82125Y1429742D01*
X82500Y1429700D01*
X82875Y1429783D01*
X83167Y1429950D01*
X83375Y1430242D01*
X83417Y1430575D01*
X83333Y1430908D01*
X83125Y1431117D01*
X82833Y1431283D01*
X82542Y1431325D01*
X82250Y1431283D01*
X81875Y1431117D01*
X82000Y1432200D01*
X83125D01*
G01X75267Y1433200D02*
Y1435700D01*
X76267D01*
X76600Y1435575D01*
X76850Y1435283D01*
X76933Y1434950D01*
X76850Y1434617D01*
X76642Y1434367D01*
X76267Y1434242D01*
X75267D01*
G01X80117Y1435492D02*
X79867Y1435617D01*
X79575Y1435700D01*
X79242D01*
X78867Y1435575D01*
X78575Y1435367D01*
X78367Y1435117D01*
X78200Y1434700D01*
X78158Y1434325D01*
X78242Y1433950D01*
X78367Y1433700D01*
X78617Y1433450D01*
X78908Y1433283D01*
X79200Y1433200D01*
X79492D01*
X79783Y1433283D01*
X80033Y1433408D01*
X80242Y1433575D01*
G01X81383Y1433700D02*
X81633Y1433408D01*
X81967Y1433242D01*
X82342Y1433200D01*
X82675Y1433242D01*
X83008Y1433450D01*
X83217Y1433700D01*
X83258Y1433950D01*
X83175Y1434242D01*
X82883Y1434450D01*
X82592Y1434533D01*
X82217D01*
G01X82592D02*
X82842Y1434658D01*
X83050Y1434867D01*
X83133Y1435117D01*
X83050Y1435367D01*
X82842Y1435575D01*
X82467Y1435700D01*
X82092Y1435658D01*
X81717Y1435492D01*
G01X76817Y1443492D02*
X76567Y1443617D01*
X76275Y1443700D01*
X75942D01*
X75567Y1443575D01*
X75275Y1443367D01*
X75067Y1443117D01*
X74900Y1442700D01*
X74858Y1442325D01*
X74942Y1441950D01*
X75067Y1441700D01*
X75317Y1441450D01*
X75608Y1441283D01*
X75900Y1441200D01*
X76192D01*
X76483Y1441283D01*
X76733Y1441408D01*
X76942Y1441575D01*
G01X78083D02*
X78333Y1441367D01*
X78625Y1441242D01*
X79000Y1441200D01*
X79375Y1441283D01*
X79667Y1441450D01*
X79875Y1441742D01*
X79917Y1442075D01*
X79833Y1442408D01*
X79625Y1442617D01*
X79333Y1442783D01*
X79042Y1442825D01*
X78750Y1442783D01*
X78375Y1442617D01*
X78500Y1443700D01*
X79625D01*
G01X82100Y1441200D02*
X82392Y1441242D01*
X82725Y1441367D01*
X82933Y1441575D01*
X83017Y1441867D01*
X82933Y1442158D01*
X82683Y1442408D01*
X82308Y1442533D01*
X81892D01*
X81642Y1442617D01*
X81433Y1442825D01*
X81350Y1443117D01*
X81475Y1443408D01*
X81767Y1443617D01*
X82100Y1443700D01*
X82433Y1443617D01*
X82725Y1443408D01*
X82850Y1443117D01*
X82767Y1442825D01*
X82558Y1442617D01*
X82308Y1442533D01*
X81892D01*
X81517Y1442408D01*
X81267Y1442158D01*
X81183Y1441867D01*
X81267Y1441575D01*
X81475Y1441367D01*
X81808Y1441242D01*
X82100Y1441200D01*
G01X64517Y1474500D02*
Y1477000D01*
X65517D01*
X65850Y1476875D01*
X66100Y1476583D01*
X66183Y1476250D01*
X66100Y1475917D01*
X65892Y1475667D01*
X65517Y1475542D01*
X64517D01*
G01X69367Y1476792D02*
X69117Y1476917D01*
X68825Y1477000D01*
X68492D01*
X68117Y1476875D01*
X67825Y1476667D01*
X67617Y1476417D01*
X67450Y1476000D01*
X67408Y1475625D01*
X67492Y1475250D01*
X67617Y1475000D01*
X67867Y1474750D01*
X68158Y1474583D01*
X68450Y1474500D01*
X68742D01*
X69033Y1474583D01*
X69283Y1474708D01*
X69492Y1474875D01*
G01X71550Y1474500D02*
Y1477000D01*
X71050Y1476500D01*
G01Y1474500D02*
X72050D01*
G01X74650Y1477000D02*
X74317Y1476917D01*
X74067Y1476708D01*
X73900Y1476458D01*
X73775Y1476125D01*
X73733Y1475750D01*
X73775Y1475375D01*
X73900Y1475042D01*
X74067Y1474792D01*
X74317Y1474583D01*
X74650Y1474500D01*
X74983Y1474583D01*
X75233Y1474792D01*
X75400Y1475042D01*
X75525Y1475375D01*
X75567Y1475750D01*
X75525Y1476125D01*
X75400Y1476458D01*
X75233Y1476708D01*
X74983Y1476917D01*
X74650Y1477000D01*
G01X69900Y1530300D02*
Y1519100D01*
G01Y1491900D02*
Y1503100D01*
G01X87900Y1491900D02*
X69900D01*
G01X70017Y1483500D02*
Y1486000D01*
X71017D01*
X71350Y1485875D01*
X71600Y1485583D01*
X71683Y1485250D01*
X71600Y1484917D01*
X71392Y1484667D01*
X71017Y1484542D01*
X70017D01*
G01X73117Y1483500D02*
Y1486000D01*
X74158D01*
X74492Y1485875D01*
X74700Y1485708D01*
X74783Y1485375D01*
X74700Y1485042D01*
X74450Y1484833D01*
X74158Y1484708D01*
X73117D01*
G01X74158D02*
X74783Y1483500D01*
G01X76133Y1484000D02*
X76383Y1483708D01*
X76717Y1483542D01*
X77092Y1483500D01*
X77425Y1483542D01*
X77758Y1483750D01*
X77967Y1484000D01*
X78008Y1484250D01*
X77925Y1484542D01*
X77633Y1484750D01*
X77342Y1484833D01*
X76967D01*
G01X77342D02*
X77592Y1484958D01*
X77800Y1485167D01*
X77883Y1485417D01*
X77800Y1485667D01*
X77592Y1485875D01*
X77217Y1486000D01*
X76842Y1485958D01*
X76467Y1485792D01*
G01X80650Y1483500D02*
Y1486000D01*
X79108Y1484208D01*
X81192D01*
G01X82300Y1486000D02*
Y1482000D01*
X89700D01*
G01X78750Y1571400D02*
Y1601400D01*
G01X57050Y1571400D02*
X78750D01*
G01X57050Y1601400D02*
Y1571400D01*
G01X78350Y1538000D02*
Y1535500D01*
G01X77392Y1538000D02*
X79308D01*
G01X82367Y1537792D02*
X82117Y1537917D01*
X81825Y1538000D01*
X81492D01*
X81117Y1537875D01*
X80825Y1537667D01*
X80617Y1537417D01*
X80450Y1537000D01*
X80408Y1536625D01*
X80492Y1536250D01*
X80617Y1536000D01*
X80867Y1535750D01*
X81158Y1535583D01*
X81450Y1535500D01*
X81742D01*
X82033Y1535583D01*
X82283Y1535708D01*
X82492Y1535875D01*
G01X84550Y1535500D02*
Y1538000D01*
X84050Y1537500D01*
G01Y1535500D02*
X85050D01*
G01X87650D02*
Y1538000D01*
X87150Y1537500D01*
G01Y1535500D02*
X88150D01*
G01X87900Y1530300D02*
X69900D01*
G01X73600Y1545250D02*
X76100D01*
G01X73600Y1544292D02*
Y1546208D01*
G01X73808Y1549267D02*
X73683Y1549017D01*
X73600Y1548725D01*
Y1548392D01*
X73725Y1548017D01*
X73933Y1547725D01*
X74183Y1547517D01*
X74600Y1547350D01*
X74975Y1547308D01*
X75350Y1547392D01*
X75600Y1547517D01*
X75850Y1547767D01*
X76017Y1548058D01*
X76100Y1548350D01*
Y1548642D01*
X76017Y1548933D01*
X75892Y1549183D01*
X75725Y1549392D01*
G01X76100Y1551450D02*
X73600D01*
X74100Y1550950D01*
G01X76100D02*
Y1551950D01*
G01X74017Y1553758D02*
X73767Y1554008D01*
X73642Y1554300D01*
X73600Y1554633D01*
X73683Y1555050D01*
X73892Y1555342D01*
X74142Y1555425D01*
X74392Y1555383D01*
X74600Y1555217D01*
X75017Y1554383D01*
X75308Y1554008D01*
X75725Y1553758D01*
X76100Y1553675D01*
Y1555425D01*
G01X68200Y1560500D02*
X57000D01*
G01X68200Y1542500D02*
Y1560500D01*
G01X57000Y1542500D02*
X68200D01*
G01X71517Y1603000D02*
Y1605500D01*
X72517D01*
X72850Y1605375D01*
X73100Y1605083D01*
X73183Y1604750D01*
X73100Y1604417D01*
X72892Y1604167D01*
X72517Y1604042D01*
X71517D01*
G01X75450Y1603000D02*
X75117Y1603042D01*
X74825Y1603208D01*
X74575Y1603458D01*
X74408Y1603750D01*
X74325Y1604083D01*
Y1604417D01*
X74408Y1604750D01*
X74575Y1605042D01*
X74825Y1605292D01*
X75117Y1605458D01*
X75450Y1605500D01*
X75783Y1605458D01*
X76075Y1605292D01*
X76325Y1605042D01*
X76492Y1604750D01*
X76575Y1604417D01*
Y1604083D01*
X76492Y1603750D01*
X76325Y1603458D01*
X76075Y1603208D01*
X75783Y1603042D01*
X75450Y1603000D01*
G01X75783Y1603667D02*
X76283Y1603000D01*
G01X78550D02*
Y1605500D01*
X78050Y1605000D01*
G01Y1603000D02*
X79050D01*
G01X80733Y1603500D02*
X80983Y1603208D01*
X81317Y1603042D01*
X81692Y1603000D01*
X82025Y1603042D01*
X82358Y1603250D01*
X82567Y1603500D01*
X82608Y1603750D01*
X82525Y1604042D01*
X82233Y1604250D01*
X81942Y1604333D01*
X81567D01*
G01X81942D02*
X82192Y1604458D01*
X82400Y1604667D01*
X82483Y1604917D01*
X82400Y1605167D01*
X82192Y1605375D01*
X81817Y1605500D01*
X81442Y1605458D01*
X81067Y1605292D01*
G01X78750Y1601400D02*
X57050D01*
G01X85500Y1611017D02*
X83000D01*
Y1612017D01*
X83125Y1612350D01*
X83417Y1612600D01*
X83750Y1612683D01*
X84083Y1612600D01*
X84333Y1612392D01*
X84458Y1612017D01*
Y1611017D01*
G01X85500Y1614117D02*
X83000D01*
Y1615158D01*
X83125Y1615492D01*
X83292Y1615700D01*
X83625Y1615783D01*
X83958Y1615700D01*
X84167Y1615450D01*
X84292Y1615158D01*
Y1614117D01*
G01Y1615158D02*
X85500Y1615783D01*
G01X83417Y1617258D02*
X83167Y1617508D01*
X83042Y1617800D01*
X83000Y1618133D01*
X83083Y1618550D01*
X83292Y1618842D01*
X83542Y1618925D01*
X83792Y1618883D01*
X84000Y1618717D01*
X84417Y1617883D01*
X84708Y1617508D01*
X85125Y1617258D01*
X85500Y1617175D01*
Y1618925D01*
G01X85208Y1620442D02*
X85417Y1620733D01*
X85500Y1621067D01*
X85417Y1621400D01*
X85167Y1621692D01*
X84792Y1621900D01*
X84417Y1621983D01*
X83958D01*
X83583Y1621900D01*
X83250Y1621692D01*
X83083Y1621442D01*
X83000Y1621150D01*
X83083Y1620817D01*
X83250Y1620567D01*
X83500Y1620400D01*
X83833Y1620317D01*
X84125Y1620400D01*
X84417Y1620608D01*
X84583Y1620858D01*
X84625Y1621150D01*
X84542Y1621483D01*
X84333Y1621733D01*
X83958Y1621983D01*
G01X65750Y1610000D02*
Y1623000D01*
X81250D01*
Y1610000D01*
X65750D01*
G01X41976Y1654969D02*
X39476D01*
Y1656010D01*
X39601Y1656344D01*
X39768Y1656552D01*
X40101Y1656635D01*
X40434Y1656552D01*
X40643Y1656302D01*
X40768Y1656010D01*
Y1654969D01*
G01Y1656010D02*
X41976Y1656635D01*
G01Y1658902D02*
X39476D01*
X39976Y1658402D01*
G01X41976D02*
Y1659402D01*
G01Y1662002D02*
X39476D01*
X39976Y1661502D01*
G01X41976D02*
Y1662502D01*
G01X41684Y1664394D02*
X41893Y1664685D01*
X41976Y1665019D01*
X41893Y1665352D01*
X41643Y1665644D01*
X41268Y1665852D01*
X40893Y1665935D01*
X40434D01*
X40059Y1665852D01*
X39726Y1665644D01*
X39559Y1665394D01*
X39476Y1665102D01*
X39559Y1664769D01*
X39726Y1664519D01*
X39976Y1664352D01*
X40309Y1664269D01*
X40601Y1664352D01*
X40893Y1664560D01*
X41059Y1664810D01*
X41101Y1665102D01*
X41018Y1665435D01*
X40809Y1665685D01*
X40434Y1665935D01*
G01X44700Y1643550D02*
X44658Y1643217D01*
X44492Y1642925D01*
X44242Y1642675D01*
X43950Y1642508D01*
X43617Y1642425D01*
X43283D01*
X42950Y1642508D01*
X42658Y1642675D01*
X42408Y1642925D01*
X42242Y1643217D01*
X42200Y1643550D01*
X42242Y1643883D01*
X42408Y1644175D01*
X42658Y1644425D01*
X42950Y1644592D01*
X43283Y1644675D01*
X43617D01*
X43950Y1644592D01*
X44242Y1644425D01*
X44492Y1644175D01*
X44658Y1643883D01*
X44700Y1643550D01*
G01X44033Y1643883D02*
X44700Y1644383D01*
G01Y1646567D02*
X44158Y1646650D01*
X43700Y1646775D01*
X43283Y1646942D01*
X42825Y1647150D01*
X42200Y1647483D01*
Y1645817D01*
G01X38000Y1638300D02*
Y1652300D01*
G01X44067Y1695000D02*
Y1697500D01*
X45067D01*
X45400Y1697375D01*
X45650Y1697083D01*
X45733Y1696750D01*
X45650Y1696417D01*
X45442Y1696167D01*
X45067Y1696042D01*
X44067D01*
G01X47083Y1695000D02*
Y1697500D01*
X47917D01*
X48250Y1697375D01*
X48500Y1697208D01*
X48708Y1696958D01*
X48875Y1696667D01*
X48917Y1696250D01*
X48875Y1695833D01*
X48708Y1695542D01*
X48500Y1695292D01*
X48250Y1695125D01*
X47917Y1695000D01*
X47083D01*
G01X50308Y1697083D02*
X50558Y1697333D01*
X50850Y1697458D01*
X51183Y1697500D01*
X51600Y1697417D01*
X51892Y1697208D01*
X51975Y1696958D01*
X51933Y1696708D01*
X51767Y1696500D01*
X50933Y1696083D01*
X50558Y1695792D01*
X50308Y1695375D01*
X50225Y1695000D01*
X51975D01*
G01X124407Y1688975D02*
X68507D01*
Y1857875D01*
X124407D01*
Y1784512D01*
X119095D01*
G03Y1773126I0J-5693D01*
G01X124407D01*
Y1688975D01*
G01X38800Y1734917D02*
X41300D01*
Y1736583D01*
G01Y1739683D02*
Y1738017D01*
X38800D01*
Y1739683D01*
G01X40008Y1739017D02*
Y1738017D01*
G01X41300Y1741033D02*
X38800D01*
Y1741867D01*
X38925Y1742200D01*
X39092Y1742450D01*
X39342Y1742658D01*
X39633Y1742825D01*
X40050Y1742867D01*
X40467Y1742825D01*
X40758Y1742658D01*
X41008Y1742450D01*
X41175Y1742200D01*
X41300Y1741867D01*
Y1741033D01*
G01Y1745050D02*
X38800D01*
X39300Y1744550D01*
G01X41300D02*
Y1745550D01*
G01X58797Y1741981D02*
X56297D01*
Y1742815D01*
X56422Y1743148D01*
X56589Y1743398D01*
X56839Y1743606D01*
X57130Y1743773D01*
X57547Y1743815D01*
X57964Y1743773D01*
X58255Y1743606D01*
X58505Y1743398D01*
X58672Y1743148D01*
X58797Y1742815D01*
Y1741981D01*
G01Y1745998D02*
X56297D01*
X56797Y1745498D01*
G01X58797D02*
Y1746498D01*
G01X56714Y1748306D02*
X56464Y1748556D01*
X56339Y1748848D01*
X56297Y1749181D01*
X56380Y1749598D01*
X56589Y1749890D01*
X56839Y1749973D01*
X57089Y1749931D01*
X57297Y1749765D01*
X57714Y1748931D01*
X58005Y1748556D01*
X58422Y1748306D01*
X58797Y1748223D01*
Y1749973D01*
G01X45600Y1750400D02*
Y1771400D01*
G01D02*
X37600D01*
G01D02*
Y1750400D01*
G01D02*
X45600D01*
G01X38500Y1777000D02*
Y1785000D01*
G01X55617Y1755800D02*
Y1758300D01*
X56658D01*
X56992Y1758175D01*
X57200Y1758008D01*
X57283Y1757675D01*
X57200Y1757342D01*
X56950Y1757133D01*
X56658Y1757008D01*
X55617D01*
G01X56658D02*
X57283Y1755800D01*
G01X59550D02*
Y1758300D01*
X59050Y1757800D01*
G01Y1755800D02*
X60050D01*
G01X62650Y1758300D02*
X62317Y1758217D01*
X62067Y1758008D01*
X61900Y1757758D01*
X61775Y1757425D01*
X61733Y1757050D01*
X61775Y1756675D01*
X61900Y1756342D01*
X62067Y1756092D01*
X62317Y1755883D01*
X62650Y1755800D01*
X62983Y1755883D01*
X63233Y1756092D01*
X63400Y1756342D01*
X63525Y1756675D01*
X63567Y1757050D01*
X63525Y1757425D01*
X63400Y1757758D01*
X63233Y1758008D01*
X62983Y1758217D01*
X62650Y1758300D01*
G01X65750Y1755800D02*
Y1758300D01*
X65250Y1757800D01*
G01Y1755800D02*
X66250D01*
G01X63602Y1741964D02*
X61102D01*
Y1743005D01*
X61227Y1743339D01*
X61394Y1743547D01*
X61727Y1743630D01*
X62060Y1743547D01*
X62269Y1743297D01*
X62394Y1743005D01*
Y1741964D01*
G01Y1743005D02*
X63602Y1743630D01*
G01X63310Y1745189D02*
X63519Y1745480D01*
X63602Y1745814D01*
X63519Y1746147D01*
X63269Y1746439D01*
X62894Y1746647D01*
X62519Y1746730D01*
X62060D01*
X61685Y1746647D01*
X61352Y1746439D01*
X61185Y1746189D01*
X61102Y1745897D01*
X61185Y1745564D01*
X61352Y1745314D01*
X61602Y1745147D01*
X61935Y1745064D01*
X62227Y1745147D01*
X62519Y1745355D01*
X62685Y1745605D01*
X62727Y1745897D01*
X62644Y1746230D01*
X62435Y1746480D01*
X62060Y1746730D01*
G01X63602Y1748914D02*
X63060Y1748997D01*
X62602Y1749122D01*
X62185Y1749289D01*
X61727Y1749497D01*
X61102Y1749830D01*
Y1748164D01*
G01X46300Y1750300D02*
X50300D01*
Y1757700D01*
G01X44100Y1774917D02*
X41600D01*
Y1775958D01*
X41725Y1776292D01*
X41892Y1776500D01*
X42225Y1776583D01*
X42558Y1776500D01*
X42767Y1776250D01*
X42892Y1775958D01*
Y1774917D01*
G01Y1775958D02*
X44100Y1776583D01*
G01Y1778850D02*
X41600D01*
X42100Y1778350D01*
G01X44100D02*
Y1779350D01*
G01X41600Y1781950D02*
X41683Y1781617D01*
X41892Y1781367D01*
X42142Y1781200D01*
X42475Y1781075D01*
X42850Y1781033D01*
X43225Y1781075D01*
X43558Y1781200D01*
X43808Y1781367D01*
X44017Y1781617D01*
X44100Y1781950D01*
X44017Y1782283D01*
X43808Y1782533D01*
X43558Y1782700D01*
X43225Y1782825D01*
X42850Y1782867D01*
X42475Y1782825D01*
X42142Y1782700D01*
X41892Y1782533D01*
X41683Y1782283D01*
X41600Y1781950D01*
G01X43725Y1784133D02*
X43933Y1784383D01*
X44058Y1784675D01*
X44100Y1785050D01*
X44017Y1785425D01*
X43850Y1785717D01*
X43558Y1785925D01*
X43225Y1785967D01*
X42892Y1785883D01*
X42683Y1785675D01*
X42517Y1785383D01*
X42475Y1785092D01*
X42517Y1784800D01*
X42683Y1784425D01*
X41600Y1784550D01*
Y1785675D01*
G01X47400Y1771800D02*
Y1767800D01*
X54800D01*
G01X57817Y1753792D02*
X57567Y1753917D01*
X57275Y1754000D01*
X56942D01*
X56567Y1753875D01*
X56275Y1753667D01*
X56067Y1753417D01*
X55900Y1753000D01*
X55858Y1752625D01*
X55942Y1752250D01*
X56067Y1752000D01*
X56317Y1751750D01*
X56608Y1751583D01*
X56900Y1751500D01*
X57192D01*
X57483Y1751583D01*
X57733Y1751708D01*
X57942Y1751875D01*
G01X60500Y1751500D02*
Y1754000D01*
X58958Y1752208D01*
X61042D01*
G01X62308Y1752542D02*
X62600Y1752833D01*
X62850Y1753000D01*
X63183Y1753083D01*
X63475Y1753000D01*
X63683Y1752833D01*
X63850Y1752583D01*
X63892Y1752292D01*
X63850Y1752042D01*
X63683Y1751792D01*
X63433Y1751583D01*
X63142Y1751500D01*
X62808Y1751583D01*
X62517Y1751833D01*
X62350Y1752208D01*
X62308Y1752625D01*
X62392Y1753167D01*
X62517Y1753458D01*
X62725Y1753750D01*
X63017Y1753958D01*
X63308Y1754000D01*
X63600Y1753917D01*
X63808Y1753708D01*
G01X36967Y1792000D02*
Y1794500D01*
X38008D01*
X38342Y1794375D01*
X38550Y1794208D01*
X38633Y1793875D01*
X38550Y1793542D01*
X38300Y1793333D01*
X38008Y1793208D01*
X36967D01*
G01X38008D02*
X38633Y1792000D01*
G01X40192Y1792292D02*
X40483Y1792083D01*
X40817Y1792000D01*
X41150Y1792083D01*
X41442Y1792333D01*
X41650Y1792708D01*
X41733Y1793083D01*
Y1793542D01*
X41650Y1793917D01*
X41442Y1794250D01*
X41192Y1794417D01*
X40900Y1794500D01*
X40567Y1794417D01*
X40317Y1794250D01*
X40150Y1794000D01*
X40067Y1793667D01*
X40150Y1793375D01*
X40358Y1793083D01*
X40608Y1792917D01*
X40900Y1792875D01*
X41233Y1792958D01*
X41483Y1793167D01*
X41733Y1793542D01*
G01X43208Y1793042D02*
X43500Y1793333D01*
X43750Y1793500D01*
X44083Y1793583D01*
X44375Y1793500D01*
X44583Y1793333D01*
X44750Y1793083D01*
X44792Y1792792D01*
X44750Y1792542D01*
X44583Y1792292D01*
X44333Y1792083D01*
X44042Y1792000D01*
X43708Y1792083D01*
X43417Y1792333D01*
X43250Y1792708D01*
X43208Y1793125D01*
X43292Y1793667D01*
X43417Y1793958D01*
X43625Y1794250D01*
X43917Y1794458D01*
X44208Y1794500D01*
X44500Y1794417D01*
X44708Y1794208D01*
G01X79658Y1879000D02*
Y1881500D01*
X81242D01*
G01X80658Y1880292D02*
X79658D01*
G01X82758Y1880042D02*
X83050Y1880333D01*
X83300Y1880500D01*
X83633Y1880583D01*
X83925Y1880500D01*
X84133Y1880333D01*
X84300Y1880083D01*
X84342Y1879792D01*
X84300Y1879542D01*
X84133Y1879292D01*
X83883Y1879083D01*
X83592Y1879000D01*
X83258Y1879083D01*
X82967Y1879333D01*
X82800Y1879708D01*
X82758Y1880125D01*
X82842Y1880667D01*
X82967Y1880958D01*
X83175Y1881250D01*
X83467Y1881458D01*
X83758Y1881500D01*
X84050Y1881417D01*
X84258Y1881208D01*
G01X56500Y1912917D02*
X51500D01*
Y1916083D01*
G01X53917Y1914917D02*
Y1912917D01*
G01X54417Y1918517D02*
X53833Y1919100D01*
X53500Y1919600D01*
X53333Y1920267D01*
X53500Y1920850D01*
X53833Y1921267D01*
X54333Y1921600D01*
X54917Y1921683D01*
X55417Y1921600D01*
X55917Y1921267D01*
X56333Y1920767D01*
X56500Y1920183D01*
X56333Y1919517D01*
X55833Y1918933D01*
X55083Y1918600D01*
X54250Y1918517D01*
X53167Y1918683D01*
X52583Y1918933D01*
X52000Y1919350D01*
X51583Y1919933D01*
X51500Y1920517D01*
X51667Y1921100D01*
X52083Y1921517D01*
G01X56667Y1925700D02*
X56583Y1925533D01*
X56417D01*
X56333Y1925700D01*
X56417Y1925867D01*
X56583D01*
X56667Y1925700D01*
G01X54417D02*
X54333Y1925533D01*
X54167D01*
X54083Y1925700D01*
X54167Y1925867D01*
X54333D01*
X54417Y1925700D01*
G01X55500Y1929467D02*
X56083Y1929967D01*
X56417Y1930633D01*
X56500Y1931383D01*
X56417Y1932050D01*
X56000Y1932717D01*
X55500Y1933133D01*
X55000Y1933217D01*
X54417Y1933050D01*
X54000Y1932467D01*
X53833Y1931883D01*
Y1931133D01*
G01Y1931883D02*
X53583Y1932383D01*
X53167Y1932800D01*
X52667Y1932967D01*
X52167Y1932800D01*
X51750Y1932383D01*
X51500Y1931633D01*
X51583Y1930883D01*
X51917Y1930133D01*
G01X56500Y1934817D02*
X51500Y1936900D01*
X56500Y1938983D01*
G01X54750Y1938233D02*
Y1935567D01*
G01X56667Y1941000D02*
X51500Y1944000D01*
G01X56500Y1948100D02*
X51500D01*
X52500Y1947100D01*
G01X56500D02*
Y1949100D01*
G01X55750Y1951867D02*
X56167Y1952367D01*
X56417Y1952950D01*
X56500Y1953700D01*
X56333Y1954450D01*
X56000Y1955033D01*
X55417Y1955450D01*
X54750Y1955533D01*
X54083Y1955367D01*
X53667Y1954950D01*
X53333Y1954367D01*
X53250Y1953783D01*
X53333Y1953200D01*
X53667Y1952450D01*
X51500Y1952700D01*
Y1954950D01*
G01Y1957217D02*
X56500Y1959300D01*
X51500Y1961383D01*
G01X73000Y1892517D02*
X70500D01*
Y1893558D01*
X70625Y1893892D01*
X70792Y1894100D01*
X71125Y1894183D01*
X71458Y1894100D01*
X71667Y1893850D01*
X71792Y1893558D01*
Y1892517D01*
G01Y1893558D02*
X73000Y1894183D01*
G01Y1896450D02*
X70500D01*
X71000Y1895950D01*
G01X73000D02*
Y1896950D01*
G01Y1899467D02*
X72458Y1899550D01*
X72000Y1899675D01*
X71583Y1899842D01*
X71125Y1900050D01*
X70500Y1900383D01*
Y1898717D01*
G01X73000Y1902567D02*
X72458Y1902650D01*
X72000Y1902775D01*
X71583Y1902942D01*
X71125Y1903150D01*
X70500Y1903483D01*
Y1901817D01*
G01X76100Y1904700D02*
Y1887100D01*
G01X84100Y1904700D02*
X76100D01*
G01X84100Y1887100D02*
Y1904700D01*
G01X76100Y1887100D02*
X84100D01*
G01X105000Y97700D02*
Y74700D01*
G01X101500Y50033D02*
X99000D01*
Y50867D01*
X99125Y51200D01*
X99292Y51450D01*
X99542Y51658D01*
X99833Y51825D01*
X100250Y51867D01*
X100667Y51825D01*
X100958Y51658D01*
X101208Y51450D01*
X101375Y51200D01*
X101500Y50867D01*
Y50033D01*
G01X101000Y53133D02*
X101292Y53383D01*
X101458Y53717D01*
X101500Y54092D01*
X101458Y54425D01*
X101250Y54758D01*
X101000Y54967D01*
X100750Y55008D01*
X100458Y54925D01*
X100250Y54633D01*
X100167Y54342D01*
Y53967D01*
G01Y54342D02*
X100042Y54592D01*
X99833Y54800D01*
X99583Y54883D01*
X99333Y54800D01*
X99125Y54592D01*
X99000Y54217D01*
X99042Y53842D01*
X99208Y53467D01*
G01X95103Y50502D02*
Y58502D01*
G01X128000Y64533D02*
X125500D01*
Y65367D01*
X125625Y65700D01*
X125792Y65950D01*
X126042Y66158D01*
X126333Y66325D01*
X126750Y66367D01*
X127167Y66325D01*
X127458Y66158D01*
X127708Y65950D01*
X127875Y65700D01*
X128000Y65367D01*
Y64533D01*
G01Y68550D02*
X125500D01*
X126000Y68050D01*
G01X128000D02*
Y69050D01*
G01X113000Y72500D02*
X92000D01*
G01D02*
Y64500D01*
G01D02*
X113000D01*
G01D02*
Y72500D01*
G01X106300Y79500D02*
X117500D01*
G01X106300Y97500D02*
Y79500D01*
G01X144700D02*
X133500D01*
G01X96067Y60000D02*
Y62500D01*
X97108D01*
X97442Y62375D01*
X97650Y62208D01*
X97733Y61875D01*
X97650Y61542D01*
X97400Y61333D01*
X97108Y61208D01*
X96067D01*
G01X97108D02*
X97733Y60000D01*
G01X99917D02*
X100000Y60542D01*
X100125Y61000D01*
X100292Y61417D01*
X100500Y61875D01*
X100833Y62500D01*
X99167D01*
G01X102183Y60500D02*
X102433Y60208D01*
X102767Y60042D01*
X103142Y60000D01*
X103475Y60042D01*
X103808Y60250D01*
X104017Y60500D01*
X104058Y60750D01*
X103975Y61042D01*
X103683Y61250D01*
X103392Y61333D01*
X103017D01*
G01X103392D02*
X103642Y61458D01*
X103850Y61667D01*
X103933Y61917D01*
X103850Y62167D01*
X103642Y62375D01*
X103267Y62500D01*
X102892Y62458D01*
X102517Y62292D01*
G01X120000Y64567D02*
X117500D01*
Y65608D01*
X117625Y65942D01*
X117792Y66150D01*
X118125Y66233D01*
X118458Y66150D01*
X118667Y65900D01*
X118792Y65608D01*
Y64567D01*
G01Y65608D02*
X120000Y66233D01*
G01Y68417D02*
X119458Y68500D01*
X119000Y68625D01*
X118583Y68792D01*
X118125Y69000D01*
X117500Y69333D01*
Y67667D01*
G01X120000Y71600D02*
X117500D01*
X118000Y71100D01*
G01X120000D02*
Y72100D01*
G01X106067Y60000D02*
Y62500D01*
X107108D01*
X107442Y62375D01*
X107650Y62208D01*
X107733Y61875D01*
X107650Y61542D01*
X107400Y61333D01*
X107108Y61208D01*
X106067D01*
G01X107108D02*
X107733Y60000D01*
G01X109917D02*
X110000Y60542D01*
X110125Y61000D01*
X110292Y61417D01*
X110500Y61875D01*
X110833Y62500D01*
X109167D01*
G01X113017Y60000D02*
X113100Y60542D01*
X113225Y61000D01*
X113392Y61417D01*
X113600Y61875D01*
X113933Y62500D01*
X112267D01*
G01X86303Y63502D02*
Y59502D01*
X93703D01*
G01X124000Y64567D02*
X121500D01*
Y65608D01*
X121625Y65942D01*
X121792Y66150D01*
X122125Y66233D01*
X122458Y66150D01*
X122667Y65900D01*
X122792Y65608D01*
Y64567D01*
G01Y65608D02*
X124000Y66233D01*
G01Y68417D02*
X123458Y68500D01*
X123000Y68625D01*
X122583Y68792D01*
X122125Y69000D01*
X121500Y69333D01*
Y67667D01*
G01X123625Y70683D02*
X123833Y70933D01*
X123958Y71225D01*
X124000Y71600D01*
X123917Y71975D01*
X123750Y72267D01*
X123458Y72475D01*
X123125Y72517D01*
X122792Y72433D01*
X122583Y72225D01*
X122417Y71933D01*
X122375Y71642D01*
X122417Y71350D01*
X122583Y70975D01*
X121500Y71100D01*
Y72225D01*
G01X99158Y99000D02*
Y101500D01*
X100742D01*
G01X100158Y100292D02*
X99158D01*
G01X103050Y99000D02*
Y101500D01*
X102550Y101000D01*
G01Y99000D02*
X103550D01*
G01X117500Y97500D02*
X106300D01*
G01X133500D02*
X144700D01*
G01X134906Y340409D02*
X164306D01*
Y311909D01*
X194306D01*
Y136909D01*
X164306D01*
Y108409D01*
X134906D01*
Y340409D01*
G01X93017Y103500D02*
Y106000D01*
X94058D01*
X94392Y105875D01*
X94600Y105708D01*
X94683Y105375D01*
X94600Y105042D01*
X94350Y104833D01*
X94058Y104708D01*
X93017D01*
G01X94058D02*
X94683Y103500D01*
G01X96950D02*
Y106000D01*
X96450Y105500D01*
G01Y103500D02*
X97450D01*
G01X100050D02*
X100342Y103542D01*
X100675Y103667D01*
X100883Y103875D01*
X100967Y104167D01*
X100883Y104458D01*
X100633Y104708D01*
X100258Y104833D01*
X99842D01*
X99592Y104917D01*
X99383Y105125D01*
X99300Y105417D01*
X99425Y105708D01*
X99717Y105917D01*
X100050Y106000D01*
X100383Y105917D01*
X100675Y105708D01*
X100800Y105417D01*
X100717Y105125D01*
X100508Y104917D01*
X100258Y104833D01*
X99842D01*
X99467Y104708D01*
X99217Y104458D01*
X99133Y104167D01*
X99217Y103875D01*
X99425Y103667D01*
X99758Y103542D01*
X100050Y103500D01*
G01X102358Y105583D02*
X102608Y105833D01*
X102900Y105958D01*
X103233Y106000D01*
X103650Y105917D01*
X103942Y105708D01*
X104025Y105458D01*
X103983Y105208D01*
X103817Y105000D01*
X102983Y104583D01*
X102608Y104292D01*
X102358Y103875D01*
X102275Y103500D01*
X104025D01*
G01X90400Y99000D02*
Y107000D01*
G01X135893Y345292D02*
X135643Y345417D01*
X135351Y345500D01*
X135018D01*
X134643Y345375D01*
X134351Y345167D01*
X134143Y344917D01*
X133976Y344500D01*
X133934Y344125D01*
X134018Y343750D01*
X134143Y343500D01*
X134393Y343250D01*
X134684Y343083D01*
X134976Y343000D01*
X135268D01*
X135559Y343083D01*
X135809Y343208D01*
X136018Y343375D01*
G01X137118Y343000D02*
Y345500D01*
X139034Y343000D01*
Y345500D01*
G01X141176Y343000D02*
Y345500D01*
X140676Y345000D01*
G01Y343000D02*
X141676D01*
G01X144276Y345500D02*
X143943Y345417D01*
X143693Y345208D01*
X143526Y344958D01*
X143401Y344625D01*
X143359Y344250D01*
X143401Y343875D01*
X143526Y343542D01*
X143693Y343292D01*
X143943Y343083D01*
X144276Y343000D01*
X144609Y343083D01*
X144859Y343292D01*
X145026Y343542D01*
X145151Y343875D01*
X145193Y344250D01*
X145151Y344625D01*
X145026Y344958D01*
X144859Y345208D01*
X144609Y345417D01*
X144276Y345500D01*
G01X115400Y399500D02*
Y397000D01*
G01X114442Y399500D02*
X116358D01*
G01X119417Y399292D02*
X119167Y399417D01*
X118875Y399500D01*
X118542D01*
X118167Y399375D01*
X117875Y399167D01*
X117667Y398917D01*
X117500Y398500D01*
X117458Y398125D01*
X117542Y397750D01*
X117667Y397500D01*
X117917Y397250D01*
X118208Y397083D01*
X118500Y397000D01*
X118792D01*
X119083Y397083D01*
X119333Y397208D01*
X119542Y397375D01*
G01X122100Y397000D02*
Y399500D01*
X120558Y397708D01*
X122642D01*
G01X112700Y389500D02*
X101500D01*
G01X112700Y407500D02*
Y389500D01*
G01X101317Y381292D02*
X101067Y381417D01*
X100775Y381500D01*
X100442D01*
X100067Y381375D01*
X99775Y381167D01*
X99567Y380917D01*
X99400Y380500D01*
X99358Y380125D01*
X99442Y379750D01*
X99567Y379500D01*
X99817Y379250D01*
X100108Y379083D01*
X100400Y379000D01*
X100692D01*
X100983Y379083D01*
X101233Y379208D01*
X101442Y379375D01*
G01X102708Y381083D02*
X102958Y381333D01*
X103250Y381458D01*
X103583Y381500D01*
X104000Y381417D01*
X104292Y381208D01*
X104375Y380958D01*
X104333Y380708D01*
X104167Y380500D01*
X103333Y380083D01*
X102958Y379792D01*
X102708Y379375D01*
X102625Y379000D01*
X104375D01*
G01X107100D02*
Y381500D01*
X105558Y379708D01*
X107642D01*
G01X126483Y376500D02*
Y379000D01*
X127317D01*
X127650Y378875D01*
X127900Y378708D01*
X128108Y378458D01*
X128275Y378167D01*
X128317Y377750D01*
X128275Y377333D01*
X128108Y377042D01*
X127900Y376792D01*
X127650Y376625D01*
X127317Y376500D01*
X126483D01*
G01X130500D02*
Y379000D01*
X130000Y378500D01*
G01Y376500D02*
X131000D01*
G01X132808Y377542D02*
X133100Y377833D01*
X133350Y378000D01*
X133683Y378083D01*
X133975Y378000D01*
X134183Y377833D01*
X134350Y377583D01*
X134392Y377292D01*
X134350Y377042D01*
X134183Y376792D01*
X133933Y376583D01*
X133642Y376500D01*
X133308Y376583D01*
X133017Y376833D01*
X132850Y377208D01*
X132808Y377625D01*
X132892Y378167D01*
X133017Y378458D01*
X133225Y378750D01*
X133517Y378958D01*
X133808Y379000D01*
X134100Y378917D01*
X134308Y378708D01*
G01X145700Y349300D02*
X105500D01*
G01Y374300D02*
X145700D01*
G01X105500Y349300D02*
Y374300D01*
G01X104600Y374400D02*
Y349400D01*
G01X133967Y425100D02*
Y427600D01*
X134967D01*
X135300Y427475D01*
X135550Y427183D01*
X135633Y426850D01*
X135550Y426517D01*
X135342Y426267D01*
X134967Y426142D01*
X133967D01*
G01X137067Y425100D02*
Y427600D01*
X138108D01*
X138442Y427475D01*
X138650Y427308D01*
X138733Y426975D01*
X138650Y426642D01*
X138400Y426433D01*
X138108Y426308D01*
X137067D01*
G01X138108D02*
X138733Y425100D01*
G01X141000D02*
Y427600D01*
X140500Y427100D01*
G01Y425100D02*
X141500D01*
G01X144100Y427600D02*
X143767Y427517D01*
X143517Y427308D01*
X143350Y427058D01*
X143225Y426725D01*
X143183Y426350D01*
X143225Y425975D01*
X143350Y425642D01*
X143517Y425392D01*
X143767Y425183D01*
X144100Y425100D01*
X144433Y425183D01*
X144683Y425392D01*
X144850Y425642D01*
X144975Y425975D01*
X145017Y426350D01*
X144975Y426725D01*
X144850Y427058D01*
X144683Y427308D01*
X144433Y427517D01*
X144100Y427600D01*
G01X146283Y425600D02*
X146533Y425308D01*
X146867Y425142D01*
X147242Y425100D01*
X147575Y425142D01*
X147908Y425350D01*
X148117Y425600D01*
X148158Y425850D01*
X148075Y426142D01*
X147783Y426350D01*
X147492Y426433D01*
X147117D01*
G01X147492D02*
X147742Y426558D01*
X147950Y426767D01*
X148033Y427017D01*
X147950Y427267D01*
X147742Y427475D01*
X147367Y427600D01*
X146992Y427558D01*
X146617Y427392D01*
G01X114567Y431500D02*
Y434000D01*
X115567D01*
X115900Y433875D01*
X116150Y433583D01*
X116233Y433250D01*
X116150Y432917D01*
X115942Y432667D01*
X115567Y432542D01*
X114567D01*
G01X117667Y431500D02*
Y434000D01*
X118708D01*
X119042Y433875D01*
X119250Y433708D01*
X119333Y433375D01*
X119250Y433042D01*
X119000Y432833D01*
X118708Y432708D01*
X117667D01*
G01X118708D02*
X119333Y431500D01*
G01X121600D02*
Y434000D01*
X121100Y433500D01*
G01Y431500D02*
X122100D01*
G01X124700Y434000D02*
X124367Y433917D01*
X124117Y433708D01*
X123950Y433458D01*
X123825Y433125D01*
X123783Y432750D01*
X123825Y432375D01*
X123950Y432042D01*
X124117Y431792D01*
X124367Y431583D01*
X124700Y431500D01*
X125033Y431583D01*
X125283Y431792D01*
X125450Y432042D01*
X125575Y432375D01*
X125617Y432750D01*
X125575Y433125D01*
X125450Y433458D01*
X125283Y433708D01*
X125033Y433917D01*
X124700Y434000D01*
G01X127008Y433583D02*
X127258Y433833D01*
X127550Y433958D01*
X127883Y434000D01*
X128300Y433917D01*
X128592Y433708D01*
X128675Y433458D01*
X128633Y433208D01*
X128467Y433000D01*
X127633Y432583D01*
X127258Y432292D01*
X127008Y431875D01*
X126925Y431500D01*
X128675D01*
G01X115900Y439500D02*
Y435500D01*
X123300D01*
G01X121100Y450267D02*
X118600D01*
Y451267D01*
X118725Y451600D01*
X119017Y451850D01*
X119350Y451933D01*
X119683Y451850D01*
X119933Y451642D01*
X120058Y451267D01*
Y450267D01*
G01X121100Y454200D02*
X121058Y453867D01*
X120892Y453575D01*
X120642Y453325D01*
X120350Y453158D01*
X120017Y453075D01*
X119683D01*
X119350Y453158D01*
X119058Y453325D01*
X118808Y453575D01*
X118642Y453867D01*
X118600Y454200D01*
X118642Y454533D01*
X118808Y454825D01*
X119058Y455075D01*
X119350Y455242D01*
X119683Y455325D01*
X120017D01*
X120350Y455242D01*
X120642Y455075D01*
X120892Y454825D01*
X121058Y454533D01*
X121100Y454200D01*
G01X120433Y454533D02*
X121100Y455033D01*
G01Y457217D02*
X120558Y457300D01*
X120100Y457425D01*
X119683Y457592D01*
X119225Y457800D01*
X118600Y458133D01*
Y456467D01*
G01X114850Y435300D02*
Y465300D01*
G01X93150Y435300D02*
X114850D01*
G01X93150Y465300D02*
Y435300D01*
G01X87350Y435800D02*
Y465800D01*
G01X101500Y407500D02*
X112700D01*
G01X115400Y421000D02*
Y418500D01*
G01X114442Y421000D02*
X116358D01*
G01X119417Y420792D02*
X119167Y420917D01*
X118875Y421000D01*
X118542D01*
X118167Y420875D01*
X117875Y420667D01*
X117667Y420417D01*
X117500Y420000D01*
X117458Y419625D01*
X117542Y419250D01*
X117667Y419000D01*
X117917Y418750D01*
X118208Y418583D01*
X118500Y418500D01*
X118792D01*
X119083Y418583D01*
X119333Y418708D01*
X119542Y418875D01*
G01X120683Y419000D02*
X120933Y418708D01*
X121267Y418542D01*
X121642Y418500D01*
X121975Y418542D01*
X122308Y418750D01*
X122517Y419000D01*
X122558Y419250D01*
X122475Y419542D01*
X122183Y419750D01*
X121892Y419833D01*
X121517D01*
G01X121892D02*
X122142Y419958D01*
X122350Y420167D01*
X122433Y420417D01*
X122350Y420667D01*
X122142Y420875D01*
X121767Y421000D01*
X121392Y420958D01*
X121017Y420792D01*
G01X112700Y410000D02*
X101500D01*
G01X112700Y428000D02*
Y410000D01*
G01X101500Y428000D02*
X112700D01*
G01X128067Y456000D02*
Y458500D01*
X129067D01*
X129400Y458375D01*
X129650Y458083D01*
X129733Y457750D01*
X129650Y457417D01*
X129442Y457167D01*
X129067Y457042D01*
X128067D01*
G01X132000Y456000D02*
X131667Y456042D01*
X131375Y456208D01*
X131125Y456458D01*
X130958Y456750D01*
X130875Y457083D01*
Y457417D01*
X130958Y457750D01*
X131125Y458042D01*
X131375Y458292D01*
X131667Y458458D01*
X132000Y458500D01*
X132333Y458458D01*
X132625Y458292D01*
X132875Y458042D01*
X133042Y457750D01*
X133125Y457417D01*
Y457083D01*
X133042Y456750D01*
X132875Y456458D01*
X132625Y456208D01*
X132333Y456042D01*
X132000Y456000D01*
G01X132333Y456667D02*
X132833Y456000D01*
G01X135100D02*
X135392Y456042D01*
X135725Y456167D01*
X135933Y456375D01*
X136017Y456667D01*
X135933Y456958D01*
X135683Y457208D01*
X135308Y457333D01*
X134892D01*
X134642Y457417D01*
X134433Y457625D01*
X134350Y457917D01*
X134475Y458208D01*
X134767Y458417D01*
X135100Y458500D01*
X135433Y458417D01*
X135725Y458208D01*
X135850Y457917D01*
X135767Y457625D01*
X135558Y457417D01*
X135308Y457333D01*
X134892D01*
X134517Y457208D01*
X134267Y456958D01*
X134183Y456667D01*
X134267Y456375D01*
X134475Y456167D01*
X134808Y456042D01*
X135100Y456000D01*
G01X114850Y465300D02*
X93150D01*
G01X103008Y489667D02*
X102883Y489417D01*
X102800Y489125D01*
Y488792D01*
X102925Y488417D01*
X103133Y488125D01*
X103383Y487917D01*
X103800Y487750D01*
X104175Y487708D01*
X104550Y487792D01*
X104800Y487917D01*
X105050Y488167D01*
X105217Y488458D01*
X105300Y488750D01*
Y489042D01*
X105217Y489333D01*
X105092Y489583D01*
X104925Y489792D01*
G01X103217Y491058D02*
X102967Y491308D01*
X102842Y491600D01*
X102800Y491933D01*
X102883Y492350D01*
X103092Y492642D01*
X103342Y492725D01*
X103592Y492683D01*
X103800Y492517D01*
X104217Y491683D01*
X104508Y491308D01*
X104925Y491058D01*
X105300Y490975D01*
Y492725D01*
G01X104925Y494033D02*
X105133Y494283D01*
X105258Y494575D01*
X105300Y494950D01*
X105217Y495325D01*
X105050Y495617D01*
X104758Y495825D01*
X104425Y495867D01*
X104092Y495783D01*
X103883Y495575D01*
X103717Y495283D01*
X103675Y494992D01*
X103717Y494700D01*
X103883Y494325D01*
X102800Y494450D01*
Y495575D01*
G01X105300Y498050D02*
X105258Y498342D01*
X105133Y498675D01*
X104925Y498883D01*
X104633Y498967D01*
X104342Y498883D01*
X104092Y498633D01*
X103967Y498258D01*
Y497842D01*
X103883Y497592D01*
X103675Y497383D01*
X103383Y497300D01*
X103092Y497425D01*
X102883Y497717D01*
X102800Y498050D01*
X102883Y498383D01*
X103092Y498675D01*
X103383Y498800D01*
X103675Y498717D01*
X103883Y498508D01*
X103967Y498258D01*
Y497842D01*
X104092Y497467D01*
X104342Y497217D01*
X104633Y497133D01*
X104925Y497217D01*
X105133Y497425D01*
X105258Y497758D01*
X105300Y498050D01*
G01X91600Y552900D02*
X93100Y551400D01*
G01X107117Y541100D02*
Y543600D01*
X108117D01*
X108450Y543475D01*
X108700Y543183D01*
X108783Y542850D01*
X108700Y542517D01*
X108492Y542267D01*
X108117Y542142D01*
X107117D01*
G01X110217Y541100D02*
Y543600D01*
X111258D01*
X111592Y543475D01*
X111800Y543308D01*
X111883Y542975D01*
X111800Y542642D01*
X111550Y542433D01*
X111258Y542308D01*
X110217D01*
G01X111258D02*
X111883Y541100D01*
G01X113442Y541392D02*
X113733Y541183D01*
X114067Y541100D01*
X114400Y541183D01*
X114692Y541433D01*
X114900Y541808D01*
X114983Y542183D01*
Y542642D01*
X114900Y543017D01*
X114692Y543350D01*
X114442Y543517D01*
X114150Y543600D01*
X113817Y543517D01*
X113567Y543350D01*
X113400Y543100D01*
X113317Y542767D01*
X113400Y542475D01*
X113608Y542183D01*
X113858Y542017D01*
X114150Y541975D01*
X114483Y542058D01*
X114733Y542267D01*
X114983Y542642D01*
G01X116542Y541392D02*
X116833Y541183D01*
X117167Y541100D01*
X117500Y541183D01*
X117792Y541433D01*
X118000Y541808D01*
X118083Y542183D01*
Y542642D01*
X118000Y543017D01*
X117792Y543350D01*
X117542Y543517D01*
X117250Y543600D01*
X116917Y543517D01*
X116667Y543350D01*
X116500Y543100D01*
X116417Y542767D01*
X116500Y542475D01*
X116708Y542183D01*
X116958Y542017D01*
X117250Y541975D01*
X117583Y542058D01*
X117833Y542267D01*
X118083Y542642D01*
G01X104100Y547600D02*
Y551600D01*
X96700D01*
G01X130000Y538850D02*
X132500D01*
G01X130000Y537892D02*
Y539808D01*
G01X132500Y541117D02*
X130000D01*
Y542117D01*
X130125Y542450D01*
X130417Y542700D01*
X130750Y542783D01*
X131083Y542700D01*
X131333Y542492D01*
X131458Y542117D01*
Y541117D01*
G01X130417Y544258D02*
X130167Y544508D01*
X130042Y544800D01*
X130000Y545133D01*
X130083Y545550D01*
X130292Y545842D01*
X130542Y545925D01*
X130792Y545883D01*
X131000Y545717D01*
X131417Y544883D01*
X131708Y544508D01*
X132125Y544258D01*
X132500Y544175D01*
Y545925D01*
G01Y548650D02*
X130000D01*
X131792Y547108D01*
Y549192D01*
G01X132500Y550967D02*
X130000D01*
Y551967D01*
X130125Y552300D01*
X130417Y552550D01*
X130750Y552633D01*
X131083Y552550D01*
X131333Y552342D01*
X131458Y551967D01*
Y550967D01*
G01X132500Y554067D02*
X130000D01*
Y555108D01*
X130125Y555442D01*
X130292Y555650D01*
X130625Y555733D01*
X130958Y555650D01*
X131167Y555400D01*
X131292Y555108D01*
Y554067D01*
G01Y555108D02*
X132500Y555733D01*
G01Y558000D02*
X130000D01*
X130500Y557500D01*
G01X132500D02*
Y558500D01*
G01X130000Y561100D02*
X130083Y560767D01*
X130292Y560517D01*
X130542Y560350D01*
X130875Y560225D01*
X131250Y560183D01*
X131625Y560225D01*
X131958Y560350D01*
X132208Y560517D01*
X132417Y560767D01*
X132500Y561100D01*
X132417Y561433D01*
X132208Y561683D01*
X131958Y561850D01*
X131625Y561975D01*
X131250Y562017D01*
X130875Y561975D01*
X130542Y561850D01*
X130292Y561683D01*
X130083Y561433D01*
X130000Y561100D01*
G01X132500Y564117D02*
X131958Y564200D01*
X131500Y564325D01*
X131083Y564492D01*
X130625Y564700D01*
X130000Y565033D01*
Y563367D01*
G01X134679Y551771D02*
X138679D01*
Y559171D01*
G01X132500Y522467D02*
X130000D01*
Y523467D01*
X130125Y523800D01*
X130417Y524050D01*
X130750Y524133D01*
X131083Y524050D01*
X131333Y523842D01*
X131458Y523467D01*
Y522467D01*
G01X132500Y525567D02*
X130000D01*
Y526608D01*
X130125Y526942D01*
X130292Y527150D01*
X130625Y527233D01*
X130958Y527150D01*
X131167Y526900D01*
X131292Y526608D01*
Y525567D01*
G01Y526608D02*
X132500Y527233D01*
G01Y529500D02*
X130000D01*
X130500Y529000D01*
G01X132500D02*
Y530000D01*
G01X130000Y532600D02*
X130083Y532267D01*
X130292Y532017D01*
X130542Y531850D01*
X130875Y531725D01*
X131250Y531683D01*
X131625Y531725D01*
X131958Y531850D01*
X132208Y532017D01*
X132417Y532267D01*
X132500Y532600D01*
X132417Y532933D01*
X132208Y533183D01*
X131958Y533350D01*
X131625Y533475D01*
X131250Y533517D01*
X130875Y533475D01*
X130542Y533350D01*
X130292Y533183D01*
X130083Y532933D01*
X130000Y532600D01*
G01X132125Y534783D02*
X132333Y535033D01*
X132458Y535325D01*
X132500Y535700D01*
X132417Y536075D01*
X132250Y536367D01*
X131958Y536575D01*
X131625Y536617D01*
X131292Y536533D01*
X131083Y536325D01*
X130917Y536033D01*
X130875Y535742D01*
X130917Y535450D01*
X131083Y535075D01*
X130000Y535200D01*
Y536325D01*
G01X134779Y537671D02*
X138779D01*
Y545071D01*
G01X102500Y523017D02*
X100000D01*
Y524017D01*
X100125Y524350D01*
X100417Y524600D01*
X100750Y524683D01*
X101083Y524600D01*
X101333Y524392D01*
X101458Y524017D01*
Y523017D01*
G01X102500Y526117D02*
X100000D01*
Y527158D01*
X100125Y527492D01*
X100292Y527700D01*
X100625Y527783D01*
X100958Y527700D01*
X101167Y527450D01*
X101292Y527158D01*
Y526117D01*
G01Y527158D02*
X102500Y527783D01*
G01X102208Y529342D02*
X102417Y529633D01*
X102500Y529967D01*
X102417Y530300D01*
X102167Y530592D01*
X101792Y530800D01*
X101417Y530883D01*
X100958D01*
X100583Y530800D01*
X100250Y530592D01*
X100083Y530342D01*
X100000Y530050D01*
X100083Y529717D01*
X100250Y529467D01*
X100500Y529300D01*
X100833Y529217D01*
X101125Y529300D01*
X101417Y529508D01*
X101583Y529758D01*
X101625Y530050D01*
X101542Y530383D01*
X101333Y530633D01*
X100958Y530883D01*
G01X102500Y533650D02*
X100000D01*
X101792Y532108D01*
Y534192D01*
G01X98100Y535900D02*
X94100D01*
Y528500D01*
G01X107117Y545300D02*
Y547800D01*
X108117D01*
X108450Y547675D01*
X108700Y547383D01*
X108783Y547050D01*
X108700Y546717D01*
X108492Y546467D01*
X108117Y546342D01*
X107117D01*
G01X111967Y547592D02*
X111717Y547717D01*
X111425Y547800D01*
X111092D01*
X110717Y547675D01*
X110425Y547467D01*
X110217Y547217D01*
X110050Y546800D01*
X110008Y546425D01*
X110092Y546050D01*
X110217Y545800D01*
X110467Y545550D01*
X110758Y545383D01*
X111050Y545300D01*
X111342D01*
X111633Y545383D01*
X111883Y545508D01*
X112092Y545675D01*
G01X114150Y545300D02*
X114442Y545342D01*
X114775Y545467D01*
X114983Y545675D01*
X115067Y545967D01*
X114983Y546258D01*
X114733Y546508D01*
X114358Y546633D01*
X113942D01*
X113692Y546717D01*
X113483Y546925D01*
X113400Y547217D01*
X113525Y547508D01*
X113817Y547717D01*
X114150Y547800D01*
X114483Y547717D01*
X114775Y547508D01*
X114900Y547217D01*
X114817Y546925D01*
X114608Y546717D01*
X114358Y546633D01*
X113942D01*
X113567Y546508D01*
X113317Y546258D01*
X113233Y545967D01*
X113317Y545675D01*
X113525Y545467D01*
X113858Y545342D01*
X114150Y545300D01*
G01X116333Y545675D02*
X116583Y545467D01*
X116875Y545342D01*
X117250Y545300D01*
X117625Y545383D01*
X117917Y545550D01*
X118125Y545842D01*
X118167Y546175D01*
X118083Y546508D01*
X117875Y546717D01*
X117583Y546883D01*
X117292Y546925D01*
X117000Y546883D01*
X116625Y546717D01*
X116750Y547800D01*
X117875D01*
G01X104017Y536000D02*
Y538500D01*
X105017D01*
X105350Y538375D01*
X105600Y538083D01*
X105683Y537750D01*
X105600Y537417D01*
X105392Y537167D01*
X105017Y537042D01*
X104017D01*
G01X108867Y538292D02*
X108617Y538417D01*
X108325Y538500D01*
X107992D01*
X107617Y538375D01*
X107325Y538167D01*
X107117Y537917D01*
X106950Y537500D01*
X106908Y537125D01*
X106992Y536750D01*
X107117Y536500D01*
X107367Y536250D01*
X107658Y536083D01*
X107950Y536000D01*
X108242D01*
X108533Y536083D01*
X108783Y536208D01*
X108992Y536375D01*
G01X111050Y536000D02*
X111342Y536042D01*
X111675Y536167D01*
X111883Y536375D01*
X111967Y536667D01*
X111883Y536958D01*
X111633Y537208D01*
X111258Y537333D01*
X110842D01*
X110592Y537417D01*
X110383Y537625D01*
X110300Y537917D01*
X110425Y538208D01*
X110717Y538417D01*
X111050Y538500D01*
X111383Y538417D01*
X111675Y538208D01*
X111800Y537917D01*
X111717Y537625D01*
X111508Y537417D01*
X111258Y537333D01*
X110842D01*
X110467Y537208D01*
X110217Y536958D01*
X110133Y536667D01*
X110217Y536375D01*
X110425Y536167D01*
X110758Y536042D01*
X111050Y536000D01*
G01X113442Y536292D02*
X113733Y536083D01*
X114067Y536000D01*
X114400Y536083D01*
X114692Y536333D01*
X114900Y536708D01*
X114983Y537083D01*
Y537542D01*
X114900Y537917D01*
X114692Y538250D01*
X114442Y538417D01*
X114150Y538500D01*
X113817Y538417D01*
X113567Y538250D01*
X113400Y538000D01*
X113317Y537667D01*
X113400Y537375D01*
X113608Y537083D01*
X113858Y536917D01*
X114150Y536875D01*
X114483Y536958D01*
X114733Y537167D01*
X114983Y537542D01*
G01X107517Y549500D02*
Y552000D01*
X108517D01*
X108850Y551875D01*
X109100Y551583D01*
X109183Y551250D01*
X109100Y550917D01*
X108892Y550667D01*
X108517Y550542D01*
X107517D01*
G01X112367Y551792D02*
X112117Y551917D01*
X111825Y552000D01*
X111492D01*
X111117Y551875D01*
X110825Y551667D01*
X110617Y551417D01*
X110450Y551000D01*
X110408Y550625D01*
X110492Y550250D01*
X110617Y550000D01*
X110867Y549750D01*
X111158Y549583D01*
X111450Y549500D01*
X111742D01*
X112033Y549583D01*
X112283Y549708D01*
X112492Y549875D01*
G01X113842Y549792D02*
X114133Y549583D01*
X114467Y549500D01*
X114800Y549583D01*
X115092Y549833D01*
X115300Y550208D01*
X115383Y550583D01*
Y551042D01*
X115300Y551417D01*
X115092Y551750D01*
X114842Y551917D01*
X114550Y552000D01*
X114217Y551917D01*
X113967Y551750D01*
X113800Y551500D01*
X113717Y551167D01*
X113800Y550875D01*
X114008Y550583D01*
X114258Y550417D01*
X114550Y550375D01*
X114883Y550458D01*
X115133Y550667D01*
X115383Y551042D01*
G01X117567Y549500D02*
X117650Y550042D01*
X117775Y550500D01*
X117942Y550917D01*
X118150Y551375D01*
X118483Y552000D01*
X116817D01*
G01X91600Y552900D02*
X93100Y554400D01*
G01X136000Y568517D02*
X133500D01*
Y569517D01*
X133625Y569850D01*
X133917Y570100D01*
X134250Y570183D01*
X134583Y570100D01*
X134833Y569892D01*
X134958Y569517D01*
Y568517D01*
G01X133708Y573367D02*
X133583Y573117D01*
X133500Y572825D01*
Y572492D01*
X133625Y572117D01*
X133833Y571825D01*
X134083Y571617D01*
X134500Y571450D01*
X134875Y571408D01*
X135250Y571492D01*
X135500Y571617D01*
X135750Y571867D01*
X135917Y572158D01*
X136000Y572450D01*
Y572742D01*
X135917Y573033D01*
X135792Y573283D01*
X135625Y573492D01*
G01X135708Y574842D02*
X135917Y575133D01*
X136000Y575467D01*
X135917Y575800D01*
X135667Y576092D01*
X135292Y576300D01*
X134917Y576383D01*
X134458D01*
X134083Y576300D01*
X133750Y576092D01*
X133583Y575842D01*
X133500Y575550D01*
X133583Y575217D01*
X133750Y574967D01*
X134000Y574800D01*
X134333Y574717D01*
X134625Y574800D01*
X134917Y575008D01*
X135083Y575258D01*
X135125Y575550D01*
X135042Y575883D01*
X134833Y576133D01*
X134458Y576383D01*
G01X133917Y577858D02*
X133667Y578108D01*
X133542Y578400D01*
X133500Y578733D01*
X133583Y579150D01*
X133792Y579442D01*
X134042Y579525D01*
X134292Y579483D01*
X134500Y579317D01*
X134917Y578483D01*
X135208Y578108D01*
X135625Y577858D01*
X136000Y577775D01*
Y579525D01*
G01X99500Y572517D02*
X97000D01*
Y573517D01*
X97125Y573850D01*
X97417Y574100D01*
X97750Y574183D01*
X98083Y574100D01*
X98333Y573892D01*
X98458Y573517D01*
Y572517D01*
G01X97208Y577367D02*
X97083Y577117D01*
X97000Y576825D01*
Y576492D01*
X97125Y576117D01*
X97333Y575825D01*
X97583Y575617D01*
X98000Y575450D01*
X98375Y575408D01*
X98750Y575492D01*
X99000Y575617D01*
X99250Y575867D01*
X99417Y576158D01*
X99500Y576450D01*
Y576742D01*
X99417Y577033D01*
X99292Y577283D01*
X99125Y577492D01*
G01X99208Y578842D02*
X99417Y579133D01*
X99500Y579467D01*
X99417Y579800D01*
X99167Y580092D01*
X98792Y580300D01*
X98417Y580383D01*
X97958D01*
X97583Y580300D01*
X97250Y580092D01*
X97083Y579842D01*
X97000Y579550D01*
X97083Y579217D01*
X97250Y578967D01*
X97500Y578800D01*
X97833Y578717D01*
X98125Y578800D01*
X98417Y579008D01*
X98583Y579258D01*
X98625Y579550D01*
X98542Y579883D01*
X98333Y580133D01*
X97958Y580383D01*
G01X98458Y581858D02*
X98167Y582150D01*
X98000Y582400D01*
X97917Y582733D01*
X98000Y583025D01*
X98167Y583233D01*
X98417Y583400D01*
X98708Y583442D01*
X98958Y583400D01*
X99208Y583233D01*
X99417Y582983D01*
X99500Y582692D01*
X99417Y582358D01*
X99167Y582067D01*
X98792Y581900D01*
X98375Y581858D01*
X97833Y581942D01*
X97542Y582067D01*
X97250Y582275D01*
X97042Y582567D01*
X97000Y582858D01*
X97083Y583150D01*
X97292Y583358D01*
G01X132500Y582400D02*
X135000D01*
G01X132500Y581442D02*
Y583358D01*
G01X135000Y584667D02*
X132500D01*
Y585667D01*
X132625Y586000D01*
X132917Y586250D01*
X133250Y586333D01*
X133583Y586250D01*
X133833Y586042D01*
X133958Y585667D01*
Y584667D01*
G01X134708Y587892D02*
X134917Y588183D01*
X135000Y588517D01*
X134917Y588850D01*
X134667Y589142D01*
X134292Y589350D01*
X133917Y589433D01*
X133458D01*
X133083Y589350D01*
X132750Y589142D01*
X132583Y588892D01*
X132500Y588600D01*
X132583Y588267D01*
X132750Y588017D01*
X133000Y587850D01*
X133333Y587767D01*
X133625Y587850D01*
X133917Y588058D01*
X134083Y588308D01*
X134125Y588600D01*
X134042Y588933D01*
X133833Y589183D01*
X133458Y589433D01*
G01X123900Y599000D02*
Y596500D01*
G01X122942Y599000D02*
X124858D01*
G01X126167Y596500D02*
Y599000D01*
X127167D01*
X127500Y598875D01*
X127750Y598583D01*
X127833Y598250D01*
X127750Y597917D01*
X127542Y597667D01*
X127167Y597542D01*
X126167D01*
G01X129308D02*
X129600Y597833D01*
X129850Y598000D01*
X130183Y598083D01*
X130475Y598000D01*
X130683Y597833D01*
X130850Y597583D01*
X130892Y597292D01*
X130850Y597042D01*
X130683Y596792D01*
X130433Y596583D01*
X130142Y596500D01*
X129808Y596583D01*
X129517Y596833D01*
X129350Y597208D01*
X129308Y597625D01*
X129392Y598167D01*
X129517Y598458D01*
X129725Y598750D01*
X130017Y598958D01*
X130308Y599000D01*
X130600Y598917D01*
X130808Y598708D01*
G01X119350Y604000D02*
Y601500D01*
G01X118392Y604000D02*
X120308D01*
G01X121617Y601500D02*
Y604000D01*
X122617D01*
X122950Y603875D01*
X123200Y603583D01*
X123283Y603250D01*
X123200Y602917D01*
X122992Y602667D01*
X122617Y602542D01*
X121617D01*
G01X125550Y601500D02*
Y604000D01*
X125050Y603500D01*
G01Y601500D02*
X126050D01*
G01X128650Y604000D02*
X128317Y603917D01*
X128067Y603708D01*
X127900Y603458D01*
X127775Y603125D01*
X127733Y602750D01*
X127775Y602375D01*
X127900Y602042D01*
X128067Y601792D01*
X128317Y601583D01*
X128650Y601500D01*
X128983Y601583D01*
X129233Y601792D01*
X129400Y602042D01*
X129525Y602375D01*
X129567Y602750D01*
X129525Y603125D01*
X129400Y603458D01*
X129233Y603708D01*
X128983Y603917D01*
X128650Y604000D01*
G01X106900Y599500D02*
Y597000D01*
G01X105942Y599500D02*
X107858D01*
G01X109167Y597000D02*
Y599500D01*
X110167D01*
X110500Y599375D01*
X110750Y599083D01*
X110833Y598750D01*
X110750Y598417D01*
X110542Y598167D01*
X110167Y598042D01*
X109167D01*
G01X113100Y597000D02*
Y599500D01*
X112600Y599000D01*
G01Y597000D02*
X113600D01*
G01X109300Y583867D02*
X106800D01*
Y584908D01*
X106925Y585242D01*
X107092Y585450D01*
X107425Y585533D01*
X107758Y585450D01*
X107967Y585200D01*
X108092Y584908D01*
Y583867D01*
G01Y584908D02*
X109300Y585533D01*
G01Y587800D02*
X106800D01*
X107300Y587300D01*
G01X109300D02*
Y588300D01*
G01X108258Y590108D02*
X107967Y590400D01*
X107800Y590650D01*
X107717Y590983D01*
X107800Y591275D01*
X107967Y591483D01*
X108217Y591650D01*
X108508Y591692D01*
X108758Y591650D01*
X109008Y591483D01*
X109217Y591233D01*
X109300Y590942D01*
X109217Y590608D01*
X108967Y590317D01*
X108592Y590150D01*
X108175Y590108D01*
X107633Y590192D01*
X107342Y590317D01*
X107050Y590525D01*
X106842Y590817D01*
X106800Y591108D01*
X106883Y591400D01*
X107092Y591608D01*
G01X114800Y583196D02*
X118800D01*
Y590596D01*
G01X130500Y573567D02*
X128000D01*
Y574608D01*
X128125Y574942D01*
X128292Y575150D01*
X128625Y575233D01*
X128958Y575150D01*
X129167Y574900D01*
X129292Y574608D01*
Y573567D01*
G01Y574608D02*
X130500Y575233D01*
G01X130000Y576583D02*
X130292Y576833D01*
X130458Y577167D01*
X130500Y577542D01*
X130458Y577875D01*
X130250Y578208D01*
X130000Y578417D01*
X129750Y578458D01*
X129458Y578375D01*
X129250Y578083D01*
X129167Y577792D01*
Y577417D01*
G01Y577792D02*
X129042Y578042D01*
X128833Y578250D01*
X128583Y578333D01*
X128333Y578250D01*
X128125Y578042D01*
X128000Y577667D01*
X128042Y577292D01*
X128208Y576917D01*
G01X129458Y579808D02*
X129167Y580100D01*
X129000Y580350D01*
X128917Y580683D01*
X129000Y580975D01*
X129167Y581183D01*
X129417Y581350D01*
X129708Y581392D01*
X129958Y581350D01*
X130208Y581183D01*
X130417Y580933D01*
X130500Y580642D01*
X130417Y580308D01*
X130167Y580017D01*
X129792Y579850D01*
X129375Y579808D01*
X128833Y579892D01*
X128542Y580017D01*
X128250Y580225D01*
X128042Y580517D01*
X128000Y580808D01*
X128083Y581100D01*
X128292Y581308D01*
G01X126900Y583196D02*
X130900D01*
Y590596D01*
G01X126000Y571517D02*
X123500D01*
Y572558D01*
X123625Y572892D01*
X123792Y573100D01*
X124125Y573183D01*
X124458Y573100D01*
X124667Y572850D01*
X124792Y572558D01*
Y571517D01*
G01Y572558D02*
X126000Y573183D01*
G01Y575450D02*
X123500D01*
X124000Y574950D01*
G01X126000D02*
Y575950D01*
G01X123917Y577758D02*
X123667Y578008D01*
X123542Y578300D01*
X123500Y578633D01*
X123583Y579050D01*
X123792Y579342D01*
X124042Y579425D01*
X124292Y579383D01*
X124500Y579217D01*
X124917Y578383D01*
X125208Y578008D01*
X125625Y577758D01*
X126000Y577675D01*
Y579425D01*
G01Y581650D02*
X125958Y581942D01*
X125833Y582275D01*
X125625Y582483D01*
X125333Y582567D01*
X125042Y582483D01*
X124792Y582233D01*
X124667Y581858D01*
Y581442D01*
X124583Y581192D01*
X124375Y580983D01*
X124083Y580900D01*
X123792Y581025D01*
X123583Y581317D01*
X123500Y581650D01*
X123583Y581983D01*
X123792Y582275D01*
X124083Y582400D01*
X124375Y582317D01*
X124583Y582108D01*
X124667Y581858D01*
Y581442D01*
X124792Y581067D01*
X125042Y580817D01*
X125333Y580733D01*
X125625Y580817D01*
X125833Y581025D01*
X125958Y581358D01*
X126000Y581650D01*
G01X126900Y590604D02*
X122900D01*
Y583204D01*
G01X122100Y574367D02*
X119600D01*
Y575408D01*
X119725Y575742D01*
X119892Y575950D01*
X120225Y576033D01*
X120558Y575950D01*
X120767Y575700D01*
X120892Y575408D01*
Y574367D01*
G01Y575408D02*
X122100Y576033D01*
G01X121600Y577383D02*
X121892Y577633D01*
X122058Y577967D01*
X122100Y578342D01*
X122058Y578675D01*
X121850Y579008D01*
X121600Y579217D01*
X121350Y579258D01*
X121058Y579175D01*
X120850Y578883D01*
X120767Y578592D01*
Y578217D01*
G01Y578592D02*
X120642Y578842D01*
X120433Y579050D01*
X120183Y579133D01*
X119933Y579050D01*
X119725Y578842D01*
X119600Y578467D01*
X119642Y578092D01*
X119808Y577717D01*
G01X121725Y580483D02*
X121933Y580733D01*
X122058Y581025D01*
X122100Y581400D01*
X122017Y581775D01*
X121850Y582067D01*
X121558Y582275D01*
X121225Y582317D01*
X120892Y582233D01*
X120683Y582025D01*
X120517Y581733D01*
X120475Y581442D01*
X120517Y581150D01*
X120683Y580775D01*
X119600Y580900D01*
Y582025D01*
G01X122800Y590604D02*
X118800D01*
Y583204D01*
G01X94500Y577367D02*
X92000D01*
Y578367D01*
X92125Y578700D01*
X92417Y578950D01*
X92750Y579033D01*
X93083Y578950D01*
X93333Y578742D01*
X93458Y578367D01*
Y577367D01*
G01X94500Y580467D02*
X92000D01*
Y581508D01*
X92125Y581842D01*
X92292Y582050D01*
X92625Y582133D01*
X92958Y582050D01*
X93167Y581800D01*
X93292Y581508D01*
Y580467D01*
G01Y581508D02*
X94500Y582133D01*
G01Y584400D02*
X92000D01*
X92500Y583900D01*
G01X94500D02*
Y584900D01*
G01Y587500D02*
X92000D01*
X92500Y587000D01*
G01X94500D02*
Y588000D01*
G01X92417Y589808D02*
X92167Y590058D01*
X92042Y590350D01*
X92000Y590683D01*
X92083Y591100D01*
X92292Y591392D01*
X92542Y591475D01*
X92792Y591433D01*
X93000Y591267D01*
X93417Y590433D01*
X93708Y590058D01*
X94125Y589808D01*
X94500Y589725D01*
Y591475D01*
G01X89300Y567800D02*
X93300D01*
Y575200D01*
G01X95065Y599471D02*
X91065D01*
Y592071D01*
G01X89000Y593067D02*
X86500D01*
Y594108D01*
X86625Y594442D01*
X86792Y594650D01*
X87125Y594733D01*
X87458Y594650D01*
X87667Y594400D01*
X87792Y594108D01*
Y593067D01*
G01Y594108D02*
X89000Y594733D01*
G01Y597000D02*
X86500D01*
X87000Y596500D01*
G01X89000D02*
Y597500D01*
G01X86500Y600100D02*
X86583Y599767D01*
X86792Y599517D01*
X87042Y599350D01*
X87375Y599225D01*
X87750Y599183D01*
X88125Y599225D01*
X88458Y599350D01*
X88708Y599517D01*
X88917Y599767D01*
X89000Y600100D01*
X88917Y600433D01*
X88708Y600683D01*
X88458Y600850D01*
X88125Y600975D01*
X87750Y601017D01*
X87375Y600975D01*
X87042Y600850D01*
X86792Y600683D01*
X86583Y600433D01*
X86500Y600100D01*
G01X99265Y599471D02*
X95265D01*
Y592071D01*
G01X117950Y570000D02*
X117617Y570042D01*
X117325Y570208D01*
X117075Y570458D01*
X116908Y570750D01*
X116825Y571083D01*
Y571417D01*
X116908Y571750D01*
X117075Y572042D01*
X117325Y572292D01*
X117617Y572458D01*
X117950Y572500D01*
X118283Y572458D01*
X118575Y572292D01*
X118825Y572042D01*
X118992Y571750D01*
X119075Y571417D01*
Y571083D01*
X118992Y570750D01*
X118825Y570458D01*
X118575Y570208D01*
X118283Y570042D01*
X117950Y570000D01*
G01X118283Y570667D02*
X118783Y570000D01*
G01X121050D02*
Y572500D01*
X120550Y572000D01*
G01Y570000D02*
X121550D01*
G01X101268Y564366D02*
X115268D01*
G01X101268Y577366D02*
Y564366D01*
G01X115268Y577366D02*
X101268D01*
G01X115268Y564366D02*
Y577366D01*
G01X89000Y580517D02*
X86500D01*
Y581517D01*
X86625Y581850D01*
X86917Y582100D01*
X87250Y582183D01*
X87583Y582100D01*
X87833Y581892D01*
X87958Y581517D01*
Y580517D01*
G01X86708Y585367D02*
X86583Y585117D01*
X86500Y584825D01*
Y584492D01*
X86625Y584117D01*
X86833Y583825D01*
X87083Y583617D01*
X87500Y583450D01*
X87875Y583408D01*
X88250Y583492D01*
X88500Y583617D01*
X88750Y583867D01*
X88917Y584158D01*
X89000Y584450D01*
Y584742D01*
X88917Y585033D01*
X88792Y585283D01*
X88625Y585492D01*
G01X88708Y586842D02*
X88917Y587133D01*
X89000Y587467D01*
X88917Y587800D01*
X88667Y588092D01*
X88292Y588300D01*
X87917Y588383D01*
X87458D01*
X87083Y588300D01*
X86750Y588092D01*
X86583Y587842D01*
X86500Y587550D01*
X86583Y587217D01*
X86750Y586967D01*
X87000Y586800D01*
X87333Y586717D01*
X87625Y586800D01*
X87917Y587008D01*
X88083Y587258D01*
X88125Y587550D01*
X88042Y587883D01*
X87833Y588133D01*
X87458Y588383D01*
G01X88500Y589733D02*
X88792Y589983D01*
X88958Y590317D01*
X89000Y590692D01*
X88958Y591025D01*
X88750Y591358D01*
X88500Y591567D01*
X88250Y591608D01*
X87958Y591525D01*
X87750Y591233D01*
X87667Y590942D01*
Y590567D01*
G01Y590942D02*
X87542Y591192D01*
X87333Y591400D01*
X87083Y591483D01*
X86833Y591400D01*
X86625Y591192D01*
X86500Y590817D01*
X86542Y590442D01*
X86708Y590067D01*
G01X115208Y597367D02*
X115083Y597117D01*
X115000Y596825D01*
Y596492D01*
X115125Y596117D01*
X115333Y595825D01*
X115583Y595617D01*
X116000Y595450D01*
X116375Y595408D01*
X116750Y595492D01*
X117000Y595617D01*
X117250Y595867D01*
X117417Y596158D01*
X117500Y596450D01*
Y596742D01*
X117417Y597033D01*
X117292Y597283D01*
X117125Y597492D01*
G01X117500Y599550D02*
X117458Y599842D01*
X117333Y600175D01*
X117125Y600383D01*
X116833Y600467D01*
X116542Y600383D01*
X116292Y600133D01*
X116167Y599758D01*
Y599342D01*
X116083Y599092D01*
X115875Y598883D01*
X115583Y598800D01*
X115292Y598925D01*
X115083Y599217D01*
X115000Y599550D01*
X115083Y599883D01*
X115292Y600175D01*
X115583Y600300D01*
X115875Y600217D01*
X116083Y600008D01*
X116167Y599758D01*
Y599342D01*
X116292Y598967D01*
X116542Y598717D01*
X116833Y598633D01*
X117125Y598717D01*
X117333Y598925D01*
X117458Y599258D01*
X117500Y599550D01*
G01X111367Y581292D02*
X111117Y581417D01*
X110825Y581500D01*
X110492D01*
X110117Y581375D01*
X109825Y581167D01*
X109617Y580917D01*
X109450Y580500D01*
X109408Y580125D01*
X109492Y579750D01*
X109617Y579500D01*
X109867Y579250D01*
X110158Y579083D01*
X110450Y579000D01*
X110742D01*
X111033Y579083D01*
X111283Y579208D01*
X111492Y579375D01*
G01X113467Y579000D02*
X113550Y579542D01*
X113675Y580000D01*
X113842Y580417D01*
X114050Y580875D01*
X114383Y581500D01*
X112717D01*
G01X101708Y587767D02*
X101583Y587517D01*
X101500Y587225D01*
Y586892D01*
X101625Y586517D01*
X101833Y586225D01*
X102083Y586017D01*
X102500Y585850D01*
X102875Y585808D01*
X103250Y585892D01*
X103500Y586017D01*
X103750Y586267D01*
X103917Y586558D01*
X104000Y586850D01*
Y587142D01*
X103917Y587433D01*
X103792Y587683D01*
X103625Y587892D01*
G01Y589033D02*
X103833Y589283D01*
X103958Y589575D01*
X104000Y589950D01*
X103917Y590325D01*
X103750Y590617D01*
X103458Y590825D01*
X103125Y590867D01*
X102792Y590783D01*
X102583Y590575D01*
X102417Y590283D01*
X102375Y589992D01*
X102417Y589700D01*
X102583Y589325D01*
X101500Y589450D01*
Y590575D01*
G01X94000Y643533D02*
X95792D01*
X96167Y643700D01*
X96417Y644033D01*
X96500Y644450D01*
X96417Y644867D01*
X96167Y645200D01*
X95792Y645367D01*
X94000D01*
G01X96500Y647550D02*
X94000D01*
X94500Y647050D01*
G01X96500D02*
Y648050D01*
G01X107835Y651029D02*
X97835D01*
Y641229D01*
G01X141235Y641029D02*
Y651029D01*
X131335D01*
G01X131735Y607629D02*
X141235D01*
Y617729D01*
G01X107535Y607629D02*
X97835D01*
Y617229D01*
X97935D01*
X107535Y607629D01*
G01X99235Y624409D02*
X97235D01*
G01X99235Y634249D02*
X96235D01*
G01X110675Y649629D02*
Y651629D01*
G01X120520Y649629D02*
Y652629D01*
G01X130360Y649629D02*
Y651629D01*
G01X126425Y609029D02*
Y606029D01*
G01X116580Y609029D02*
Y607029D01*
G01X87000Y614850D02*
X89500D01*
G01X87000Y613892D02*
Y615808D01*
G01X89500Y617117D02*
X87000D01*
Y618117D01*
X87125Y618450D01*
X87417Y618700D01*
X87750Y618783D01*
X88083Y618700D01*
X88333Y618492D01*
X88458Y618117D01*
Y617117D01*
G01X89500Y621050D02*
X87000D01*
X87500Y620550D01*
G01X89500D02*
Y621550D01*
G01X88458Y623358D02*
X88167Y623650D01*
X88000Y623900D01*
X87917Y624233D01*
X88000Y624525D01*
X88167Y624733D01*
X88417Y624900D01*
X88708Y624942D01*
X88958Y624900D01*
X89208Y624733D01*
X89417Y624483D01*
X89500Y624192D01*
X89417Y623858D01*
X89167Y623567D01*
X88792Y623400D01*
X88375Y623358D01*
X87833Y623442D01*
X87542Y623567D01*
X87250Y623775D01*
X87042Y624067D01*
X87000Y624358D01*
X87083Y624650D01*
X87292Y624858D01*
G01X96500Y636117D02*
X94000D01*
Y637158D01*
X94125Y637492D01*
X94292Y637700D01*
X94625Y637783D01*
X94958Y637700D01*
X95167Y637450D01*
X95292Y637158D01*
Y636117D01*
G01Y637158D02*
X96500Y637783D01*
G01Y640050D02*
X96458Y640342D01*
X96333Y640675D01*
X96125Y640883D01*
X95833Y640967D01*
X95542Y640883D01*
X95292Y640633D01*
X95167Y640258D01*
Y639842D01*
X95083Y639592D01*
X94875Y639383D01*
X94583Y639300D01*
X94292Y639425D01*
X94083Y639717D01*
X94000Y640050D01*
X94083Y640383D01*
X94292Y640675D01*
X94583Y640800D01*
X94875Y640717D01*
X95083Y640508D01*
X95167Y640258D01*
Y639842D01*
X95292Y639467D01*
X95542Y639217D01*
X95833Y639133D01*
X96125Y639217D01*
X96333Y639425D01*
X96458Y639758D01*
X96500Y640050D01*
G01X85935Y632129D02*
Y637329D01*
G01X92935Y632129D02*
Y639929D01*
G01X85935Y632129D02*
X92935D01*
G01X85935Y645529D02*
Y636829D01*
G01X92935Y645529D02*
X85935D01*
G01X92935Y639129D02*
Y645529D01*
G01X89000Y606617D02*
X86500D01*
Y607658D01*
X86625Y607992D01*
X86792Y608200D01*
X87125Y608283D01*
X87458Y608200D01*
X87667Y607950D01*
X87792Y607658D01*
Y606617D01*
G01Y607658D02*
X89000Y608283D01*
G01Y611050D02*
X86500D01*
X88292Y609508D01*
Y611592D01*
G01X94465Y612371D02*
X90465D01*
Y604971D01*
G01X113600Y654800D02*
X117600D01*
Y662200D01*
G01X102033Y700000D02*
Y698208D01*
X102200Y697833D01*
X102533Y697583D01*
X102950Y697500D01*
X103367Y697583D01*
X103700Y697833D01*
X103867Y698208D01*
Y700000D01*
G01X105258Y699583D02*
X105508Y699833D01*
X105800Y699958D01*
X106133Y700000D01*
X106550Y699917D01*
X106842Y699708D01*
X106925Y699458D01*
X106883Y699208D01*
X106717Y699000D01*
X105883Y698583D01*
X105508Y698292D01*
X105258Y697875D01*
X105175Y697500D01*
X106925D01*
G01X100806Y673565D02*
X103306Y676065D01*
X105806Y673565D01*
X100806D01*
G01X88956D02*
Y695615D01*
X117556D01*
Y673565D01*
X88956D01*
G01X132708Y673817D02*
X132583Y673567D01*
X132500Y673275D01*
Y672942D01*
X132625Y672567D01*
X132833Y672275D01*
X133083Y672067D01*
X133500Y671900D01*
X133875Y671858D01*
X134250Y671942D01*
X134500Y672067D01*
X134750Y672317D01*
X134917Y672608D01*
X135000Y672900D01*
Y673192D01*
X134917Y673483D01*
X134792Y673733D01*
X134625Y673942D01*
G01X135000Y676000D02*
X132500D01*
X133000Y675500D01*
G01X135000D02*
Y676500D01*
G01X132917Y678308D02*
X132667Y678558D01*
X132542Y678850D01*
X132500Y679183D01*
X132583Y679600D01*
X132792Y679892D01*
X133042Y679975D01*
X133292Y679933D01*
X133500Y679767D01*
X133917Y678933D01*
X134208Y678558D01*
X134625Y678308D01*
X135000Y678225D01*
Y679975D01*
G01X120208Y683817D02*
X120083Y683567D01*
X120000Y683275D01*
Y682942D01*
X120125Y682567D01*
X120333Y682275D01*
X120583Y682067D01*
X121000Y681900D01*
X121375Y681858D01*
X121750Y681942D01*
X122000Y682067D01*
X122250Y682317D01*
X122417Y682608D01*
X122500Y682900D01*
Y683192D01*
X122417Y683483D01*
X122292Y683733D01*
X122125Y683942D01*
G01X122500Y686000D02*
X120000D01*
X120500Y685500D01*
G01X122500D02*
Y686500D01*
G01Y689100D02*
X120000D01*
X120500Y688600D01*
G01X122500D02*
Y689600D01*
G01X98500Y658400D02*
X101000D01*
G01X98500Y657442D02*
Y659358D01*
G01X101000Y660667D02*
X98500D01*
Y661667D01*
X98625Y662000D01*
X98917Y662250D01*
X99250Y662333D01*
X99583Y662250D01*
X99833Y662042D01*
X99958Y661667D01*
Y660667D01*
G01X100625Y663683D02*
X100833Y663933D01*
X100958Y664225D01*
X101000Y664600D01*
X100917Y664975D01*
X100750Y665267D01*
X100458Y665475D01*
X100125Y665517D01*
X99792Y665433D01*
X99583Y665225D01*
X99417Y664933D01*
X99375Y664642D01*
X99417Y664350D01*
X99583Y663975D01*
X98500Y664100D01*
Y665225D01*
G01X96700Y669000D02*
Y673000D01*
X89300D01*
G01X97200Y667700D02*
X93200D01*
Y660300D01*
G01X119067Y700500D02*
Y703000D01*
X120108D01*
X120442Y702875D01*
X120650Y702708D01*
X120733Y702375D01*
X120650Y702042D01*
X120400Y701833D01*
X120108Y701708D01*
X119067D01*
G01X120108D02*
X120733Y700500D01*
G01X123000D02*
Y703000D01*
X122500Y702500D01*
G01Y700500D02*
X123500D01*
G01X125392Y700792D02*
X125683Y700583D01*
X126017Y700500D01*
X126350Y700583D01*
X126642Y700833D01*
X126850Y701208D01*
X126933Y701583D01*
Y702042D01*
X126850Y702417D01*
X126642Y702750D01*
X126392Y702917D01*
X126100Y703000D01*
X125767Y702917D01*
X125517Y702750D01*
X125350Y702500D01*
X125267Y702167D01*
X125350Y701875D01*
X125558Y701583D01*
X125808Y701417D01*
X126100Y701375D01*
X126433Y701458D01*
X126683Y701667D01*
X126933Y702042D01*
G01X123956Y694165D02*
Y690165D01*
X131356D01*
G01X119067Y696500D02*
Y699000D01*
X120108D01*
X120442Y698875D01*
X120650Y698708D01*
X120733Y698375D01*
X120650Y698042D01*
X120400Y697833D01*
X120108Y697708D01*
X119067D01*
G01X120108D02*
X120733Y696500D01*
G01X123000D02*
Y699000D01*
X122500Y698500D01*
G01Y696500D02*
X123500D01*
G01X126100D02*
X126392Y696542D01*
X126725Y696667D01*
X126933Y696875D01*
X127017Y697167D01*
X126933Y697458D01*
X126683Y697708D01*
X126308Y697833D01*
X125892D01*
X125642Y697917D01*
X125433Y698125D01*
X125350Y698417D01*
X125475Y698708D01*
X125767Y698917D01*
X126100Y699000D01*
X126433Y698917D01*
X126725Y698708D01*
X126850Y698417D01*
X126767Y698125D01*
X126558Y697917D01*
X126308Y697833D01*
X125892D01*
X125517Y697708D01*
X125267Y697458D01*
X125183Y697167D01*
X125267Y696875D01*
X125475Y696667D01*
X125808Y696542D01*
X126100Y696500D01*
G01X123856Y690065D02*
Y686065D01*
X131256D01*
G01X137000Y682567D02*
X134500D01*
Y683608D01*
X134625Y683942D01*
X134792Y684150D01*
X135125Y684233D01*
X135458Y684150D01*
X135667Y683900D01*
X135792Y683608D01*
Y682567D01*
G01Y683608D02*
X137000Y684233D01*
G01Y686500D02*
X134500D01*
X135000Y686000D01*
G01X137000D02*
Y687000D01*
G01Y689517D02*
X136458Y689600D01*
X136000Y689725D01*
X135583Y689892D01*
X135125Y690100D01*
X134500Y690433D01*
Y688767D01*
G01X123856Y685665D02*
Y681665D01*
X131256D01*
G01X139765Y664071D02*
X135765D01*
Y656671D01*
G01X127335Y656629D02*
X131335D01*
Y664029D01*
G01X131535Y656629D02*
X135535D01*
Y664029D01*
G01X86067Y702000D02*
Y704500D01*
X87108D01*
X87442Y704375D01*
X87650Y704208D01*
X87733Y703875D01*
X87650Y703542D01*
X87400Y703333D01*
X87108Y703208D01*
X86067D01*
G01X87108D02*
X87733Y702000D01*
G01X90000D02*
X90292Y702042D01*
X90625Y702167D01*
X90833Y702375D01*
X90917Y702667D01*
X90833Y702958D01*
X90583Y703208D01*
X90208Y703333D01*
X89792D01*
X89542Y703417D01*
X89333Y703625D01*
X89250Y703917D01*
X89375Y704208D01*
X89667Y704417D01*
X90000Y704500D01*
X90333Y704417D01*
X90625Y704208D01*
X90750Y703917D01*
X90667Y703625D01*
X90458Y703417D01*
X90208Y703333D01*
X89792D01*
X89417Y703208D01*
X89167Y702958D01*
X89083Y702667D01*
X89167Y702375D01*
X89375Y702167D01*
X89708Y702042D01*
X90000Y702000D01*
G01X92183Y702500D02*
X92433Y702208D01*
X92767Y702042D01*
X93142Y702000D01*
X93475Y702042D01*
X93808Y702250D01*
X94017Y702500D01*
X94058Y702750D01*
X93975Y703042D01*
X93683Y703250D01*
X93392Y703333D01*
X93017D01*
G01X93392D02*
X93642Y703458D01*
X93850Y703667D01*
X93933Y703917D01*
X93850Y704167D01*
X93642Y704375D01*
X93267Y704500D01*
X92892Y704458D01*
X92517Y704292D01*
G01X93200Y705900D02*
Y709900D01*
X85800D01*
G01X98517Y669000D02*
Y671500D01*
X99558D01*
X99892Y671375D01*
X100100Y671208D01*
X100183Y670875D01*
X100100Y670542D01*
X99850Y670333D01*
X99558Y670208D01*
X98517D01*
G01X99558D02*
X100183Y669000D01*
G01X102450D02*
Y671500D01*
X101950Y671000D01*
G01Y669000D02*
X102950D01*
G01X105467D02*
X105550Y669542D01*
X105675Y670000D01*
X105842Y670417D01*
X106050Y670875D01*
X106383Y671500D01*
X104717D01*
G01X107858Y670042D02*
X108150Y670333D01*
X108400Y670500D01*
X108733Y670583D01*
X109025Y670500D01*
X109233Y670333D01*
X109400Y670083D01*
X109442Y669792D01*
X109400Y669542D01*
X109233Y669292D01*
X108983Y669083D01*
X108692Y669000D01*
X108358Y669083D01*
X108067Y669333D01*
X107900Y669708D01*
X107858Y670125D01*
X107942Y670667D01*
X108067Y670958D01*
X108275Y671250D01*
X108567Y671458D01*
X108858Y671500D01*
X109150Y671417D01*
X109358Y671208D01*
G01X110900Y672600D02*
Y668600D01*
X118300D01*
G01X121000Y658200D02*
Y662200D01*
X113600D01*
G01X110300Y660200D02*
Y664200D01*
X102900D01*
G01Y656800D02*
X106900D01*
Y664200D01*
G01X114300Y665200D02*
X118300D01*
Y672600D01*
G01X130267Y700292D02*
X130017Y700417D01*
X129725Y700500D01*
X129392D01*
X129017Y700375D01*
X128725Y700167D01*
X128517Y699917D01*
X128350Y699500D01*
X128308Y699125D01*
X128392Y698750D01*
X128517Y698500D01*
X128767Y698250D01*
X129058Y698083D01*
X129350Y698000D01*
X129642D01*
X129933Y698083D01*
X130183Y698208D01*
X130392Y698375D01*
G01X131658Y700083D02*
X131908Y700333D01*
X132200Y700458D01*
X132533Y700500D01*
X132950Y700417D01*
X133242Y700208D01*
X133325Y699958D01*
X133283Y699708D01*
X133117Y699500D01*
X132283Y699083D01*
X131908Y698792D01*
X131658Y698375D01*
X131575Y698000D01*
X133325D01*
G01X134633Y698375D02*
X134883Y698167D01*
X135175Y698042D01*
X135550Y698000D01*
X135925Y698083D01*
X136217Y698250D01*
X136425Y698542D01*
X136467Y698875D01*
X136383Y699208D01*
X136175Y699417D01*
X135883Y699583D01*
X135592Y699625D01*
X135300Y699583D01*
X134925Y699417D01*
X135050Y700500D01*
X136175D01*
G01X137858Y699042D02*
X138150Y699333D01*
X138400Y699500D01*
X138733Y699583D01*
X139025Y699500D01*
X139233Y699333D01*
X139400Y699083D01*
X139442Y698792D01*
X139400Y698542D01*
X139233Y698292D01*
X138983Y698083D01*
X138692Y698000D01*
X138358Y698083D01*
X138067Y698333D01*
X137900Y698708D01*
X137858Y699125D01*
X137942Y699667D01*
X138067Y699958D01*
X138275Y700250D01*
X138567Y700458D01*
X138858Y700500D01*
X139150Y700417D01*
X139358Y700208D01*
G01X110000Y704983D02*
X107500D01*
Y705817D01*
X107625Y706150D01*
X107792Y706400D01*
X108042Y706608D01*
X108333Y706775D01*
X108750Y706817D01*
X109167Y706775D01*
X109458Y706608D01*
X109708Y706400D01*
X109875Y706150D01*
X110000Y705817D01*
Y704983D01*
G01Y709000D02*
X107500D01*
X108000Y708500D01*
G01X110000D02*
Y709500D01*
G01X109500Y711183D02*
X109792Y711433D01*
X109958Y711767D01*
X110000Y712142D01*
X109958Y712475D01*
X109750Y712808D01*
X109500Y713017D01*
X109250Y713058D01*
X108958Y712975D01*
X108750Y712683D01*
X108667Y712392D01*
Y712017D01*
G01Y712392D02*
X108542Y712642D01*
X108333Y712850D01*
X108083Y712933D01*
X107833Y712850D01*
X107625Y712642D01*
X107500Y712267D01*
X107542Y711892D01*
X107708Y711517D01*
G01X139700Y704500D02*
Y716500D01*
X112300D01*
Y704500D01*
X139700D01*
G01X127500Y737917D02*
X122500D01*
Y741083D01*
G01X124917Y739917D02*
Y737917D01*
G01X126500Y743267D02*
X127083Y743767D01*
X127417Y744433D01*
X127500Y745183D01*
X127417Y745850D01*
X127000Y746517D01*
X126500Y746933D01*
X126000Y747017D01*
X125417Y746850D01*
X125000Y746267D01*
X124833Y745683D01*
Y744933D01*
G01Y745683D02*
X124583Y746183D01*
X124167Y746600D01*
X123667Y746767D01*
X123167Y746600D01*
X122750Y746183D01*
X122500Y745433D01*
X122583Y744683D01*
X122917Y743933D01*
G01X127667Y750700D02*
X127583Y750533D01*
X127417D01*
X127333Y750700D01*
X127417Y750867D01*
X127583D01*
X127667Y750700D01*
G01X125417D02*
X125333Y750533D01*
X125167D01*
X125083Y750700D01*
X125167Y750867D01*
X125333D01*
X125417Y750700D01*
G01X126500Y754467D02*
X127083Y754967D01*
X127417Y755633D01*
X127500Y756383D01*
X127417Y757050D01*
X127000Y757717D01*
X126500Y758133D01*
X126000Y758217D01*
X125417Y758050D01*
X125000Y757467D01*
X124833Y756883D01*
Y756133D01*
G01Y756883D02*
X124583Y757383D01*
X124167Y757800D01*
X123667Y757967D01*
X123167Y757800D01*
X122750Y757383D01*
X122500Y756633D01*
X122583Y755883D01*
X122917Y755133D01*
G01X127500Y759817D02*
X122500Y761900D01*
X127500Y763983D01*
G01X125750Y763233D02*
Y760567D01*
G01X127667Y766000D02*
X122500Y769000D01*
G01X127500Y773100D02*
X122500D01*
X123500Y772100D01*
G01X127500D02*
Y774100D01*
G01X126750Y776867D02*
X127167Y777367D01*
X127417Y777950D01*
X127500Y778700D01*
X127333Y779450D01*
X127000Y780033D01*
X126417Y780450D01*
X125750Y780533D01*
X125083Y780367D01*
X124667Y779950D01*
X124333Y779367D01*
X124250Y778783D01*
X124333Y778200D01*
X124667Y777450D01*
X122500Y777700D01*
Y779950D01*
G01Y782217D02*
X127500Y784300D01*
X122500Y786383D01*
G01X105402Y769397D02*
Y746397D01*
G01X105000Y713033D02*
X102500D01*
Y713867D01*
X102625Y714200D01*
X102792Y714450D01*
X103042Y714658D01*
X103333Y714825D01*
X103750Y714867D01*
X104167Y714825D01*
X104458Y714658D01*
X104708Y714450D01*
X104875Y714200D01*
X105000Y713867D01*
Y713033D01*
G01Y717050D02*
X104958Y717342D01*
X104833Y717675D01*
X104625Y717883D01*
X104333Y717967D01*
X104042Y717883D01*
X103792Y717633D01*
X103667Y717258D01*
Y716842D01*
X103583Y716592D01*
X103375Y716383D01*
X103083Y716300D01*
X102792Y716425D01*
X102583Y716717D01*
X102500Y717050D01*
X102583Y717383D01*
X102792Y717675D01*
X103083Y717800D01*
X103375Y717717D01*
X103583Y717508D01*
X103667Y717258D01*
Y716842D01*
X103792Y716467D01*
X104042Y716217D01*
X104333Y716133D01*
X104625Y716217D01*
X104833Y716425D01*
X104958Y716758D01*
X105000Y717050D01*
G01X99000Y711400D02*
Y719400D01*
G01X104000Y738033D02*
X101500D01*
Y738867D01*
X101625Y739200D01*
X101792Y739450D01*
X102042Y739658D01*
X102333Y739825D01*
X102750Y739867D01*
X103167Y739825D01*
X103458Y739658D01*
X103708Y739450D01*
X103875Y739200D01*
X104000Y738867D01*
Y738033D01*
G01X102958Y741258D02*
X102667Y741550D01*
X102500Y741800D01*
X102417Y742133D01*
X102500Y742425D01*
X102667Y742633D01*
X102917Y742800D01*
X103208Y742842D01*
X103458Y742800D01*
X103708Y742633D01*
X103917Y742383D01*
X104000Y742092D01*
X103917Y741758D01*
X103667Y741467D01*
X103292Y741300D01*
X102875Y741258D01*
X102333Y741342D01*
X102042Y741467D01*
X101750Y741675D01*
X101542Y741967D01*
X101500Y742258D01*
X101583Y742550D01*
X101792Y742758D01*
G01X98500Y736400D02*
Y744400D01*
G01X113000Y719467D02*
X110500D01*
Y720467D01*
X110625Y720800D01*
X110917Y721050D01*
X111250Y721133D01*
X111583Y721050D01*
X111833Y720842D01*
X111958Y720467D01*
Y719467D01*
G01X113000Y722567D02*
X110500D01*
Y723608D01*
X110625Y723942D01*
X110792Y724150D01*
X111125Y724233D01*
X111458Y724150D01*
X111667Y723900D01*
X111792Y723608D01*
Y722567D01*
G01Y723608D02*
X113000Y724233D01*
G01Y726500D02*
X110500D01*
X111000Y726000D01*
G01X113000D02*
Y727000D01*
G01Y729600D02*
X110500D01*
X111000Y729100D01*
G01X113000D02*
Y730100D01*
G01Y732617D02*
X112458Y732700D01*
X112000Y732825D01*
X111583Y732992D01*
X111125Y733200D01*
X110500Y733533D01*
Y731867D01*
G01X91000Y722067D02*
X88500D01*
Y723108D01*
X88625Y723442D01*
X88792Y723650D01*
X89125Y723733D01*
X89458Y723650D01*
X89667Y723400D01*
X89792Y723108D01*
Y722067D01*
G01Y723108D02*
X91000Y723733D01*
G01Y726000D02*
X90958Y726292D01*
X90833Y726625D01*
X90625Y726833D01*
X90333Y726917D01*
X90042Y726833D01*
X89792Y726583D01*
X89667Y726208D01*
Y725792D01*
X89583Y725542D01*
X89375Y725333D01*
X89083Y725250D01*
X88792Y725375D01*
X88583Y725667D01*
X88500Y726000D01*
X88583Y726333D01*
X88792Y726625D01*
X89083Y726750D01*
X89375Y726667D01*
X89583Y726458D01*
X89667Y726208D01*
Y725792D01*
X89792Y725417D01*
X90042Y725167D01*
X90333Y725083D01*
X90625Y725167D01*
X90833Y725375D01*
X90958Y725708D01*
X91000Y726000D01*
G01X90625Y728183D02*
X90833Y728433D01*
X90958Y728725D01*
X91000Y729100D01*
X90917Y729475D01*
X90750Y729767D01*
X90458Y729975D01*
X90125Y730017D01*
X89792Y729933D01*
X89583Y729725D01*
X89417Y729433D01*
X89375Y729142D01*
X89417Y728850D01*
X89583Y728475D01*
X88500Y728600D01*
Y729725D01*
G01X93067Y731500D02*
Y734000D01*
X94108D01*
X94442Y733875D01*
X94650Y733708D01*
X94733Y733375D01*
X94650Y733042D01*
X94400Y732833D01*
X94108Y732708D01*
X93067D01*
G01X94108D02*
X94733Y731500D01*
G01X97000D02*
X97292Y731542D01*
X97625Y731667D01*
X97833Y731875D01*
X97917Y732167D01*
X97833Y732458D01*
X97583Y732708D01*
X97208Y732833D01*
X96792D01*
X96542Y732917D01*
X96333Y733125D01*
X96250Y733417D01*
X96375Y733708D01*
X96667Y733917D01*
X97000Y734000D01*
X97333Y733917D01*
X97625Y733708D01*
X97750Y733417D01*
X97667Y733125D01*
X97458Y732917D01*
X97208Y732833D01*
X96792D01*
X96417Y732708D01*
X96167Y732458D01*
X96083Y732167D01*
X96167Y731875D01*
X96375Y731667D01*
X96708Y731542D01*
X97000Y731500D01*
G01X100100D02*
Y734000D01*
X99600Y733500D01*
G01Y731500D02*
X100600D01*
G01X128900Y733300D02*
Y719300D01*
G01X141900Y733300D02*
X128900D01*
G01Y719300D02*
X141900D01*
G01X105200Y807400D02*
X94000D01*
G01X105200Y789400D02*
Y807400D01*
G01X94000Y789400D02*
X105200D01*
G01X111917Y779692D02*
X111667Y779817D01*
X111375Y779900D01*
X111042D01*
X110667Y779775D01*
X110375Y779567D01*
X110167Y779317D01*
X110000Y778900D01*
X109958Y778525D01*
X110042Y778150D01*
X110167Y777900D01*
X110417Y777650D01*
X110708Y777483D01*
X111000Y777400D01*
X111292D01*
X111583Y777483D01*
X111833Y777608D01*
X112042Y777775D01*
G01X114600Y777400D02*
Y779900D01*
X113058Y778108D01*
X115142D01*
G01X116408Y779483D02*
X116658Y779733D01*
X116950Y779858D01*
X117283Y779900D01*
X117700Y779817D01*
X117992Y779608D01*
X118075Y779358D01*
X118033Y779108D01*
X117867Y778900D01*
X117033Y778483D01*
X116658Y778192D01*
X116408Y777775D01*
X116325Y777400D01*
X118075D01*
G01X111917Y775692D02*
X111667Y775817D01*
X111375Y775900D01*
X111042D01*
X110667Y775775D01*
X110375Y775567D01*
X110167Y775317D01*
X110000Y774900D01*
X109958Y774525D01*
X110042Y774150D01*
X110167Y773900D01*
X110417Y773650D01*
X110708Y773483D01*
X111000Y773400D01*
X111292D01*
X111583Y773483D01*
X111833Y773608D01*
X112042Y773775D01*
G01X114600Y773400D02*
Y775900D01*
X113058Y774108D01*
X115142D01*
G01X117200Y773400D02*
Y775900D01*
X116700Y775400D01*
G01Y773400D02*
X117700D01*
G01X96517Y775300D02*
Y777800D01*
X97558D01*
X97892Y777675D01*
X98100Y777508D01*
X98183Y777175D01*
X98100Y776842D01*
X97850Y776633D01*
X97558Y776508D01*
X96517D01*
G01X97558D02*
X98183Y775300D01*
G01X100450D02*
Y777800D01*
X99950Y777300D01*
G01Y775300D02*
X100950D01*
G01X103550D02*
X103842Y775342D01*
X104175Y775467D01*
X104383Y775675D01*
X104467Y775967D01*
X104383Y776258D01*
X104133Y776508D01*
X103758Y776633D01*
X103342D01*
X103092Y776717D01*
X102883Y776925D01*
X102800Y777217D01*
X102925Y777508D01*
X103217Y777717D01*
X103550Y777800D01*
X103883Y777717D01*
X104175Y777508D01*
X104300Y777217D01*
X104217Y776925D01*
X104008Y776717D01*
X103758Y776633D01*
X103342D01*
X102967Y776508D01*
X102717Y776258D01*
X102633Y775967D01*
X102717Y775675D01*
X102925Y775467D01*
X103258Y775342D01*
X103550Y775300D01*
G01X106650Y777800D02*
X106317Y777717D01*
X106067Y777508D01*
X105900Y777258D01*
X105775Y776925D01*
X105733Y776550D01*
X105775Y776175D01*
X105900Y775842D01*
X106067Y775592D01*
X106317Y775383D01*
X106650Y775300D01*
X106983Y775383D01*
X107233Y775592D01*
X107400Y775842D01*
X107525Y776175D01*
X107567Y776550D01*
X107525Y776925D01*
X107400Y777258D01*
X107233Y777508D01*
X106983Y777717D01*
X106650Y777800D01*
G01X95000Y772700D02*
Y780700D01*
G01X116900Y864404D02*
Y850404D01*
X96800D01*
Y864404D01*
X116900D01*
G01X96950Y859254D02*
X97050D01*
X98900Y857404D01*
X97100Y855604D01*
X97000D01*
G01X126000Y826017D02*
X123500D01*
Y827058D01*
X123625Y827392D01*
X123792Y827600D01*
X124125Y827683D01*
X124458Y827600D01*
X124667Y827350D01*
X124792Y827058D01*
Y826017D01*
G01Y827058D02*
X126000Y827683D01*
G01Y829950D02*
X123500D01*
X124000Y829450D01*
G01X126000D02*
Y830450D01*
G01X125500Y832133D02*
X125792Y832383D01*
X125958Y832717D01*
X126000Y833092D01*
X125958Y833425D01*
X125750Y833758D01*
X125500Y833967D01*
X125250Y834008D01*
X124958Y833925D01*
X124750Y833633D01*
X124667Y833342D01*
Y832967D01*
G01Y833342D02*
X124542Y833592D01*
X124333Y833800D01*
X124083Y833883D01*
X123833Y833800D01*
X123625Y833592D01*
X123500Y833217D01*
X123542Y832842D01*
X123708Y832467D01*
G01X125708Y835442D02*
X125917Y835733D01*
X126000Y836067D01*
X125917Y836400D01*
X125667Y836692D01*
X125292Y836900D01*
X124917Y836983D01*
X124458D01*
X124083Y836900D01*
X123750Y836692D01*
X123583Y836442D01*
X123500Y836150D01*
X123583Y835817D01*
X123750Y835567D01*
X124000Y835400D01*
X124333Y835317D01*
X124625Y835400D01*
X124917Y835608D01*
X125083Y835858D01*
X125125Y836150D01*
X125042Y836483D01*
X124833Y836733D01*
X124458Y836983D01*
G01X117600Y826400D02*
X121600D01*
Y833800D01*
G01X116500Y826517D02*
X114000D01*
Y827558D01*
X114125Y827892D01*
X114292Y828100D01*
X114625Y828183D01*
X114958Y828100D01*
X115167Y827850D01*
X115292Y827558D01*
Y826517D01*
G01Y827558D02*
X116500Y828183D01*
G01Y830450D02*
X114000D01*
X114500Y829950D01*
G01X116500D02*
Y830950D01*
G01X116000Y832633D02*
X116292Y832883D01*
X116458Y833217D01*
X116500Y833592D01*
X116458Y833925D01*
X116250Y834258D01*
X116000Y834467D01*
X115750Y834508D01*
X115458Y834425D01*
X115250Y834133D01*
X115167Y833842D01*
Y833467D01*
G01Y833842D02*
X115042Y834092D01*
X114833Y834300D01*
X114583Y834383D01*
X114333Y834300D01*
X114125Y834092D01*
X114000Y833717D01*
X114042Y833342D01*
X114208Y832967D01*
G01X116500Y836567D02*
X115958Y836650D01*
X115500Y836775D01*
X115083Y836942D01*
X114625Y837150D01*
X114000Y837483D01*
Y835817D01*
G01X109200Y826400D02*
X113200D01*
Y833800D01*
G01X108500Y826517D02*
X106000D01*
Y827558D01*
X106125Y827892D01*
X106292Y828100D01*
X106625Y828183D01*
X106958Y828100D01*
X107167Y827850D01*
X107292Y827558D01*
Y826517D01*
G01Y827558D02*
X108500Y828183D01*
G01Y830450D02*
X106000D01*
X106500Y829950D01*
G01X108500D02*
Y830950D01*
G01X108000Y832633D02*
X108292Y832883D01*
X108458Y833217D01*
X108500Y833592D01*
X108458Y833925D01*
X108250Y834258D01*
X108000Y834467D01*
X107750Y834508D01*
X107458Y834425D01*
X107250Y834133D01*
X107167Y833842D01*
Y833467D01*
G01Y833842D02*
X107042Y834092D01*
X106833Y834300D01*
X106583Y834383D01*
X106333Y834300D01*
X106125Y834092D01*
X106000Y833717D01*
X106042Y833342D01*
X106208Y832967D01*
G01X107458Y835858D02*
X107167Y836150D01*
X107000Y836400D01*
X106917Y836733D01*
X107000Y837025D01*
X107167Y837233D01*
X107417Y837400D01*
X107708Y837442D01*
X107958Y837400D01*
X108208Y837233D01*
X108417Y836983D01*
X108500Y836692D01*
X108417Y836358D01*
X108167Y836067D01*
X107792Y835900D01*
X107375Y835858D01*
X106833Y835942D01*
X106542Y836067D01*
X106250Y836275D01*
X106042Y836567D01*
X106000Y836858D01*
X106083Y837150D01*
X106292Y837358D01*
G01X100900Y826396D02*
X104900D01*
Y833796D01*
G01X102033Y877000D02*
Y875208D01*
X102200Y874833D01*
X102533Y874583D01*
X102950Y874500D01*
X103367Y874583D01*
X103700Y874833D01*
X103867Y875208D01*
Y877000D01*
G01X105967Y874500D02*
X106050Y875042D01*
X106175Y875500D01*
X106342Y875917D01*
X106550Y876375D01*
X106883Y877000D01*
X105217D01*
G01X90708Y883317D02*
X90583Y883067D01*
X90500Y882775D01*
Y882442D01*
X90625Y882067D01*
X90833Y881775D01*
X91083Y881567D01*
X91500Y881400D01*
X91875Y881358D01*
X92250Y881442D01*
X92500Y881567D01*
X92750Y881817D01*
X92917Y882108D01*
X93000Y882400D01*
Y882692D01*
X92917Y882983D01*
X92792Y883233D01*
X92625Y883442D01*
G01X93000Y885500D02*
X90500D01*
X91000Y885000D01*
G01X93000D02*
Y886000D01*
G01X92625Y887683D02*
X92833Y887933D01*
X92958Y888225D01*
X93000Y888600D01*
X92917Y888975D01*
X92750Y889267D01*
X92458Y889475D01*
X92125Y889517D01*
X91792Y889433D01*
X91583Y889225D01*
X91417Y888933D01*
X91375Y888642D01*
X91417Y888350D01*
X91583Y887975D01*
X90500Y888100D01*
Y889225D01*
G01X86708Y883317D02*
X86583Y883067D01*
X86500Y882775D01*
Y882442D01*
X86625Y882067D01*
X86833Y881775D01*
X87083Y881567D01*
X87500Y881400D01*
X87875Y881358D01*
X88250Y881442D01*
X88500Y881567D01*
X88750Y881817D01*
X88917Y882108D01*
X89000Y882400D01*
Y882692D01*
X88917Y882983D01*
X88792Y883233D01*
X88625Y883442D01*
G01X89000Y885500D02*
X86500D01*
X87000Y885000D01*
G01X89000D02*
Y886000D01*
G01X87958Y887808D02*
X87667Y888100D01*
X87500Y888350D01*
X87417Y888683D01*
X87500Y888975D01*
X87667Y889183D01*
X87917Y889350D01*
X88208Y889392D01*
X88458Y889350D01*
X88708Y889183D01*
X88917Y888933D01*
X89000Y888642D01*
X88917Y888308D01*
X88667Y888017D01*
X88292Y887850D01*
X87875Y887808D01*
X87333Y887892D01*
X87042Y888017D01*
X86750Y888225D01*
X86542Y888517D01*
X86500Y888808D01*
X86583Y889100D01*
X86792Y889308D01*
G01X111500Y889017D02*
X109000D01*
Y890058D01*
X109125Y890392D01*
X109292Y890600D01*
X109625Y890683D01*
X109958Y890600D01*
X110167Y890350D01*
X110292Y890058D01*
Y889017D01*
G01Y890058D02*
X111500Y890683D01*
G01Y892950D02*
X109000D01*
X109500Y892450D01*
G01X111500D02*
Y893450D01*
G01Y896550D02*
X109000D01*
X110792Y895008D01*
Y897092D01*
G01X109000Y899150D02*
X109083Y898817D01*
X109292Y898567D01*
X109542Y898400D01*
X109875Y898275D01*
X110250Y898233D01*
X110625Y898275D01*
X110958Y898400D01*
X111208Y898567D01*
X111417Y898817D01*
X111500Y899150D01*
X111417Y899483D01*
X111208Y899733D01*
X110958Y899900D01*
X110625Y900025D01*
X110250Y900067D01*
X109875Y900025D01*
X109542Y899900D01*
X109292Y899733D01*
X109083Y899483D01*
X109000Y899150D01*
G01X112900Y886800D02*
X108900D01*
Y879400D01*
G01X103500Y889017D02*
X101000D01*
Y890058D01*
X101125Y890392D01*
X101292Y890600D01*
X101625Y890683D01*
X101958Y890600D01*
X102167Y890350D01*
X102292Y890058D01*
Y889017D01*
G01Y890058D02*
X103500Y890683D01*
G01Y892950D02*
X101000D01*
X101500Y892450D01*
G01X103500D02*
Y893450D01*
G01Y896550D02*
X101000D01*
X102792Y895008D01*
Y897092D01*
G01X103500Y899150D02*
X101000D01*
X101500Y898650D01*
G01X103500D02*
Y899650D01*
G01X104600Y886800D02*
X100600D01*
Y879400D01*
G01X119500Y889017D02*
X117000D01*
Y890058D01*
X117125Y890392D01*
X117292Y890600D01*
X117625Y890683D01*
X117958Y890600D01*
X118167Y890350D01*
X118292Y890058D01*
Y889017D01*
G01Y890058D02*
X119500Y890683D01*
G01Y892950D02*
X117000D01*
X117500Y892450D01*
G01X119500D02*
Y893450D01*
G01X119000Y895133D02*
X119292Y895383D01*
X119458Y895717D01*
X119500Y896092D01*
X119458Y896425D01*
X119250Y896758D01*
X119000Y896967D01*
X118750Y897008D01*
X118458Y896925D01*
X118250Y896633D01*
X118167Y896342D01*
Y895967D01*
G01Y896342D02*
X118042Y896592D01*
X117833Y896800D01*
X117583Y896883D01*
X117333Y896800D01*
X117125Y896592D01*
X117000Y896217D01*
X117042Y895842D01*
X117208Y895467D01*
G01X119500Y899150D02*
X119458Y899442D01*
X119333Y899775D01*
X119125Y899983D01*
X118833Y900067D01*
X118542Y899983D01*
X118292Y899733D01*
X118167Y899358D01*
Y898942D01*
X118083Y898692D01*
X117875Y898483D01*
X117583Y898400D01*
X117292Y898525D01*
X117083Y898817D01*
X117000Y899150D01*
X117083Y899483D01*
X117292Y899775D01*
X117583Y899900D01*
X117875Y899817D01*
X118083Y899608D01*
X118167Y899358D01*
Y898942D01*
X118292Y898567D01*
X118542Y898317D01*
X118833Y898233D01*
X119125Y898317D01*
X119333Y898525D01*
X119458Y898858D01*
X119500Y899150D01*
G01X121300Y886800D02*
X117300D01*
Y879400D01*
G01X101500Y952517D02*
X99000D01*
Y953517D01*
X99125Y953850D01*
X99417Y954100D01*
X99750Y954183D01*
X100083Y954100D01*
X100333Y953892D01*
X100458Y953517D01*
Y952517D01*
G01X101500Y955617D02*
X99000D01*
Y956658D01*
X99125Y956992D01*
X99292Y957200D01*
X99625Y957283D01*
X99958Y957200D01*
X100167Y956950D01*
X100292Y956658D01*
Y955617D01*
G01Y956658D02*
X101500Y957283D01*
G01X101125Y958633D02*
X101333Y958883D01*
X101458Y959175D01*
X101500Y959550D01*
X101417Y959925D01*
X101250Y960217D01*
X100958Y960425D01*
X100625Y960467D01*
X100292Y960383D01*
X100083Y960175D01*
X99917Y959883D01*
X99875Y959592D01*
X99917Y959300D01*
X100083Y958925D01*
X99000Y959050D01*
Y960175D01*
G01X101500Y963150D02*
X99000D01*
X100792Y961608D01*
Y963692D01*
G01X96000Y915017D02*
X93500D01*
Y916017D01*
X93625Y916350D01*
X93917Y916600D01*
X94250Y916683D01*
X94583Y916600D01*
X94833Y916392D01*
X94958Y916017D01*
Y915017D01*
G01X93708Y919867D02*
X93583Y919617D01*
X93500Y919325D01*
Y918992D01*
X93625Y918617D01*
X93833Y918325D01*
X94083Y918117D01*
X94500Y917950D01*
X94875Y917908D01*
X95250Y917992D01*
X95500Y918117D01*
X95750Y918367D01*
X95917Y918658D01*
X96000Y918950D01*
Y919242D01*
X95917Y919533D01*
X95792Y919783D01*
X95625Y919992D01*
G01X96000Y922550D02*
X93500D01*
X95292Y921008D01*
Y923092D01*
G01X95500Y924233D02*
X95792Y924483D01*
X95958Y924817D01*
X96000Y925192D01*
X95958Y925525D01*
X95750Y925858D01*
X95500Y926067D01*
X95250Y926108D01*
X94958Y926025D01*
X94750Y925733D01*
X94667Y925442D01*
Y925067D01*
G01Y925442D02*
X94542Y925692D01*
X94333Y925900D01*
X94083Y925983D01*
X93833Y925900D01*
X93625Y925692D01*
X93500Y925317D01*
X93542Y924942D01*
X93708Y924567D01*
G01X100000Y945300D02*
Y939800D01*
G01X92000Y945300D02*
X100000D01*
G01X92000Y939800D02*
Y945300D01*
G01Y927700D02*
Y933200D01*
G01X100000Y927700D02*
X92000D01*
G01X100000Y933200D02*
Y927700D01*
G01X121500Y925067D02*
X119000D01*
Y926108D01*
X119125Y926442D01*
X119292Y926650D01*
X119625Y926733D01*
X119958Y926650D01*
X120167Y926400D01*
X120292Y926108D01*
Y925067D01*
G01Y926108D02*
X121500Y926733D01*
G01Y929500D02*
X119000D01*
X120792Y927958D01*
Y930042D01*
G01X121500Y932600D02*
X119000D01*
X120792Y931058D01*
Y933142D01*
G01X124529Y957744D02*
X120529D01*
Y950344D01*
G01X117500Y925067D02*
X115000D01*
Y926108D01*
X115125Y926442D01*
X115292Y926650D01*
X115625Y926733D01*
X115958Y926650D01*
X116167Y926400D01*
X116292Y926108D01*
Y925067D01*
G01Y926108D02*
X117500Y926733D01*
G01Y929500D02*
X115000D01*
X116792Y927958D01*
Y930042D01*
G01X117000Y931183D02*
X117292Y931433D01*
X117458Y931767D01*
X117500Y932142D01*
X117458Y932475D01*
X117250Y932808D01*
X117000Y933017D01*
X116750Y933058D01*
X116458Y932975D01*
X116250Y932683D01*
X116167Y932392D01*
Y932017D01*
G01Y932392D02*
X116042Y932642D01*
X115833Y932850D01*
X115583Y932933D01*
X115333Y932850D01*
X115125Y932642D01*
X115000Y932267D01*
X115042Y931892D01*
X115208Y931517D01*
G01X119529Y957744D02*
X115529D01*
Y950344D01*
G01X113500Y925067D02*
X111000D01*
Y926108D01*
X111125Y926442D01*
X111292Y926650D01*
X111625Y926733D01*
X111958Y926650D01*
X112167Y926400D01*
X112292Y926108D01*
Y925067D01*
G01Y926108D02*
X113500Y926733D01*
G01Y929500D02*
X111000D01*
X112792Y927958D01*
Y930042D01*
G01X111417Y931308D02*
X111167Y931558D01*
X111042Y931850D01*
X111000Y932183D01*
X111083Y932600D01*
X111292Y932892D01*
X111542Y932975D01*
X111792Y932933D01*
X112000Y932767D01*
X112417Y931933D01*
X112708Y931558D01*
X113125Y931308D01*
X113500Y931225D01*
Y932975D01*
G01X114529Y957744D02*
X110529D01*
Y950344D01*
G01X122071Y914623D02*
X119571D01*
Y915664D01*
X119696Y915998D01*
X119863Y916206D01*
X120196Y916289D01*
X120529Y916206D01*
X120738Y915956D01*
X120863Y915664D01*
Y914623D01*
G01Y915664D02*
X122071Y916289D01*
G01Y919056D02*
X119571D01*
X121363Y917514D01*
Y919598D01*
G01X122071Y921656D02*
X119571D01*
X120071Y921156D01*
G01X122071D02*
Y922156D01*
G01X119671Y934356D02*
X123671D01*
Y941756D01*
G01X117700Y914567D02*
X115200D01*
Y915608D01*
X115325Y915942D01*
X115492Y916150D01*
X115825Y916233D01*
X116158Y916150D01*
X116367Y915900D01*
X116492Y915608D01*
Y914567D01*
G01Y915608D02*
X117700Y916233D01*
G01Y919000D02*
X115200D01*
X116992Y917458D01*
Y919542D01*
G01X115200Y921600D02*
X115283Y921267D01*
X115492Y921017D01*
X115742Y920850D01*
X116075Y920725D01*
X116450Y920683D01*
X116825Y920725D01*
X117158Y920850D01*
X117408Y921017D01*
X117617Y921267D01*
X117700Y921600D01*
X117617Y921933D01*
X117408Y922183D01*
X117158Y922350D01*
X116825Y922475D01*
X116450Y922517D01*
X116075Y922475D01*
X115742Y922350D01*
X115492Y922183D01*
X115283Y921933D01*
X115200Y921600D01*
G01X115300Y934300D02*
X119300D01*
Y941700D01*
G01X112500Y914567D02*
X110000D01*
Y915608D01*
X110125Y915942D01*
X110292Y916150D01*
X110625Y916233D01*
X110958Y916150D01*
X111167Y915900D01*
X111292Y915608D01*
Y914567D01*
G01Y915608D02*
X112500Y916233D01*
G01X112000Y917583D02*
X112292Y917833D01*
X112458Y918167D01*
X112500Y918542D01*
X112458Y918875D01*
X112250Y919208D01*
X112000Y919417D01*
X111750Y919458D01*
X111458Y919375D01*
X111250Y919083D01*
X111167Y918792D01*
Y918417D01*
G01Y918792D02*
X111042Y919042D01*
X110833Y919250D01*
X110583Y919333D01*
X110333Y919250D01*
X110125Y919042D01*
X110000Y918667D01*
X110042Y918292D01*
X110208Y917917D01*
G01X112208Y920892D02*
X112417Y921183D01*
X112500Y921517D01*
X112417Y921850D01*
X112167Y922142D01*
X111792Y922350D01*
X111417Y922433D01*
X110958D01*
X110583Y922350D01*
X110250Y922142D01*
X110083Y921892D01*
X110000Y921600D01*
X110083Y921267D01*
X110250Y921017D01*
X110500Y920850D01*
X110833Y920767D01*
X111125Y920850D01*
X111417Y921058D01*
X111583Y921308D01*
X111625Y921600D01*
X111542Y921933D01*
X111333Y922183D01*
X110958Y922433D01*
G01X108500Y934300D02*
X112500D01*
Y941700D01*
G01X137500Y931067D02*
X135000D01*
Y932108D01*
X135125Y932442D01*
X135292Y932650D01*
X135625Y932733D01*
X135958Y932650D01*
X136167Y932400D01*
X136292Y932108D01*
Y931067D01*
G01Y932108D02*
X137500Y932733D01*
G01X137125Y934083D02*
X137333Y934333D01*
X137458Y934625D01*
X137500Y935000D01*
X137417Y935375D01*
X137250Y935667D01*
X136958Y935875D01*
X136625Y935917D01*
X136292Y935833D01*
X136083Y935625D01*
X135917Y935333D01*
X135875Y935042D01*
X135917Y934750D01*
X136083Y934375D01*
X135000Y934500D01*
Y935625D01*
G01X137125Y937183D02*
X137333Y937433D01*
X137458Y937725D01*
X137500Y938100D01*
X137417Y938475D01*
X137250Y938767D01*
X136958Y938975D01*
X136625Y939017D01*
X136292Y938933D01*
X136083Y938725D01*
X135917Y938433D01*
X135875Y938142D01*
X135917Y937850D01*
X136083Y937475D01*
X135000Y937600D01*
Y938725D01*
G01X134000Y942400D02*
X138000D01*
Y949800D01*
G01X133500Y931067D02*
X131000D01*
Y932108D01*
X131125Y932442D01*
X131292Y932650D01*
X131625Y932733D01*
X131958Y932650D01*
X132167Y932400D01*
X132292Y932108D01*
Y931067D01*
G01Y932108D02*
X133500Y932733D01*
G01X133125Y934083D02*
X133333Y934333D01*
X133458Y934625D01*
X133500Y935000D01*
X133417Y935375D01*
X133250Y935667D01*
X132958Y935875D01*
X132625Y935917D01*
X132292Y935833D01*
X132083Y935625D01*
X131917Y935333D01*
X131875Y935042D01*
X131917Y934750D01*
X132083Y934375D01*
X131000Y934500D01*
Y935625D01*
G01X133500Y938600D02*
X131000D01*
X132792Y937058D01*
Y939142D01*
G01X129500Y942400D02*
X133500D01*
Y949800D01*
G01X106500Y916017D02*
X104000D01*
Y917058D01*
X104125Y917392D01*
X104292Y917600D01*
X104625Y917683D01*
X104958Y917600D01*
X105167Y917350D01*
X105292Y917058D01*
Y916017D01*
G01Y917058D02*
X106500Y917683D01*
G01Y919950D02*
X104000D01*
X104500Y919450D01*
G01X106500D02*
Y920450D01*
G01X106125Y922133D02*
X106333Y922383D01*
X106458Y922675D01*
X106500Y923050D01*
X106417Y923425D01*
X106250Y923717D01*
X105958Y923925D01*
X105625Y923967D01*
X105292Y923883D01*
X105083Y923675D01*
X104917Y923383D01*
X104875Y923092D01*
X104917Y922800D01*
X105083Y922425D01*
X104000Y922550D01*
Y923675D01*
G01X106500Y926650D02*
X104000D01*
X105792Y925108D01*
Y927192D01*
G01X101000Y943200D02*
X108000D01*
Y929800D01*
X101000D01*
Y943200D01*
G01X136300Y970600D02*
X134100Y968400D01*
G01X136300Y970600D02*
X134100Y972800D01*
G01Y977600D02*
Y963600D01*
G01X155600D02*
X134800D01*
G01X134100Y977600D02*
X155600D01*
G01X111033Y993500D02*
Y991708D01*
X111200Y991333D01*
X111533Y991083D01*
X111950Y991000D01*
X112367Y991083D01*
X112700Y991333D01*
X112867Y991708D01*
Y993500D01*
G01X114133Y991375D02*
X114383Y991167D01*
X114675Y991042D01*
X115050Y991000D01*
X115425Y991083D01*
X115717Y991250D01*
X115925Y991542D01*
X115967Y991875D01*
X115883Y992208D01*
X115675Y992417D01*
X115383Y992583D01*
X115092Y992625D01*
X114800Y992583D01*
X114425Y992417D01*
X114550Y993500D01*
X115675D01*
G01X96000Y986017D02*
X93500D01*
Y987017D01*
X93625Y987350D01*
X93917Y987600D01*
X94250Y987683D01*
X94583Y987600D01*
X94833Y987392D01*
X94958Y987017D01*
Y986017D01*
G01X96000Y989117D02*
X93500D01*
Y990158D01*
X93625Y990492D01*
X93792Y990700D01*
X94125Y990783D01*
X94458Y990700D01*
X94667Y990450D01*
X94792Y990158D01*
Y989117D01*
G01Y990158D02*
X96000Y990783D01*
G01X95625Y992133D02*
X95833Y992383D01*
X95958Y992675D01*
X96000Y993050D01*
X95917Y993425D01*
X95750Y993717D01*
X95458Y993925D01*
X95125Y993967D01*
X94792Y993883D01*
X94583Y993675D01*
X94417Y993383D01*
X94375Y993092D01*
X94417Y992800D01*
X94583Y992425D01*
X93500Y992550D01*
Y993675D01*
G01X94958Y995358D02*
X94667Y995650D01*
X94500Y995900D01*
X94417Y996233D01*
X94500Y996525D01*
X94667Y996733D01*
X94917Y996900D01*
X95208Y996942D01*
X95458Y996900D01*
X95708Y996733D01*
X95917Y996483D01*
X96000Y996192D01*
X95917Y995858D01*
X95667Y995567D01*
X95292Y995400D01*
X94875Y995358D01*
X94333Y995442D01*
X94042Y995567D01*
X93750Y995775D01*
X93542Y996067D01*
X93500Y996358D01*
X93583Y996650D01*
X93792Y996858D01*
G01X101317Y1009792D02*
X101067Y1009917D01*
X100775Y1010000D01*
X100442D01*
X100067Y1009875D01*
X99775Y1009667D01*
X99567Y1009417D01*
X99400Y1009000D01*
X99358Y1008625D01*
X99442Y1008250D01*
X99567Y1008000D01*
X99817Y1007750D01*
X100108Y1007583D01*
X100400Y1007500D01*
X100692D01*
X100983Y1007583D01*
X101233Y1007708D01*
X101442Y1007875D01*
G01X103500Y1007500D02*
Y1010000D01*
X103000Y1009500D01*
G01Y1007500D02*
X104000D01*
G01X107100D02*
Y1010000D01*
X105558Y1008208D01*
X107642D01*
G01X101317Y1013792D02*
X101067Y1013917D01*
X100775Y1014000D01*
X100442D01*
X100067Y1013875D01*
X99775Y1013667D01*
X99567Y1013417D01*
X99400Y1013000D01*
X99358Y1012625D01*
X99442Y1012250D01*
X99567Y1012000D01*
X99817Y1011750D01*
X100108Y1011583D01*
X100400Y1011500D01*
X100692D01*
X100983Y1011583D01*
X101233Y1011708D01*
X101442Y1011875D01*
G01X103500Y1011500D02*
Y1014000D01*
X103000Y1013500D01*
G01Y1011500D02*
X104000D01*
G01X105683Y1012000D02*
X105933Y1011708D01*
X106267Y1011542D01*
X106642Y1011500D01*
X106975Y1011542D01*
X107308Y1011750D01*
X107517Y1012000D01*
X107558Y1012250D01*
X107475Y1012542D01*
X107183Y1012750D01*
X106892Y1012833D01*
X106517D01*
G01X106892D02*
X107142Y1012958D01*
X107350Y1013167D01*
X107433Y1013417D01*
X107350Y1013667D01*
X107142Y1013875D01*
X106767Y1014000D01*
X106392Y1013958D01*
X106017Y1013792D01*
G01X107500Y994017D02*
X105000D01*
Y995017D01*
X105125Y995350D01*
X105417Y995600D01*
X105750Y995683D01*
X106083Y995600D01*
X106333Y995392D01*
X106458Y995017D01*
Y994017D01*
G01X105208Y998867D02*
X105083Y998617D01*
X105000Y998325D01*
Y997992D01*
X105125Y997617D01*
X105333Y997325D01*
X105583Y997117D01*
X106000Y996950D01*
X106375Y996908D01*
X106750Y996992D01*
X107000Y997117D01*
X107250Y997367D01*
X107417Y997658D01*
X107500Y997950D01*
Y998242D01*
X107417Y998533D01*
X107292Y998783D01*
X107125Y998992D01*
G01X107500Y1001550D02*
X105000D01*
X106792Y1000008D01*
Y1002092D01*
G01X105417Y1003358D02*
X105167Y1003608D01*
X105042Y1003900D01*
X105000Y1004233D01*
X105083Y1004650D01*
X105292Y1004942D01*
X105542Y1005025D01*
X105792Y1004983D01*
X106000Y1004817D01*
X106417Y1003983D01*
X106708Y1003608D01*
X107125Y1003358D01*
X107500Y1003275D01*
Y1005025D01*
G01X135208Y989317D02*
X135083Y989067D01*
X135000Y988775D01*
Y988442D01*
X135125Y988067D01*
X135333Y987775D01*
X135583Y987567D01*
X136000Y987400D01*
X136375Y987358D01*
X136750Y987442D01*
X137000Y987567D01*
X137250Y987817D01*
X137417Y988108D01*
X137500Y988400D01*
Y988692D01*
X137417Y988983D01*
X137292Y989233D01*
X137125Y989442D01*
G01X137500Y991500D02*
X135000D01*
X135500Y991000D01*
G01X137500D02*
Y992000D01*
G01X137208Y993892D02*
X137417Y994183D01*
X137500Y994517D01*
X137417Y994850D01*
X137167Y995142D01*
X136792Y995350D01*
X136417Y995433D01*
X135958D01*
X135583Y995350D01*
X135250Y995142D01*
X135083Y994892D01*
X135000Y994600D01*
X135083Y994267D01*
X135250Y994017D01*
X135500Y993850D01*
X135833Y993767D01*
X136125Y993850D01*
X136417Y994058D01*
X136583Y994308D01*
X136625Y994600D01*
X136542Y994933D01*
X136333Y995183D01*
X135958Y995433D01*
G01X129708Y965817D02*
X129583Y965567D01*
X129500Y965275D01*
Y964942D01*
X129625Y964567D01*
X129833Y964275D01*
X130083Y964067D01*
X130500Y963900D01*
X130875Y963858D01*
X131250Y963942D01*
X131500Y964067D01*
X131750Y964317D01*
X131917Y964608D01*
X132000Y964900D01*
Y965192D01*
X131917Y965483D01*
X131792Y965733D01*
X131625Y965942D01*
G01X129917Y967208D02*
X129667Y967458D01*
X129542Y967750D01*
X129500Y968083D01*
X129583Y968500D01*
X129792Y968792D01*
X130042Y968875D01*
X130292Y968833D01*
X130500Y968667D01*
X130917Y967833D01*
X131208Y967458D01*
X131625Y967208D01*
X132000Y967125D01*
Y968875D01*
G01X129500Y971100D02*
X129583Y970767D01*
X129792Y970517D01*
X130042Y970350D01*
X130375Y970225D01*
X130750Y970183D01*
X131125Y970225D01*
X131458Y970350D01*
X131708Y970517D01*
X131917Y970767D01*
X132000Y971100D01*
X131917Y971433D01*
X131708Y971683D01*
X131458Y971850D01*
X131125Y971975D01*
X130750Y972017D01*
X130375Y971975D01*
X130042Y971850D01*
X129792Y971683D01*
X129583Y971433D01*
X129500Y971100D01*
G01X124800Y1004467D02*
X122300D01*
Y1005508D01*
X122425Y1005842D01*
X122592Y1006050D01*
X122925Y1006133D01*
X123258Y1006050D01*
X123467Y1005800D01*
X123592Y1005508D01*
Y1004467D01*
G01Y1005508D02*
X124800Y1006133D01*
G01Y1008900D02*
X122300D01*
X124092Y1007358D01*
Y1009442D01*
G01X124800Y1011417D02*
X124258Y1011500D01*
X123800Y1011625D01*
X123383Y1011792D01*
X122925Y1012000D01*
X122300Y1012333D01*
Y1010667D01*
G01X121300Y995900D02*
X125300D01*
Y1003300D01*
G01X120800Y1004467D02*
X118300D01*
Y1005508D01*
X118425Y1005842D01*
X118592Y1006050D01*
X118925Y1006133D01*
X119258Y1006050D01*
X119467Y1005800D01*
X119592Y1005508D01*
Y1004467D01*
G01Y1005508D02*
X120800Y1006133D01*
G01Y1008900D02*
X118300D01*
X120092Y1007358D01*
Y1009442D01*
G01X119758Y1010708D02*
X119467Y1011000D01*
X119300Y1011250D01*
X119217Y1011583D01*
X119300Y1011875D01*
X119467Y1012083D01*
X119717Y1012250D01*
X120008Y1012292D01*
X120258Y1012250D01*
X120508Y1012083D01*
X120717Y1011833D01*
X120800Y1011542D01*
X120717Y1011208D01*
X120467Y1010917D01*
X120092Y1010750D01*
X119675Y1010708D01*
X119133Y1010792D01*
X118842Y1010917D01*
X118550Y1011125D01*
X118342Y1011417D01*
X118300Y1011708D01*
X118383Y1012000D01*
X118592Y1012208D01*
G01X117300Y995900D02*
X121300D01*
Y1003300D01*
G01X116300Y1004467D02*
X113800D01*
Y1005508D01*
X113925Y1005842D01*
X114092Y1006050D01*
X114425Y1006133D01*
X114758Y1006050D01*
X114967Y1005800D01*
X115092Y1005508D01*
Y1004467D01*
G01Y1005508D02*
X116300Y1006133D01*
G01Y1008900D02*
X113800D01*
X115592Y1007358D01*
Y1009442D01*
G01X115925Y1010583D02*
X116133Y1010833D01*
X116258Y1011125D01*
X116300Y1011500D01*
X116217Y1011875D01*
X116050Y1012167D01*
X115758Y1012375D01*
X115425Y1012417D01*
X115092Y1012333D01*
X114883Y1012125D01*
X114717Y1011833D01*
X114675Y1011542D01*
X114717Y1011250D01*
X114883Y1010875D01*
X113800Y1011000D01*
Y1012125D01*
G01X112800Y995900D02*
X116800D01*
Y1003300D01*
G01X101500Y994517D02*
X99000D01*
Y995517D01*
X99125Y995850D01*
X99417Y996100D01*
X99750Y996183D01*
X100083Y996100D01*
X100333Y995892D01*
X100458Y995517D01*
Y994517D01*
G01X101500Y997617D02*
X99000D01*
Y998658D01*
X99125Y998992D01*
X99292Y999200D01*
X99625Y999283D01*
X99958Y999200D01*
X100167Y998950D01*
X100292Y998658D01*
Y997617D01*
G01Y998658D02*
X101500Y999283D01*
G01X101125Y1000633D02*
X101333Y1000883D01*
X101458Y1001175D01*
X101500Y1001550D01*
X101417Y1001925D01*
X101250Y1002217D01*
X100958Y1002425D01*
X100625Y1002467D01*
X100292Y1002383D01*
X100083Y1002175D01*
X99917Y1001883D01*
X99875Y1001592D01*
X99917Y1001300D01*
X100083Y1000925D01*
X99000Y1001050D01*
Y1002175D01*
G01X101125Y1003733D02*
X101333Y1003983D01*
X101458Y1004275D01*
X101500Y1004650D01*
X101417Y1005025D01*
X101250Y1005317D01*
X100958Y1005525D01*
X100625Y1005567D01*
X100292Y1005483D01*
X100083Y1005275D01*
X99917Y1004983D01*
X99875Y1004692D01*
X99917Y1004400D01*
X100083Y1004025D01*
X99000Y1004150D01*
Y1005275D01*
G01X97000Y974300D02*
X101000D01*
Y981700D01*
G01X136500Y1007517D02*
X134000D01*
Y1008558D01*
X134125Y1008892D01*
X134292Y1009100D01*
X134625Y1009183D01*
X134958Y1009100D01*
X135167Y1008850D01*
X135292Y1008558D01*
Y1007517D01*
G01Y1008558D02*
X136500Y1009183D01*
G01Y1011450D02*
X134000D01*
X134500Y1010950D01*
G01X136500D02*
Y1011950D01*
G01X134000Y1014550D02*
X134083Y1014217D01*
X134292Y1013967D01*
X134542Y1013800D01*
X134875Y1013675D01*
X135250Y1013633D01*
X135625Y1013675D01*
X135958Y1013800D01*
X136208Y1013967D01*
X136417Y1014217D01*
X136500Y1014550D01*
X136417Y1014883D01*
X136208Y1015133D01*
X135958Y1015300D01*
X135625Y1015425D01*
X135250Y1015467D01*
X134875Y1015425D01*
X134542Y1015300D01*
X134292Y1015133D01*
X134083Y1014883D01*
X134000Y1014550D01*
G01X135458Y1016858D02*
X135167Y1017150D01*
X135000Y1017400D01*
X134917Y1017733D01*
X135000Y1018025D01*
X135167Y1018233D01*
X135417Y1018400D01*
X135708Y1018442D01*
X135958Y1018400D01*
X136208Y1018233D01*
X136417Y1017983D01*
X136500Y1017692D01*
X136417Y1017358D01*
X136167Y1017067D01*
X135792Y1016900D01*
X135375Y1016858D01*
X134833Y1016942D01*
X134542Y1017067D01*
X134250Y1017275D01*
X134042Y1017567D01*
X134000Y1017858D01*
X134083Y1018150D01*
X134292Y1018358D01*
G01X133000Y997800D02*
X137000D01*
Y1005200D01*
G01X128500Y1019917D02*
X123500D01*
Y1023083D01*
G01X125917Y1021917D02*
Y1019917D01*
G01X128500Y1028100D02*
X123500D01*
X127083Y1025017D01*
Y1029183D01*
G01X128667Y1032700D02*
X128583Y1032533D01*
X128417D01*
X128333Y1032700D01*
X128417Y1032867D01*
X128583D01*
X128667Y1032700D01*
G01X126417D02*
X126333Y1032533D01*
X126167D01*
X126083Y1032700D01*
X126167Y1032867D01*
X126333D01*
X126417Y1032700D01*
G01X127500Y1036467D02*
X128083Y1036967D01*
X128417Y1037633D01*
X128500Y1038383D01*
X128417Y1039050D01*
X128000Y1039717D01*
X127500Y1040133D01*
X127000Y1040217D01*
X126417Y1040050D01*
X126000Y1039467D01*
X125833Y1038883D01*
Y1038133D01*
G01Y1038883D02*
X125583Y1039383D01*
X125167Y1039800D01*
X124667Y1039967D01*
X124167Y1039800D01*
X123750Y1039383D01*
X123500Y1038633D01*
X123583Y1037883D01*
X123917Y1037133D01*
G01X128500Y1041817D02*
X123500Y1043900D01*
X128500Y1045983D01*
G01X126750Y1045233D02*
Y1042567D01*
G01X128667Y1048000D02*
X123500Y1051000D01*
G01X128500Y1055100D02*
X123500D01*
X124500Y1054100D01*
G01X128500D02*
Y1056100D01*
G01X127750Y1058867D02*
X128167Y1059367D01*
X128417Y1059950D01*
X128500Y1060700D01*
X128333Y1061450D01*
X128000Y1062033D01*
X127417Y1062450D01*
X126750Y1062533D01*
X126083Y1062367D01*
X125667Y1061950D01*
X125333Y1061367D01*
X125250Y1060783D01*
X125333Y1060200D01*
X125667Y1059450D01*
X123500Y1059700D01*
Y1061950D01*
G01Y1064217D02*
X128500Y1066300D01*
X123500Y1068383D01*
G01X96500Y1061600D02*
Y1038600D01*
G01X88500Y1031033D02*
X86000D01*
Y1031867D01*
X86125Y1032200D01*
X86292Y1032450D01*
X86542Y1032658D01*
X86833Y1032825D01*
X87250Y1032867D01*
X87667Y1032825D01*
X87958Y1032658D01*
X88208Y1032450D01*
X88375Y1032200D01*
X88500Y1031867D01*
Y1031033D01*
G01X88125Y1034133D02*
X88333Y1034383D01*
X88458Y1034675D01*
X88500Y1035050D01*
X88417Y1035425D01*
X88250Y1035717D01*
X87958Y1035925D01*
X87625Y1035967D01*
X87292Y1035883D01*
X87083Y1035675D01*
X86917Y1035383D01*
X86875Y1035092D01*
X86917Y1034800D01*
X87083Y1034425D01*
X86000Y1034550D01*
Y1035675D01*
G01X111017Y1058692D02*
X110767Y1058817D01*
X110475Y1058900D01*
X110142D01*
X109767Y1058775D01*
X109475Y1058567D01*
X109267Y1058317D01*
X109100Y1057900D01*
X109058Y1057525D01*
X109142Y1057150D01*
X109267Y1056900D01*
X109517Y1056650D01*
X109808Y1056483D01*
X110100Y1056400D01*
X110392D01*
X110683Y1056483D01*
X110933Y1056608D01*
X111142Y1056775D01*
G01X113700Y1056400D02*
Y1058900D01*
X112158Y1057108D01*
X114242D01*
G01X116300Y1058900D02*
X115967Y1058817D01*
X115717Y1058608D01*
X115550Y1058358D01*
X115425Y1058025D01*
X115383Y1057650D01*
X115425Y1057275D01*
X115550Y1056942D01*
X115717Y1056692D01*
X115967Y1056483D01*
X116300Y1056400D01*
X116633Y1056483D01*
X116883Y1056692D01*
X117050Y1056942D01*
X117175Y1057275D01*
X117217Y1057650D01*
X117175Y1058025D01*
X117050Y1058358D01*
X116883Y1058608D01*
X116633Y1058817D01*
X116300Y1058900D01*
G01X111017Y1053992D02*
X110767Y1054117D01*
X110475Y1054200D01*
X110142D01*
X109767Y1054075D01*
X109475Y1053867D01*
X109267Y1053617D01*
X109100Y1053200D01*
X109058Y1052825D01*
X109142Y1052450D01*
X109267Y1052200D01*
X109517Y1051950D01*
X109808Y1051783D01*
X110100Y1051700D01*
X110392D01*
X110683Y1051783D01*
X110933Y1051908D01*
X111142Y1052075D01*
G01X112283Y1052200D02*
X112533Y1051908D01*
X112867Y1051742D01*
X113242Y1051700D01*
X113575Y1051742D01*
X113908Y1051950D01*
X114117Y1052200D01*
X114158Y1052450D01*
X114075Y1052742D01*
X113783Y1052950D01*
X113492Y1053033D01*
X113117D01*
G01X113492D02*
X113742Y1053158D01*
X113950Y1053367D01*
X114033Y1053617D01*
X113950Y1053867D01*
X113742Y1054075D01*
X113367Y1054200D01*
X112992Y1054158D01*
X112617Y1053992D01*
G01X115592Y1051992D02*
X115883Y1051783D01*
X116217Y1051700D01*
X116550Y1051783D01*
X116842Y1052033D01*
X117050Y1052408D01*
X117133Y1052783D01*
Y1053242D01*
X117050Y1053617D01*
X116842Y1053950D01*
X116592Y1054117D01*
X116300Y1054200D01*
X115967Y1054117D01*
X115717Y1053950D01*
X115550Y1053700D01*
X115467Y1053367D01*
X115550Y1053075D01*
X115758Y1052783D01*
X116008Y1052617D01*
X116300Y1052575D01*
X116633Y1052658D01*
X116883Y1052867D01*
X117133Y1053242D01*
G01X107000Y1077417D02*
X102000D01*
Y1080583D01*
G01X104417Y1079417D02*
Y1077417D01*
G01X106250Y1082767D02*
X106667Y1083267D01*
X106917Y1083850D01*
X107000Y1084600D01*
X106833Y1085350D01*
X106500Y1085933D01*
X105917Y1086350D01*
X105250Y1086433D01*
X104583Y1086267D01*
X104167Y1085850D01*
X103833Y1085267D01*
X103750Y1084683D01*
X103833Y1084100D01*
X104167Y1083350D01*
X102000Y1083600D01*
Y1085850D01*
G01X107167Y1090200D02*
X107083Y1090033D01*
X106917D01*
X106833Y1090200D01*
X106917Y1090367D01*
X107083D01*
X107167Y1090200D01*
G01X104917D02*
X104833Y1090033D01*
X104667D01*
X104583Y1090200D01*
X104667Y1090367D01*
X104833D01*
X104917Y1090200D01*
G01X106000Y1093967D02*
X106583Y1094467D01*
X106917Y1095133D01*
X107000Y1095883D01*
X106917Y1096550D01*
X106500Y1097217D01*
X106000Y1097633D01*
X105500Y1097717D01*
X104917Y1097550D01*
X104500Y1096967D01*
X104333Y1096383D01*
Y1095633D01*
G01Y1096383D02*
X104083Y1096883D01*
X103667Y1097300D01*
X103167Y1097467D01*
X102667Y1097300D01*
X102250Y1096883D01*
X102000Y1096133D01*
X102083Y1095383D01*
X102417Y1094633D01*
G01X107000Y1099317D02*
X102000Y1101400D01*
X107000Y1103483D01*
G01X105250Y1102733D02*
Y1100067D01*
G01X107167Y1105500D02*
X102000Y1108500D01*
G01X107000Y1112600D02*
X102000D01*
X103000Y1111600D01*
G01X107000D02*
Y1113600D01*
G01X106250Y1116367D02*
X106667Y1116867D01*
X106917Y1117450D01*
X107000Y1118200D01*
X106833Y1118950D01*
X106500Y1119533D01*
X105917Y1119950D01*
X105250Y1120033D01*
X104583Y1119867D01*
X104167Y1119450D01*
X103833Y1118867D01*
X103750Y1118283D01*
X103833Y1117700D01*
X104167Y1116950D01*
X102000Y1117200D01*
Y1119450D01*
G01Y1121717D02*
X107000Y1123800D01*
X102000Y1125883D01*
G01X120658Y1114500D02*
Y1117000D01*
X122242D01*
G01X121658Y1115792D02*
X120658D01*
G01X123633Y1114875D02*
X123883Y1114667D01*
X124175Y1114542D01*
X124550Y1114500D01*
X124925Y1114583D01*
X125217Y1114750D01*
X125425Y1115042D01*
X125467Y1115375D01*
X125383Y1115708D01*
X125175Y1115917D01*
X124883Y1116083D01*
X124592Y1116125D01*
X124300Y1116083D01*
X123925Y1115917D01*
X124050Y1117000D01*
X125175D01*
G01X95300Y1081600D02*
Y1099600D01*
G01X134208Y1111317D02*
X134083Y1111067D01*
X134000Y1110775D01*
Y1110442D01*
X134125Y1110067D01*
X134333Y1109775D01*
X134583Y1109567D01*
X135000Y1109400D01*
X135375Y1109358D01*
X135750Y1109442D01*
X136000Y1109567D01*
X136250Y1109817D01*
X136417Y1110108D01*
X136500Y1110400D01*
Y1110692D01*
X136417Y1110983D01*
X136292Y1111233D01*
X136125Y1111442D01*
G01X136500Y1114000D02*
X134000D01*
X135792Y1112458D01*
Y1114542D01*
G01X136500Y1116600D02*
X136458Y1116892D01*
X136333Y1117225D01*
X136125Y1117433D01*
X135833Y1117517D01*
X135542Y1117433D01*
X135292Y1117183D01*
X135167Y1116808D01*
Y1116392D01*
X135083Y1116142D01*
X134875Y1115933D01*
X134583Y1115850D01*
X134292Y1115975D01*
X134083Y1116267D01*
X134000Y1116600D01*
X134083Y1116933D01*
X134292Y1117225D01*
X134583Y1117350D01*
X134875Y1117267D01*
X135083Y1117058D01*
X135167Y1116808D01*
Y1116392D01*
X135292Y1116017D01*
X135542Y1115767D01*
X135833Y1115683D01*
X136125Y1115767D01*
X136333Y1115975D01*
X136458Y1116308D01*
X136500Y1116600D01*
G01X110597Y1158098D02*
X133597D01*
G01X110597Y1119298D02*
Y1158098D01*
G01X133597Y1119298D02*
X110597D01*
G01X133597Y1158098D02*
Y1119298D01*
G01X92502Y1119097D02*
Y1140097D01*
G01X105000Y1152517D02*
X102500D01*
Y1153558D01*
X102625Y1153892D01*
X102792Y1154100D01*
X103125Y1154183D01*
X103458Y1154100D01*
X103667Y1153850D01*
X103792Y1153558D01*
Y1152517D01*
G01Y1153558D02*
X105000Y1154183D01*
G01Y1156450D02*
X102500D01*
X103000Y1155950D01*
G01X105000D02*
Y1156950D01*
G01Y1159467D02*
X104458Y1159550D01*
X104000Y1159675D01*
X103583Y1159842D01*
X103125Y1160050D01*
X102500Y1160383D01*
Y1158717D01*
G01X105000Y1162650D02*
X104958Y1162942D01*
X104833Y1163275D01*
X104625Y1163483D01*
X104333Y1163567D01*
X104042Y1163483D01*
X103792Y1163233D01*
X103667Y1162858D01*
Y1162442D01*
X103583Y1162192D01*
X103375Y1161983D01*
X103083Y1161900D01*
X102792Y1162025D01*
X102583Y1162317D01*
X102500Y1162650D01*
X102583Y1162983D01*
X102792Y1163275D01*
X103083Y1163400D01*
X103375Y1163317D01*
X103583Y1163108D01*
X103667Y1162858D01*
Y1162442D01*
X103792Y1162067D01*
X104042Y1161817D01*
X104333Y1161733D01*
X104625Y1161817D01*
X104833Y1162025D01*
X104958Y1162358D01*
X105000Y1162650D01*
G01X101100Y1148300D02*
Y1130700D01*
G01X109100Y1148300D02*
X101100D01*
G01X109100Y1130700D02*
Y1148300D01*
G01X101100Y1130700D02*
X109100D01*
G01X95950Y1258500D02*
X95617Y1258542D01*
X95325Y1258708D01*
X95075Y1258958D01*
X94908Y1259250D01*
X94825Y1259583D01*
Y1259917D01*
X94908Y1260250D01*
X95075Y1260542D01*
X95325Y1260792D01*
X95617Y1260958D01*
X95950Y1261000D01*
X96283Y1260958D01*
X96575Y1260792D01*
X96825Y1260542D01*
X96992Y1260250D01*
X97075Y1259917D01*
Y1259583D01*
X96992Y1259250D01*
X96825Y1258958D01*
X96575Y1258708D01*
X96283Y1258542D01*
X95950Y1258500D01*
G01X96283Y1259167D02*
X96783Y1258500D01*
G01X98258Y1260583D02*
X98508Y1260833D01*
X98800Y1260958D01*
X99133Y1261000D01*
X99550Y1260917D01*
X99842Y1260708D01*
X99925Y1260458D01*
X99883Y1260208D01*
X99717Y1260000D01*
X98883Y1259583D01*
X98508Y1259292D01*
X98258Y1258875D01*
X98175Y1258500D01*
X99925D01*
G01X101268Y1253343D02*
X115268D01*
G01X101268Y1266343D02*
Y1253343D01*
G01X115268Y1266343D02*
X101268D01*
G01X115268Y1253343D02*
Y1266343D01*
G01X123767Y1362292D02*
X123517Y1362417D01*
X123225Y1362500D01*
X122892D01*
X122517Y1362375D01*
X122225Y1362167D01*
X122017Y1361917D01*
X121850Y1361500D01*
X121808Y1361125D01*
X121892Y1360750D01*
X122017Y1360500D01*
X122267Y1360250D01*
X122558Y1360083D01*
X122850Y1360000D01*
X123142D01*
X123433Y1360083D01*
X123683Y1360208D01*
X123892Y1360375D01*
G01X125158Y1362083D02*
X125408Y1362333D01*
X125700Y1362458D01*
X126033Y1362500D01*
X126450Y1362417D01*
X126742Y1362208D01*
X126825Y1361958D01*
X126783Y1361708D01*
X126617Y1361500D01*
X125783Y1361083D01*
X125408Y1360792D01*
X125158Y1360375D01*
X125075Y1360000D01*
X126825D01*
G01X128133Y1360375D02*
X128383Y1360167D01*
X128675Y1360042D01*
X129050Y1360000D01*
X129425Y1360083D01*
X129717Y1360250D01*
X129925Y1360542D01*
X129967Y1360875D01*
X129883Y1361208D01*
X129675Y1361417D01*
X129383Y1361583D01*
X129092Y1361625D01*
X128800Y1361583D01*
X128425Y1361417D01*
X128550Y1362500D01*
X129675D01*
G01X131442Y1360292D02*
X131733Y1360083D01*
X132067Y1360000D01*
X132400Y1360083D01*
X132692Y1360333D01*
X132900Y1360708D01*
X132983Y1361083D01*
Y1361542D01*
X132900Y1361917D01*
X132692Y1362250D01*
X132442Y1362417D01*
X132150Y1362500D01*
X131817Y1362417D01*
X131567Y1362250D01*
X131400Y1362000D01*
X131317Y1361667D01*
X131400Y1361375D01*
X131608Y1361083D01*
X131858Y1360917D01*
X132150Y1360875D01*
X132483Y1360958D01*
X132733Y1361167D01*
X132983Y1361542D01*
G01X106767Y1362292D02*
X106517Y1362417D01*
X106225Y1362500D01*
X105892D01*
X105517Y1362375D01*
X105225Y1362167D01*
X105017Y1361917D01*
X104850Y1361500D01*
X104808Y1361125D01*
X104892Y1360750D01*
X105017Y1360500D01*
X105267Y1360250D01*
X105558Y1360083D01*
X105850Y1360000D01*
X106142D01*
X106433Y1360083D01*
X106683Y1360208D01*
X106892Y1360375D01*
G01X108158Y1362083D02*
X108408Y1362333D01*
X108700Y1362458D01*
X109033Y1362500D01*
X109450Y1362417D01*
X109742Y1362208D01*
X109825Y1361958D01*
X109783Y1361708D01*
X109617Y1361500D01*
X108783Y1361083D01*
X108408Y1360792D01*
X108158Y1360375D01*
X108075Y1360000D01*
X109825D01*
G01X111258Y1361042D02*
X111550Y1361333D01*
X111800Y1361500D01*
X112133Y1361583D01*
X112425Y1361500D01*
X112633Y1361333D01*
X112800Y1361083D01*
X112842Y1360792D01*
X112800Y1360542D01*
X112633Y1360292D01*
X112383Y1360083D01*
X112092Y1360000D01*
X111758Y1360083D01*
X111467Y1360333D01*
X111300Y1360708D01*
X111258Y1361125D01*
X111342Y1361667D01*
X111467Y1361958D01*
X111675Y1362250D01*
X111967Y1362458D01*
X112258Y1362500D01*
X112550Y1362417D01*
X112758Y1362208D01*
G01X115150Y1362500D02*
X114817Y1362417D01*
X114567Y1362208D01*
X114400Y1361958D01*
X114275Y1361625D01*
X114233Y1361250D01*
X114275Y1360875D01*
X114400Y1360542D01*
X114567Y1360292D01*
X114817Y1360083D01*
X115150Y1360000D01*
X115483Y1360083D01*
X115733Y1360292D01*
X115900Y1360542D01*
X116025Y1360875D01*
X116067Y1361250D01*
X116025Y1361625D01*
X115900Y1361958D01*
X115733Y1362208D01*
X115483Y1362417D01*
X115150Y1362500D01*
G01X124000Y1370017D02*
X121500D01*
Y1371058D01*
X121625Y1371392D01*
X121792Y1371600D01*
X122125Y1371683D01*
X122458Y1371600D01*
X122667Y1371350D01*
X122792Y1371058D01*
Y1370017D01*
G01Y1371058D02*
X124000Y1371683D01*
G01Y1373950D02*
X121500D01*
X122000Y1373450D01*
G01X124000D02*
Y1374450D01*
G01X121500Y1377050D02*
X121583Y1376717D01*
X121792Y1376467D01*
X122042Y1376300D01*
X122375Y1376175D01*
X122750Y1376133D01*
X123125Y1376175D01*
X123458Y1376300D01*
X123708Y1376467D01*
X123917Y1376717D01*
X124000Y1377050D01*
X123917Y1377383D01*
X123708Y1377633D01*
X123458Y1377800D01*
X123125Y1377925D01*
X122750Y1377967D01*
X122375Y1377925D01*
X122042Y1377800D01*
X121792Y1377633D01*
X121583Y1377383D01*
X121500Y1377050D01*
G01X123708Y1379442D02*
X123917Y1379733D01*
X124000Y1380067D01*
X123917Y1380400D01*
X123667Y1380692D01*
X123292Y1380900D01*
X122917Y1380983D01*
X122458D01*
X122083Y1380900D01*
X121750Y1380692D01*
X121583Y1380442D01*
X121500Y1380150D01*
X121583Y1379817D01*
X121750Y1379567D01*
X122000Y1379400D01*
X122333Y1379317D01*
X122625Y1379400D01*
X122917Y1379608D01*
X123083Y1379858D01*
X123125Y1380150D01*
X123042Y1380483D01*
X122833Y1380733D01*
X122458Y1380983D01*
G01X129000Y1370017D02*
X126500D01*
Y1371058D01*
X126625Y1371392D01*
X126792Y1371600D01*
X127125Y1371683D01*
X127458Y1371600D01*
X127667Y1371350D01*
X127792Y1371058D01*
Y1370017D01*
G01Y1371058D02*
X129000Y1371683D01*
G01Y1373950D02*
X126500D01*
X127000Y1373450D01*
G01X129000D02*
Y1374450D01*
G01X126500Y1377050D02*
X126583Y1376717D01*
X126792Y1376467D01*
X127042Y1376300D01*
X127375Y1376175D01*
X127750Y1376133D01*
X128125Y1376175D01*
X128458Y1376300D01*
X128708Y1376467D01*
X128917Y1376717D01*
X129000Y1377050D01*
X128917Y1377383D01*
X128708Y1377633D01*
X128458Y1377800D01*
X128125Y1377925D01*
X127750Y1377967D01*
X127375Y1377925D01*
X127042Y1377800D01*
X126792Y1377633D01*
X126583Y1377383D01*
X126500Y1377050D01*
G01X129000Y1380150D02*
X128958Y1380442D01*
X128833Y1380775D01*
X128625Y1380983D01*
X128333Y1381067D01*
X128042Y1380983D01*
X127792Y1380733D01*
X127667Y1380358D01*
Y1379942D01*
X127583Y1379692D01*
X127375Y1379483D01*
X127083Y1379400D01*
X126792Y1379525D01*
X126583Y1379817D01*
X126500Y1380150D01*
X126583Y1380483D01*
X126792Y1380775D01*
X127083Y1380900D01*
X127375Y1380817D01*
X127583Y1380608D01*
X127667Y1380358D01*
Y1379942D01*
X127792Y1379567D01*
X128042Y1379317D01*
X128333Y1379233D01*
X128625Y1379317D01*
X128833Y1379525D01*
X128958Y1379858D01*
X129000Y1380150D01*
G01X119000Y1370017D02*
X116500D01*
Y1371017D01*
X116625Y1371350D01*
X116917Y1371600D01*
X117250Y1371683D01*
X117583Y1371600D01*
X117833Y1371392D01*
X117958Y1371017D01*
Y1370017D01*
G01X119000Y1373117D02*
X116500D01*
Y1374158D01*
X116625Y1374492D01*
X116792Y1374700D01*
X117125Y1374783D01*
X117458Y1374700D01*
X117667Y1374450D01*
X117792Y1374158D01*
Y1373117D01*
G01Y1374158D02*
X119000Y1374783D01*
G01Y1377050D02*
X116500D01*
X117000Y1376550D01*
G01X119000D02*
Y1377550D01*
G01X118625Y1379233D02*
X118833Y1379483D01*
X118958Y1379775D01*
X119000Y1380150D01*
X118917Y1380525D01*
X118750Y1380817D01*
X118458Y1381025D01*
X118125Y1381067D01*
X117792Y1380983D01*
X117583Y1380775D01*
X117417Y1380483D01*
X117375Y1380192D01*
X117417Y1379900D01*
X117583Y1379525D01*
X116500Y1379650D01*
Y1380775D01*
G01X117400Y1365000D02*
X117067Y1365042D01*
X116775Y1365208D01*
X116525Y1365458D01*
X116358Y1365750D01*
X116275Y1366083D01*
Y1366417D01*
X116358Y1366750D01*
X116525Y1367042D01*
X116775Y1367292D01*
X117067Y1367458D01*
X117400Y1367500D01*
X117733Y1367458D01*
X118025Y1367292D01*
X118275Y1367042D01*
X118442Y1366750D01*
X118525Y1366417D01*
Y1366083D01*
X118442Y1365750D01*
X118275Y1365458D01*
X118025Y1365208D01*
X117733Y1365042D01*
X117400Y1365000D01*
G01X117733Y1365667D02*
X118233Y1365000D01*
G01X121000D02*
Y1367500D01*
X119458Y1365708D01*
X121542D01*
G01X122892Y1365292D02*
X123183Y1365083D01*
X123517Y1365000D01*
X123850Y1365083D01*
X124142Y1365333D01*
X124350Y1365708D01*
X124433Y1366083D01*
Y1366542D01*
X124350Y1366917D01*
X124142Y1367250D01*
X123892Y1367417D01*
X123600Y1367500D01*
X123267Y1367417D01*
X123017Y1367250D01*
X122850Y1367000D01*
X122767Y1366667D01*
X122850Y1366375D01*
X123058Y1366083D01*
X123308Y1365917D01*
X123600Y1365875D01*
X123933Y1365958D01*
X124183Y1366167D01*
X124433Y1366542D01*
G01X138996Y1388300D02*
X133496D01*
G01Y1396300D02*
X138996D01*
G01X121396D02*
X126896D01*
G01X121396Y1388300D02*
Y1396300D01*
G01X126896Y1388300D02*
X121396D01*
G01X120300Y1383500D02*
X114800D01*
G01X120300Y1391500D02*
Y1383500D01*
G01X114800Y1391500D02*
X120300D01*
G01X102700D02*
X108200D01*
G01X102700Y1383500D02*
Y1391500D01*
G01X108200Y1383500D02*
X102700D01*
G01X134000Y1415017D02*
X131500D01*
Y1416017D01*
X131625Y1416350D01*
X131917Y1416600D01*
X132250Y1416683D01*
X132583Y1416600D01*
X132833Y1416392D01*
X132958Y1416017D01*
Y1415017D01*
G01X134000Y1418117D02*
X131500D01*
Y1419158D01*
X131625Y1419492D01*
X131792Y1419700D01*
X132125Y1419783D01*
X132458Y1419700D01*
X132667Y1419450D01*
X132792Y1419158D01*
Y1418117D01*
G01Y1419158D02*
X134000Y1419783D01*
G01X133500Y1421133D02*
X133792Y1421383D01*
X133958Y1421717D01*
X134000Y1422092D01*
X133958Y1422425D01*
X133750Y1422758D01*
X133500Y1422967D01*
X133250Y1423008D01*
X132958Y1422925D01*
X132750Y1422633D01*
X132667Y1422342D01*
Y1421967D01*
G01Y1422342D02*
X132542Y1422592D01*
X132333Y1422800D01*
X132083Y1422883D01*
X131833Y1422800D01*
X131625Y1422592D01*
X131500Y1422217D01*
X131542Y1421842D01*
X131708Y1421467D01*
G01X133708Y1424442D02*
X133917Y1424733D01*
X134000Y1425067D01*
X133917Y1425400D01*
X133667Y1425692D01*
X133292Y1425900D01*
X132917Y1425983D01*
X132458D01*
X132083Y1425900D01*
X131750Y1425692D01*
X131583Y1425442D01*
X131500Y1425150D01*
X131583Y1424817D01*
X131750Y1424567D01*
X132000Y1424400D01*
X132333Y1424317D01*
X132625Y1424400D01*
X132917Y1424608D01*
X133083Y1424858D01*
X133125Y1425150D01*
X133042Y1425483D01*
X132833Y1425733D01*
X132458Y1425983D01*
G01X121000Y1418800D02*
X125000D01*
Y1426200D01*
G01X125500Y1418800D02*
X129500D01*
Y1426200D01*
G01X102500Y1425700D02*
X98500D01*
Y1418300D01*
G01X93500Y1425700D02*
X89500D01*
Y1418300D01*
G01X104317Y1411500D02*
Y1414000D01*
X105317D01*
X105650Y1413875D01*
X105900Y1413583D01*
X105983Y1413250D01*
X105900Y1412917D01*
X105692Y1412667D01*
X105317Y1412542D01*
X104317D01*
G01X107417Y1411500D02*
Y1414000D01*
X108458D01*
X108792Y1413875D01*
X109000Y1413708D01*
X109083Y1413375D01*
X109000Y1413042D01*
X108750Y1412833D01*
X108458Y1412708D01*
X107417D01*
G01X108458D02*
X109083Y1411500D01*
G01X111350D02*
Y1414000D01*
X110850Y1413500D01*
G01Y1411500D02*
X111850D01*
G01X113658Y1412542D02*
X113950Y1412833D01*
X114200Y1413000D01*
X114533Y1413083D01*
X114825Y1413000D01*
X115033Y1412833D01*
X115200Y1412583D01*
X115242Y1412292D01*
X115200Y1412042D01*
X115033Y1411792D01*
X114783Y1411583D01*
X114492Y1411500D01*
X114158Y1411583D01*
X113867Y1411833D01*
X113700Y1412208D01*
X113658Y1412625D01*
X113742Y1413167D01*
X113867Y1413458D01*
X114075Y1413750D01*
X114367Y1413958D01*
X114658Y1414000D01*
X114950Y1413917D01*
X115158Y1413708D01*
G01X115100Y1419600D02*
Y1423600D01*
X107700D01*
G01X116000Y1418800D02*
X120000D01*
Y1426200D01*
G01X104517Y1415000D02*
Y1417500D01*
X105517D01*
X105850Y1417375D01*
X106100Y1417083D01*
X106183Y1416750D01*
X106100Y1416417D01*
X105892Y1416167D01*
X105517Y1416042D01*
X104517D01*
G01X107617Y1415000D02*
Y1417500D01*
X108658D01*
X108992Y1417375D01*
X109200Y1417208D01*
X109283Y1416875D01*
X109200Y1416542D01*
X108950Y1416333D01*
X108658Y1416208D01*
X107617D01*
G01X108658D02*
X109283Y1415000D01*
G01X111550D02*
Y1417500D01*
X111050Y1417000D01*
G01Y1415000D02*
X112050D01*
G01X113858Y1417083D02*
X114108Y1417333D01*
X114400Y1417458D01*
X114733Y1417500D01*
X115150Y1417417D01*
X115442Y1417208D01*
X115525Y1416958D01*
X115483Y1416708D01*
X115317Y1416500D01*
X114483Y1416083D01*
X114108Y1415792D01*
X113858Y1415375D01*
X113775Y1415000D01*
X115525D01*
G01X107000Y1425700D02*
X103000D01*
Y1418300D01*
G01X93600D02*
X97600D01*
Y1425700D01*
G01X137000Y1413804D02*
X133000D01*
Y1406404D01*
G01X136700Y1406004D02*
X132700D01*
Y1398604D01*
G01X109500Y1406100D02*
Y1410100D01*
X102100D01*
G01X109900Y1410200D02*
Y1406200D01*
X117300D01*
G01X136069Y1433019D02*
Y1419019D01*
G01D02*
X149069D01*
G01X101500Y1395400D02*
X101458Y1395067D01*
X101292Y1394775D01*
X101042Y1394525D01*
X100750Y1394358D01*
X100417Y1394275D01*
X100083D01*
X99750Y1394358D01*
X99458Y1394525D01*
X99208Y1394775D01*
X99042Y1395067D01*
X99000Y1395400D01*
X99042Y1395733D01*
X99208Y1396025D01*
X99458Y1396275D01*
X99750Y1396442D01*
X100083Y1396525D01*
X100417D01*
X100750Y1396442D01*
X101042Y1396275D01*
X101292Y1396025D01*
X101458Y1395733D01*
X101500Y1395400D01*
G01X100833Y1395733D02*
X101500Y1396233D01*
G01Y1398500D02*
X99000D01*
X99500Y1398000D01*
G01X101500D02*
Y1399000D01*
G01X99000Y1401600D02*
X99083Y1401267D01*
X99292Y1401017D01*
X99542Y1400850D01*
X99875Y1400725D01*
X100250Y1400683D01*
X100625Y1400725D01*
X100958Y1400850D01*
X101208Y1401017D01*
X101417Y1401267D01*
X101500Y1401600D01*
X101417Y1401933D01*
X101208Y1402183D01*
X100958Y1402350D01*
X100625Y1402475D01*
X100250Y1402517D01*
X99875Y1402475D01*
X99542Y1402350D01*
X99292Y1402183D01*
X99083Y1401933D01*
X99000Y1401600D01*
G01X116800Y1394000D02*
Y1405400D01*
G01X103400Y1394000D02*
X116800D01*
G01X103400Y1405400D02*
Y1394000D01*
G01X116800Y1405400D02*
X103400D01*
G01X118500Y1412704D02*
Y1398704D01*
G01X131500Y1412704D02*
X118500D01*
G01X131500Y1398704D02*
Y1412704D01*
G01X118500Y1398704D02*
X131500D01*
G01X115867Y1467100D02*
Y1469600D01*
X116867D01*
X117200Y1469475D01*
X117450Y1469183D01*
X117533Y1468850D01*
X117450Y1468517D01*
X117242Y1468267D01*
X116867Y1468142D01*
X115867D01*
G01X118883Y1469600D02*
Y1467808D01*
X119050Y1467433D01*
X119383Y1467183D01*
X119800Y1467100D01*
X120217Y1467183D01*
X120550Y1467433D01*
X120717Y1467808D01*
Y1469600D01*
G01X122900Y1467100D02*
Y1469600D01*
X122400Y1469100D01*
G01Y1467100D02*
X123400D01*
G01X111900Y1465000D02*
Y1468000D01*
G01X122100Y1436000D02*
Y1439000D01*
G01X132000Y1457100D02*
X130000D01*
G01X104000Y1446800D02*
X102000D01*
G01X130850Y1460850D02*
Y1465850D01*
X125850D01*
G01Y1438150D02*
X130850D01*
Y1443150D01*
G01X108150Y1438150D02*
X103150D01*
Y1443150D01*
G01X125500Y1473067D02*
X123000D01*
Y1474067D01*
X123125Y1474400D01*
X123417Y1474650D01*
X123750Y1474733D01*
X124083Y1474650D01*
X124333Y1474442D01*
X124458Y1474067D01*
Y1473067D01*
G01X125500Y1476083D02*
X123000D01*
Y1476917D01*
X123125Y1477250D01*
X123292Y1477500D01*
X123542Y1477708D01*
X123833Y1477875D01*
X124250Y1477917D01*
X124667Y1477875D01*
X124958Y1477708D01*
X125208Y1477500D01*
X125375Y1477250D01*
X125500Y1476917D01*
Y1476083D01*
G01Y1480100D02*
X123000D01*
X123500Y1479600D01*
G01X125500D02*
Y1480600D01*
G01X121500Y1473067D02*
X119000D01*
Y1474067D01*
X119125Y1474400D01*
X119417Y1474650D01*
X119750Y1474733D01*
X120083Y1474650D01*
X120333Y1474442D01*
X120458Y1474067D01*
Y1473067D01*
G01X119208Y1477917D02*
X119083Y1477667D01*
X119000Y1477375D01*
Y1477042D01*
X119125Y1476667D01*
X119333Y1476375D01*
X119583Y1476167D01*
X120000Y1476000D01*
X120375Y1475958D01*
X120750Y1476042D01*
X121000Y1476167D01*
X121250Y1476417D01*
X121417Y1476708D01*
X121500Y1477000D01*
Y1477292D01*
X121417Y1477583D01*
X121292Y1477833D01*
X121125Y1478042D01*
G01X120458Y1479308D02*
X120167Y1479600D01*
X120000Y1479850D01*
X119917Y1480183D01*
X120000Y1480475D01*
X120167Y1480683D01*
X120417Y1480850D01*
X120708Y1480892D01*
X120958Y1480850D01*
X121208Y1480683D01*
X121417Y1480433D01*
X121500Y1480142D01*
X121417Y1479808D01*
X121167Y1479517D01*
X120792Y1479350D01*
X120375Y1479308D01*
X119833Y1479392D01*
X119542Y1479517D01*
X119250Y1479725D01*
X119042Y1480017D01*
X119000Y1480308D01*
X119083Y1480600D01*
X119292Y1480808D01*
G01X103950Y1433800D02*
Y1431300D01*
G01X102992Y1433800D02*
X104908D01*
G01X106217Y1431300D02*
Y1433800D01*
X107217D01*
X107550Y1433675D01*
X107800Y1433383D01*
X107883Y1433050D01*
X107800Y1432717D01*
X107592Y1432467D01*
X107217Y1432342D01*
X106217D01*
G01X109358Y1433383D02*
X109608Y1433633D01*
X109900Y1433758D01*
X110233Y1433800D01*
X110650Y1433717D01*
X110942Y1433508D01*
X111025Y1433258D01*
X110983Y1433008D01*
X110817Y1432800D01*
X109983Y1432383D01*
X109608Y1432092D01*
X109358Y1431675D01*
X109275Y1431300D01*
X111025D01*
G01X112458Y1433383D02*
X112708Y1433633D01*
X113000Y1433758D01*
X113333Y1433800D01*
X113750Y1433717D01*
X114042Y1433508D01*
X114125Y1433258D01*
X114083Y1433008D01*
X113917Y1432800D01*
X113083Y1432383D01*
X112708Y1432092D01*
X112458Y1431675D01*
X112375Y1431300D01*
X114125D01*
G01X135200Y1426300D02*
Y1430300D01*
X127800D01*
G01X139500Y1445700D02*
X135500D01*
Y1438300D01*
G01X94817Y1467100D02*
Y1469600D01*
X95817D01*
X96150Y1469475D01*
X96400Y1469183D01*
X96483Y1468850D01*
X96400Y1468517D01*
X96192Y1468267D01*
X95817Y1468142D01*
X94817D01*
G01X97917Y1467100D02*
Y1469600D01*
X98958D01*
X99292Y1469475D01*
X99500Y1469308D01*
X99583Y1468975D01*
X99500Y1468642D01*
X99250Y1468433D01*
X98958Y1468308D01*
X97917D01*
G01X98958D02*
X99583Y1467100D01*
G01X100933Y1467600D02*
X101183Y1467308D01*
X101517Y1467142D01*
X101892Y1467100D01*
X102225Y1467142D01*
X102558Y1467350D01*
X102767Y1467600D01*
X102808Y1467850D01*
X102725Y1468142D01*
X102433Y1468350D01*
X102142Y1468433D01*
X101767D01*
G01X102142D02*
X102392Y1468558D01*
X102600Y1468767D01*
X102683Y1469017D01*
X102600Y1469267D01*
X102392Y1469475D01*
X102017Y1469600D01*
X101642Y1469558D01*
X101267Y1469392D01*
G01X104158Y1468142D02*
X104450Y1468433D01*
X104700Y1468600D01*
X105033Y1468683D01*
X105325Y1468600D01*
X105533Y1468433D01*
X105700Y1468183D01*
X105742Y1467892D01*
X105700Y1467642D01*
X105533Y1467392D01*
X105283Y1467183D01*
X104992Y1467100D01*
X104658Y1467183D01*
X104367Y1467433D01*
X104200Y1467808D01*
X104158Y1468225D01*
X104242Y1468767D01*
X104367Y1469058D01*
X104575Y1469350D01*
X104867Y1469558D01*
X105158Y1469600D01*
X105450Y1469517D01*
X105658Y1469308D01*
G01X93500Y1458800D02*
X97500D01*
Y1466200D01*
G01X89300Y1453000D02*
Y1449000D01*
X96700D01*
G01Y1444500D02*
Y1448500D01*
X89300D01*
G01X107700Y1427900D02*
Y1423900D01*
X115100D01*
G01X89300Y1441000D02*
Y1437000D01*
X96700D01*
G01X149069Y1433019D02*
X136069D01*
G01X132317Y1436792D02*
X132067Y1436917D01*
X131775Y1437000D01*
X131442D01*
X131067Y1436875D01*
X130775Y1436667D01*
X130567Y1436417D01*
X130400Y1436000D01*
X130358Y1435625D01*
X130442Y1435250D01*
X130567Y1435000D01*
X130817Y1434750D01*
X131108Y1434583D01*
X131400Y1434500D01*
X131692D01*
X131983Y1434583D01*
X132233Y1434708D01*
X132442Y1434875D01*
G01X133583D02*
X133833Y1434667D01*
X134125Y1434542D01*
X134500Y1434500D01*
X134875Y1434583D01*
X135167Y1434750D01*
X135375Y1435042D01*
X135417Y1435375D01*
X135333Y1435708D01*
X135125Y1435917D01*
X134833Y1436083D01*
X134542Y1436125D01*
X134250Y1436083D01*
X133875Y1435917D01*
X134000Y1437000D01*
X135125D01*
G01X137600Y1434500D02*
Y1437000D01*
X137100Y1436500D01*
G01Y1434500D02*
X138100D01*
G01X117300Y1473317D02*
X114800D01*
Y1474317D01*
X114925Y1474650D01*
X115217Y1474900D01*
X115550Y1474983D01*
X115883Y1474900D01*
X116133Y1474692D01*
X116258Y1474317D01*
Y1473317D01*
G01X117300Y1476417D02*
X114800D01*
Y1477458D01*
X114925Y1477792D01*
X115092Y1478000D01*
X115425Y1478083D01*
X115758Y1478000D01*
X115967Y1477750D01*
X116092Y1477458D01*
Y1476417D01*
G01Y1477458D02*
X117300Y1478083D01*
G01Y1480350D02*
X114800D01*
X115300Y1479850D01*
G01X117300D02*
Y1480850D01*
G01X114800Y1483450D02*
X114883Y1483117D01*
X115092Y1482867D01*
X115342Y1482700D01*
X115675Y1482575D01*
X116050Y1482533D01*
X116425Y1482575D01*
X116758Y1482700D01*
X117008Y1482867D01*
X117217Y1483117D01*
X117300Y1483450D01*
X117217Y1483783D01*
X117008Y1484033D01*
X116758Y1484200D01*
X116425Y1484325D01*
X116050Y1484367D01*
X115675Y1484325D01*
X115342Y1484200D01*
X115092Y1484033D01*
X114883Y1483783D01*
X114800Y1483450D01*
G01X127000Y1471800D02*
X131000D01*
Y1479200D01*
G01X138000Y1505517D02*
X135500D01*
Y1506517D01*
X135625Y1506850D01*
X135917Y1507100D01*
X136250Y1507183D01*
X136583Y1507100D01*
X136833Y1506892D01*
X136958Y1506517D01*
Y1505517D01*
G01X138000Y1508617D02*
X135500D01*
Y1509658D01*
X135625Y1509992D01*
X135792Y1510200D01*
X136125Y1510283D01*
X136458Y1510200D01*
X136667Y1509950D01*
X136792Y1509658D01*
Y1508617D01*
G01Y1509658D02*
X138000Y1510283D01*
G01X135917Y1511758D02*
X135667Y1512008D01*
X135542Y1512300D01*
X135500Y1512633D01*
X135583Y1513050D01*
X135792Y1513342D01*
X136042Y1513425D01*
X136292Y1513383D01*
X136500Y1513217D01*
X136917Y1512383D01*
X137208Y1512008D01*
X137625Y1511758D01*
X138000Y1511675D01*
Y1513425D01*
G01Y1516150D02*
X135500D01*
X137292Y1514608D01*
Y1516692D01*
G01X135000Y1496300D02*
X139000D01*
Y1503700D01*
G01X134000Y1505517D02*
X131500D01*
Y1506517D01*
X131625Y1506850D01*
X131917Y1507100D01*
X132250Y1507183D01*
X132583Y1507100D01*
X132833Y1506892D01*
X132958Y1506517D01*
Y1505517D01*
G01X134000Y1508617D02*
X131500D01*
Y1509658D01*
X131625Y1509992D01*
X131792Y1510200D01*
X132125Y1510283D01*
X132458Y1510200D01*
X132667Y1509950D01*
X132792Y1509658D01*
Y1508617D01*
G01Y1509658D02*
X134000Y1510283D01*
G01X131917Y1511758D02*
X131667Y1512008D01*
X131542Y1512300D01*
X131500Y1512633D01*
X131583Y1513050D01*
X131792Y1513342D01*
X132042Y1513425D01*
X132292Y1513383D01*
X132500Y1513217D01*
X132917Y1512383D01*
X133208Y1512008D01*
X133625Y1511758D01*
X134000Y1511675D01*
Y1513425D01*
G01X133500Y1514733D02*
X133792Y1514983D01*
X133958Y1515317D01*
X134000Y1515692D01*
X133958Y1516025D01*
X133750Y1516358D01*
X133500Y1516567D01*
X133250Y1516608D01*
X132958Y1516525D01*
X132750Y1516233D01*
X132667Y1515942D01*
Y1515567D01*
G01Y1515942D02*
X132542Y1516192D01*
X132333Y1516400D01*
X132083Y1516483D01*
X131833Y1516400D01*
X131625Y1516192D01*
X131500Y1515817D01*
X131542Y1515442D01*
X131708Y1515067D01*
G01X131000Y1496300D02*
X135000D01*
Y1503700D01*
G01X130000Y1505517D02*
X127500D01*
Y1506517D01*
X127625Y1506850D01*
X127917Y1507100D01*
X128250Y1507183D01*
X128583Y1507100D01*
X128833Y1506892D01*
X128958Y1506517D01*
Y1505517D01*
G01X130000Y1508617D02*
X127500D01*
Y1509658D01*
X127625Y1509992D01*
X127792Y1510200D01*
X128125Y1510283D01*
X128458Y1510200D01*
X128667Y1509950D01*
X128792Y1509658D01*
Y1508617D01*
G01Y1509658D02*
X130000Y1510283D01*
G01X127917Y1511758D02*
X127667Y1512008D01*
X127542Y1512300D01*
X127500Y1512633D01*
X127583Y1513050D01*
X127792Y1513342D01*
X128042Y1513425D01*
X128292Y1513383D01*
X128500Y1513217D01*
X128917Y1512383D01*
X129208Y1512008D01*
X129625Y1511758D01*
X130000Y1511675D01*
Y1513425D01*
G01X127917Y1514858D02*
X127667Y1515108D01*
X127542Y1515400D01*
X127500Y1515733D01*
X127583Y1516150D01*
X127792Y1516442D01*
X128042Y1516525D01*
X128292Y1516483D01*
X128500Y1516317D01*
X128917Y1515483D01*
X129208Y1515108D01*
X129625Y1514858D01*
X130000Y1514775D01*
Y1516525D01*
G01X127000Y1496300D02*
X131000D01*
Y1503700D01*
G01X126000Y1505517D02*
X123500D01*
Y1506517D01*
X123625Y1506850D01*
X123917Y1507100D01*
X124250Y1507183D01*
X124583Y1507100D01*
X124833Y1506892D01*
X124958Y1506517D01*
Y1505517D01*
G01X126000Y1508617D02*
X123500D01*
Y1509658D01*
X123625Y1509992D01*
X123792Y1510200D01*
X124125Y1510283D01*
X124458Y1510200D01*
X124667Y1509950D01*
X124792Y1509658D01*
Y1508617D01*
G01Y1509658D02*
X126000Y1510283D01*
G01X123917Y1511758D02*
X123667Y1512008D01*
X123542Y1512300D01*
X123500Y1512633D01*
X123583Y1513050D01*
X123792Y1513342D01*
X124042Y1513425D01*
X124292Y1513383D01*
X124500Y1513217D01*
X124917Y1512383D01*
X125208Y1512008D01*
X125625Y1511758D01*
X126000Y1511675D01*
Y1513425D01*
G01Y1515650D02*
X123500D01*
X124000Y1515150D01*
G01X126000D02*
Y1516150D01*
G01X123000Y1496300D02*
X127000D01*
Y1503700D01*
G01X122000Y1505517D02*
X119500D01*
Y1506517D01*
X119625Y1506850D01*
X119917Y1507100D01*
X120250Y1507183D01*
X120583Y1507100D01*
X120833Y1506892D01*
X120958Y1506517D01*
Y1505517D01*
G01X122000Y1508617D02*
X119500D01*
Y1509658D01*
X119625Y1509992D01*
X119792Y1510200D01*
X120125Y1510283D01*
X120458Y1510200D01*
X120667Y1509950D01*
X120792Y1509658D01*
Y1508617D01*
G01Y1509658D02*
X122000Y1510283D01*
G01X119917Y1511758D02*
X119667Y1512008D01*
X119542Y1512300D01*
X119500Y1512633D01*
X119583Y1513050D01*
X119792Y1513342D01*
X120042Y1513425D01*
X120292Y1513383D01*
X120500Y1513217D01*
X120917Y1512383D01*
X121208Y1512008D01*
X121625Y1511758D01*
X122000Y1511675D01*
Y1513425D01*
G01X119500Y1515650D02*
X119583Y1515317D01*
X119792Y1515067D01*
X120042Y1514900D01*
X120375Y1514775D01*
X120750Y1514733D01*
X121125Y1514775D01*
X121458Y1514900D01*
X121708Y1515067D01*
X121917Y1515317D01*
X122000Y1515650D01*
X121917Y1515983D01*
X121708Y1516233D01*
X121458Y1516400D01*
X121125Y1516525D01*
X120750Y1516567D01*
X120375Y1516525D01*
X120042Y1516400D01*
X119792Y1516233D01*
X119583Y1515983D01*
X119500Y1515650D01*
G01X119000Y1496300D02*
X123000D01*
Y1503700D01*
G01X96067Y1493000D02*
Y1495500D01*
X97067D01*
X97400Y1495375D01*
X97650Y1495083D01*
X97733Y1494750D01*
X97650Y1494417D01*
X97442Y1494167D01*
X97067Y1494042D01*
X96067D01*
G01X99167Y1493000D02*
Y1495500D01*
X100208D01*
X100542Y1495375D01*
X100750Y1495208D01*
X100833Y1494875D01*
X100750Y1494542D01*
X100500Y1494333D01*
X100208Y1494208D01*
X99167D01*
G01X100208D02*
X100833Y1493000D01*
G01X102308Y1495083D02*
X102558Y1495333D01*
X102850Y1495458D01*
X103183Y1495500D01*
X103600Y1495417D01*
X103892Y1495208D01*
X103975Y1494958D01*
X103933Y1494708D01*
X103767Y1494500D01*
X102933Y1494083D01*
X102558Y1493792D01*
X102308Y1493375D01*
X102225Y1493000D01*
X103975D01*
G01X109500Y1492200D02*
X105500D01*
Y1484800D01*
G01X118000Y1505517D02*
X115500D01*
Y1506517D01*
X115625Y1506850D01*
X115917Y1507100D01*
X116250Y1507183D01*
X116583Y1507100D01*
X116833Y1506892D01*
X116958Y1506517D01*
Y1505517D01*
G01X118000Y1508617D02*
X115500D01*
Y1509658D01*
X115625Y1509992D01*
X115792Y1510200D01*
X116125Y1510283D01*
X116458Y1510200D01*
X116667Y1509950D01*
X116792Y1509658D01*
Y1508617D01*
G01Y1509658D02*
X118000Y1510283D01*
G01Y1512550D02*
X115500D01*
X116000Y1512050D01*
G01X118000D02*
Y1513050D01*
G01X117708Y1514942D02*
X117917Y1515233D01*
X118000Y1515567D01*
X117917Y1515900D01*
X117667Y1516192D01*
X117292Y1516400D01*
X116917Y1516483D01*
X116458D01*
X116083Y1516400D01*
X115750Y1516192D01*
X115583Y1515942D01*
X115500Y1515650D01*
X115583Y1515317D01*
X115750Y1515067D01*
X116000Y1514900D01*
X116333Y1514817D01*
X116625Y1514900D01*
X116917Y1515108D01*
X117083Y1515358D01*
X117125Y1515650D01*
X117042Y1515983D01*
X116833Y1516233D01*
X116458Y1516483D01*
G01X115000Y1496300D02*
X119000D01*
Y1503700D01*
G01X114000Y1505517D02*
X111500D01*
Y1506517D01*
X111625Y1506850D01*
X111917Y1507100D01*
X112250Y1507183D01*
X112583Y1507100D01*
X112833Y1506892D01*
X112958Y1506517D01*
Y1505517D01*
G01X114000Y1508617D02*
X111500D01*
Y1509658D01*
X111625Y1509992D01*
X111792Y1510200D01*
X112125Y1510283D01*
X112458Y1510200D01*
X112667Y1509950D01*
X112792Y1509658D01*
Y1508617D01*
G01Y1509658D02*
X114000Y1510283D01*
G01Y1512550D02*
X111500D01*
X112000Y1512050D01*
G01X114000D02*
Y1513050D01*
G01Y1515650D02*
X113958Y1515942D01*
X113833Y1516275D01*
X113625Y1516483D01*
X113333Y1516567D01*
X113042Y1516483D01*
X112792Y1516233D01*
X112667Y1515858D01*
Y1515442D01*
X112583Y1515192D01*
X112375Y1514983D01*
X112083Y1514900D01*
X111792Y1515025D01*
X111583Y1515317D01*
X111500Y1515650D01*
X111583Y1515983D01*
X111792Y1516275D01*
X112083Y1516400D01*
X112375Y1516317D01*
X112583Y1516108D01*
X112667Y1515858D01*
Y1515442D01*
X112792Y1515067D01*
X113042Y1514817D01*
X113333Y1514733D01*
X113625Y1514817D01*
X113833Y1515025D01*
X113958Y1515358D01*
X114000Y1515650D01*
G01X111000Y1496300D02*
X115000D01*
Y1503700D01*
G01X110000Y1505517D02*
X107500D01*
Y1506517D01*
X107625Y1506850D01*
X107917Y1507100D01*
X108250Y1507183D01*
X108583Y1507100D01*
X108833Y1506892D01*
X108958Y1506517D01*
Y1505517D01*
G01X110000Y1508617D02*
X107500D01*
Y1509658D01*
X107625Y1509992D01*
X107792Y1510200D01*
X108125Y1510283D01*
X108458Y1510200D01*
X108667Y1509950D01*
X108792Y1509658D01*
Y1508617D01*
G01Y1509658D02*
X110000Y1510283D01*
G01Y1512550D02*
X107500D01*
X108000Y1512050D01*
G01X110000D02*
Y1513050D01*
G01Y1515567D02*
X109458Y1515650D01*
X109000Y1515775D01*
X108583Y1515942D01*
X108125Y1516150D01*
X107500Y1516483D01*
Y1514817D01*
G01X107000Y1496300D02*
X111000D01*
Y1503700D01*
G01X135900Y1485700D02*
X139900D01*
Y1493100D01*
G01X87900Y1519100D02*
Y1530300D01*
G01Y1503100D02*
Y1491900D01*
G01X96067Y1485000D02*
Y1487500D01*
X97067D01*
X97400Y1487375D01*
X97650Y1487083D01*
X97733Y1486750D01*
X97650Y1486417D01*
X97442Y1486167D01*
X97067Y1486042D01*
X96067D01*
G01X100917Y1487292D02*
X100667Y1487417D01*
X100375Y1487500D01*
X100042D01*
X99667Y1487375D01*
X99375Y1487167D01*
X99167Y1486917D01*
X99000Y1486500D01*
X98958Y1486125D01*
X99042Y1485750D01*
X99167Y1485500D01*
X99417Y1485250D01*
X99708Y1485083D01*
X100000Y1485000D01*
X100292D01*
X100583Y1485083D01*
X100833Y1485208D01*
X101042Y1485375D01*
G01X103100Y1485000D02*
Y1487500D01*
X102600Y1487000D01*
G01Y1485000D02*
X103600D01*
G01X94300Y1482817D02*
X91800D01*
Y1483817D01*
X91925Y1484150D01*
X92217Y1484400D01*
X92550Y1484483D01*
X92883Y1484400D01*
X93133Y1484192D01*
X93258Y1483817D01*
Y1482817D01*
G01X94300Y1485917D02*
X91800D01*
Y1486958D01*
X91925Y1487292D01*
X92092Y1487500D01*
X92425Y1487583D01*
X92758Y1487500D01*
X92967Y1487250D01*
X93092Y1486958D01*
Y1485917D01*
G01Y1486958D02*
X94300Y1487583D01*
G01X93800Y1488933D02*
X94092Y1489183D01*
X94258Y1489517D01*
X94300Y1489892D01*
X94258Y1490225D01*
X94050Y1490558D01*
X93800Y1490767D01*
X93550Y1490808D01*
X93258Y1490725D01*
X93050Y1490433D01*
X92967Y1490142D01*
Y1489767D01*
G01Y1490142D02*
X92842Y1490392D01*
X92633Y1490600D01*
X92383Y1490683D01*
X92133Y1490600D01*
X91925Y1490392D01*
X91800Y1490017D01*
X91842Y1489642D01*
X92008Y1489267D01*
G01X94300Y1492867D02*
X93758Y1492950D01*
X93300Y1493075D01*
X92883Y1493242D01*
X92425Y1493450D01*
X91800Y1493783D01*
Y1492117D01*
G01X91500Y1473800D02*
X95500D01*
Y1481200D01*
G01X114517Y1487000D02*
Y1489500D01*
X115517D01*
X115850Y1489375D01*
X116100Y1489083D01*
X116183Y1488750D01*
X116100Y1488417D01*
X115892Y1488167D01*
X115517Y1488042D01*
X114517D01*
G01X117617Y1487000D02*
Y1489500D01*
X118658D01*
X118992Y1489375D01*
X119200Y1489208D01*
X119283Y1488875D01*
X119200Y1488542D01*
X118950Y1488333D01*
X118658Y1488208D01*
X117617D01*
G01X118658D02*
X119283Y1487000D01*
G01X121550D02*
Y1489500D01*
X121050Y1489000D01*
G01Y1487000D02*
X122050D01*
G01X125150D02*
Y1489500D01*
X123608Y1487708D01*
X125692D01*
G01X126800Y1484000D02*
Y1480000D01*
X134200D01*
G01X96067Y1489000D02*
Y1491500D01*
X97067D01*
X97400Y1491375D01*
X97650Y1491083D01*
X97733Y1490750D01*
X97650Y1490417D01*
X97442Y1490167D01*
X97067Y1490042D01*
X96067D01*
G01X100917Y1491292D02*
X100667Y1491417D01*
X100375Y1491500D01*
X100042D01*
X99667Y1491375D01*
X99375Y1491167D01*
X99167Y1490917D01*
X99000Y1490500D01*
X98958Y1490125D01*
X99042Y1489750D01*
X99167Y1489500D01*
X99417Y1489250D01*
X99708Y1489083D01*
X100000Y1489000D01*
X100292D01*
X100583Y1489083D01*
X100833Y1489208D01*
X101042Y1489375D01*
G01X102308Y1491083D02*
X102558Y1491333D01*
X102850Y1491458D01*
X103183Y1491500D01*
X103600Y1491417D01*
X103892Y1491208D01*
X103975Y1490958D01*
X103933Y1490708D01*
X103767Y1490500D01*
X102933Y1490083D01*
X102558Y1489792D01*
X102308Y1489375D01*
X102225Y1489000D01*
X103975D01*
G01X125150Y1571300D02*
X146850D01*
G01X125150Y1601300D02*
Y1571300D01*
G01X111850D02*
Y1601300D01*
G01X90150Y1571300D02*
X111850D01*
G01X90150Y1601300D02*
Y1571300D01*
G01X132967Y1603600D02*
Y1606100D01*
X133967D01*
X134300Y1605975D01*
X134550Y1605683D01*
X134633Y1605350D01*
X134550Y1605017D01*
X134342Y1604767D01*
X133967Y1604642D01*
X132967D01*
G01X136900Y1603600D02*
X136567Y1603642D01*
X136275Y1603808D01*
X136025Y1604058D01*
X135858Y1604350D01*
X135775Y1604683D01*
Y1605017D01*
X135858Y1605350D01*
X136025Y1605642D01*
X136275Y1605892D01*
X136567Y1606058D01*
X136900Y1606100D01*
X137233Y1606058D01*
X137525Y1605892D01*
X137775Y1605642D01*
X137942Y1605350D01*
X138025Y1605017D01*
Y1604683D01*
X137942Y1604350D01*
X137775Y1604058D01*
X137525Y1603808D01*
X137233Y1603642D01*
X136900Y1603600D01*
G01X137233Y1604267D02*
X137733Y1603600D01*
G01X139208Y1605683D02*
X139458Y1605933D01*
X139750Y1606058D01*
X140083Y1606100D01*
X140500Y1606017D01*
X140792Y1605808D01*
X140875Y1605558D01*
X140833Y1605308D01*
X140667Y1605100D01*
X139833Y1604683D01*
X139458Y1604392D01*
X139208Y1603975D01*
X139125Y1603600D01*
X140875D01*
G01X146850Y1601300D02*
X125150D01*
G01X98467Y1604100D02*
Y1606600D01*
X99467D01*
X99800Y1606475D01*
X100050Y1606183D01*
X100133Y1605850D01*
X100050Y1605517D01*
X99842Y1605267D01*
X99467Y1605142D01*
X98467D01*
G01X102400Y1604100D02*
X102067Y1604142D01*
X101775Y1604308D01*
X101525Y1604558D01*
X101358Y1604850D01*
X101275Y1605183D01*
Y1605517D01*
X101358Y1605850D01*
X101525Y1606142D01*
X101775Y1606392D01*
X102067Y1606558D01*
X102400Y1606600D01*
X102733Y1606558D01*
X103025Y1606392D01*
X103275Y1606142D01*
X103442Y1605850D01*
X103525Y1605517D01*
Y1605183D01*
X103442Y1604850D01*
X103275Y1604558D01*
X103025Y1604308D01*
X102733Y1604142D01*
X102400Y1604100D01*
G01X102733Y1604767D02*
X103233Y1604100D01*
G01X105500D02*
Y1606600D01*
X105000Y1606100D01*
G01Y1604100D02*
X106000D01*
G01X111850Y1601300D02*
X90150D01*
G01X124750Y1610000D02*
Y1623000D01*
X140250D01*
Y1610000D01*
X124750D01*
G01X116000Y1611517D02*
X113500D01*
Y1612517D01*
X113625Y1612850D01*
X113917Y1613100D01*
X114250Y1613183D01*
X114583Y1613100D01*
X114833Y1612892D01*
X114958Y1612517D01*
Y1611517D01*
G01X116000Y1614617D02*
X113500D01*
Y1615658D01*
X113625Y1615992D01*
X113792Y1616200D01*
X114125Y1616283D01*
X114458Y1616200D01*
X114667Y1615950D01*
X114792Y1615658D01*
Y1614617D01*
G01Y1615658D02*
X116000Y1616283D01*
G01X115500Y1617633D02*
X115792Y1617883D01*
X115958Y1618217D01*
X116000Y1618592D01*
X115958Y1618925D01*
X115750Y1619258D01*
X115500Y1619467D01*
X115250Y1619508D01*
X114958Y1619425D01*
X114750Y1619133D01*
X114667Y1618842D01*
Y1618467D01*
G01Y1618842D02*
X114542Y1619092D01*
X114333Y1619300D01*
X114083Y1619383D01*
X113833Y1619300D01*
X113625Y1619092D01*
X113500Y1618717D01*
X113542Y1618342D01*
X113708Y1617967D01*
G01X113500Y1621650D02*
X113583Y1621317D01*
X113792Y1621067D01*
X114042Y1620900D01*
X114375Y1620775D01*
X114750Y1620733D01*
X115125Y1620775D01*
X115458Y1620900D01*
X115708Y1621067D01*
X115917Y1621317D01*
X116000Y1621650D01*
X115917Y1621983D01*
X115708Y1622233D01*
X115458Y1622400D01*
X115125Y1622525D01*
X114750Y1622567D01*
X114375Y1622525D01*
X114042Y1622400D01*
X113792Y1622233D01*
X113583Y1621983D01*
X113500Y1621650D01*
G01X96250Y1610000D02*
Y1623000D01*
X111750D01*
Y1610000D01*
X96250D01*
G01X189367Y1688975D02*
X133467D01*
Y1773126D01*
X138779D01*
G03Y1784512I0J5693D01*
G01X133467D01*
Y1857875D01*
X189367D01*
Y1688975D01*
G01X128208Y1763817D02*
X128083Y1763567D01*
X128000Y1763275D01*
Y1762942D01*
X128125Y1762567D01*
X128333Y1762275D01*
X128583Y1762067D01*
X129000Y1761900D01*
X129375Y1761858D01*
X129750Y1761942D01*
X130000Y1762067D01*
X130250Y1762317D01*
X130417Y1762608D01*
X130500Y1762900D01*
Y1763192D01*
X130417Y1763483D01*
X130292Y1763733D01*
X130125Y1763942D01*
G01X130500Y1765042D02*
X128000D01*
X130500Y1766958D01*
X128000D01*
G01X130500Y1769100D02*
X130458Y1769392D01*
X130333Y1769725D01*
X130125Y1769933D01*
X129833Y1770017D01*
X129542Y1769933D01*
X129292Y1769683D01*
X129167Y1769308D01*
Y1768892D01*
X129083Y1768642D01*
X128875Y1768433D01*
X128583Y1768350D01*
X128292Y1768475D01*
X128083Y1768767D01*
X128000Y1769100D01*
X128083Y1769433D01*
X128292Y1769725D01*
X128583Y1769850D01*
X128875Y1769767D01*
X129083Y1769558D01*
X129167Y1769308D01*
Y1768892D01*
X129292Y1768517D01*
X129542Y1768267D01*
X129833Y1768183D01*
X130125Y1768267D01*
X130333Y1768475D01*
X130458Y1768808D01*
X130500Y1769100D01*
G01X144937Y1784819D02*
X112937D01*
Y1772819D01*
X144937D01*
Y1784819D01*
G01X86997Y1877198D02*
Y1915998D01*
G01X109997Y1877198D02*
X86997D01*
G01X109997Y1915998D02*
Y1877198D01*
G01X119850Y1874000D02*
Y1871500D01*
G01X118892Y1874000D02*
X120808D01*
G01X123867Y1873792D02*
X123617Y1873917D01*
X123325Y1874000D01*
X122992D01*
X122617Y1873875D01*
X122325Y1873667D01*
X122117Y1873417D01*
X121950Y1873000D01*
X121908Y1872625D01*
X121992Y1872250D01*
X122117Y1872000D01*
X122367Y1871750D01*
X122658Y1871583D01*
X122950Y1871500D01*
X123242D01*
X123533Y1871583D01*
X123783Y1871708D01*
X123992Y1871875D01*
G01X126050Y1871500D02*
Y1874000D01*
X125550Y1873500D01*
G01Y1871500D02*
X126550D01*
G01X129150D02*
X129442Y1871542D01*
X129775Y1871667D01*
X129983Y1871875D01*
X130067Y1872167D01*
X129983Y1872458D01*
X129733Y1872708D01*
X129358Y1872833D01*
X128942D01*
X128692Y1872917D01*
X128483Y1873125D01*
X128400Y1873417D01*
X128525Y1873708D01*
X128817Y1873917D01*
X129150Y1874000D01*
X129483Y1873917D01*
X129775Y1873708D01*
X129900Y1873417D01*
X129817Y1873125D01*
X129608Y1872917D01*
X129358Y1872833D01*
X128942D01*
X128567Y1872708D01*
X128317Y1872458D01*
X128233Y1872167D01*
X128317Y1871875D01*
X128525Y1871667D01*
X128858Y1871542D01*
X129150Y1871500D01*
G01X133298Y1876703D02*
Y1887903D01*
G01X115298Y1876703D02*
X133298D01*
G01X115298Y1887903D02*
Y1876703D01*
G01X91517Y1861000D02*
Y1863500D01*
X92517D01*
X92850Y1863375D01*
X93100Y1863083D01*
X93183Y1862750D01*
X93100Y1862417D01*
X92892Y1862167D01*
X92517Y1862042D01*
X91517D01*
G01X94408Y1861000D02*
X95450Y1863500D01*
X96492Y1861000D01*
G01X96117Y1861875D02*
X94783D01*
G01X97633Y1861000D02*
Y1863500D01*
X98467D01*
X98800Y1863375D01*
X99050Y1863208D01*
X99258Y1862958D01*
X99425Y1862667D01*
X99467Y1862250D01*
X99425Y1861833D01*
X99258Y1861542D01*
X99050Y1861292D01*
X98800Y1861125D01*
X98467Y1861000D01*
X97633D01*
G01X101650D02*
Y1863500D01*
X101150Y1863000D01*
G01Y1861000D02*
X102150D01*
G01X86997Y1915998D02*
X109997D01*
G01X133298Y1915103D02*
Y1903903D01*
G01X115298Y1915103D02*
X133298D01*
G01X115298Y1903903D02*
Y1915103D01*
G01X137586Y1963287D02*
Y1967287D01*
X136786Y1966487D01*
G01Y1963287D02*
X138386D01*
G01X147000Y85850D02*
X149500D01*
G01X147000Y84892D02*
Y86808D01*
G01X147208Y89867D02*
X147083Y89617D01*
X147000Y89325D01*
Y88992D01*
X147125Y88617D01*
X147333Y88325D01*
X147583Y88117D01*
X148000Y87950D01*
X148375Y87908D01*
X148750Y87992D01*
X149000Y88117D01*
X149250Y88367D01*
X149417Y88658D01*
X149500Y88950D01*
Y89242D01*
X149417Y89533D01*
X149292Y89783D01*
X149125Y89992D01*
G01X149500Y92050D02*
X147000D01*
X147500Y91550D01*
G01X149500D02*
Y92550D01*
G01X149000Y94233D02*
X149292Y94483D01*
X149458Y94817D01*
X149500Y95192D01*
X149458Y95525D01*
X149250Y95858D01*
X149000Y96067D01*
X148750Y96108D01*
X148458Y96025D01*
X148250Y95733D01*
X148167Y95442D01*
Y95067D01*
G01Y95442D02*
X148042Y95692D01*
X147833Y95900D01*
X147583Y95983D01*
X147333Y95900D01*
X147125Y95692D01*
X147000Y95317D01*
X147042Y94942D01*
X147208Y94567D01*
G01X144700Y97500D02*
Y79500D01*
G01X176709Y98740D02*
Y101240D01*
G01X178459D02*
Y98740D01*
G01Y99990D02*
X176709D01*
G01X180684Y98740D02*
Y101240D01*
X180184Y100740D01*
G01Y98740D02*
X181184D01*
G01X153600Y347700D02*
X164800D01*
G01X153600Y365700D02*
Y347700D01*
G01X192000D02*
X180800D01*
G01X143800Y401900D02*
Y399400D01*
G01X142842Y401900D02*
X144758D01*
G01X147817Y401692D02*
X147567Y401817D01*
X147275Y401900D01*
X146942D01*
X146567Y401775D01*
X146275Y401567D01*
X146067Y401317D01*
X145900Y400900D01*
X145858Y400525D01*
X145942Y400150D01*
X146067Y399900D01*
X146317Y399650D01*
X146608Y399483D01*
X146900Y399400D01*
X147192D01*
X147483Y399483D01*
X147733Y399608D01*
X147942Y399775D01*
G01X150000Y399400D02*
X150292Y399442D01*
X150625Y399567D01*
X150833Y399775D01*
X150917Y400067D01*
X150833Y400358D01*
X150583Y400608D01*
X150208Y400733D01*
X149792D01*
X149542Y400817D01*
X149333Y401025D01*
X149250Y401317D01*
X149375Y401608D01*
X149667Y401817D01*
X150000Y401900D01*
X150333Y401817D01*
X150625Y401608D01*
X150750Y401317D01*
X150667Y401025D01*
X150458Y400817D01*
X150208Y400733D01*
X149792D01*
X149417Y400608D01*
X149167Y400358D01*
X149083Y400067D01*
X149167Y399775D01*
X149375Y399567D01*
X149708Y399442D01*
X150000Y399400D01*
G01X153700Y388900D02*
X164900D01*
G01X153700Y406900D02*
Y388900D01*
G01X192100D02*
X180900D01*
G01X149000Y353400D02*
X151500D01*
G01X149000Y352442D02*
Y354358D01*
G01X149208Y357417D02*
X149083Y357167D01*
X149000Y356875D01*
Y356542D01*
X149125Y356167D01*
X149333Y355875D01*
X149583Y355667D01*
X150000Y355500D01*
X150375Y355458D01*
X150750Y355542D01*
X151000Y355667D01*
X151250Y355917D01*
X151417Y356208D01*
X151500Y356500D01*
Y356792D01*
X151417Y357083D01*
X151292Y357333D01*
X151125Y357542D01*
G01X150458Y358808D02*
X150167Y359100D01*
X150000Y359350D01*
X149917Y359683D01*
X150000Y359975D01*
X150167Y360183D01*
X150417Y360350D01*
X150708Y360392D01*
X150958Y360350D01*
X151208Y360183D01*
X151417Y359933D01*
X151500Y359642D01*
X151417Y359308D01*
X151167Y359017D01*
X150792Y358850D01*
X150375Y358808D01*
X149833Y358892D01*
X149542Y359017D01*
X149250Y359225D01*
X149042Y359517D01*
X149000Y359808D01*
X149083Y360100D01*
X149292Y360308D01*
G01X164800Y365700D02*
X153600D01*
G01X180800D02*
X192000D01*
G01X149000Y373800D02*
X151500D01*
G01X149000Y372842D02*
Y374758D01*
G01X149208Y377817D02*
X149083Y377567D01*
X149000Y377275D01*
Y376942D01*
X149125Y376567D01*
X149333Y376275D01*
X149583Y376067D01*
X150000Y375900D01*
X150375Y375858D01*
X150750Y375942D01*
X151000Y376067D01*
X151250Y376317D01*
X151417Y376608D01*
X151500Y376900D01*
Y377192D01*
X151417Y377483D01*
X151292Y377733D01*
X151125Y377942D01*
G01Y379083D02*
X151333Y379333D01*
X151458Y379625D01*
X151500Y380000D01*
X151417Y380375D01*
X151250Y380667D01*
X150958Y380875D01*
X150625Y380917D01*
X150292Y380833D01*
X150083Y380625D01*
X149917Y380333D01*
X149875Y380042D01*
X149917Y379750D01*
X150083Y379375D01*
X149000Y379500D01*
Y380625D01*
G01X153800Y367900D02*
X165000D01*
G01X153800Y385900D02*
Y367900D01*
G01X165000Y385900D02*
X153800D01*
G01X192200Y367900D02*
X181000D01*
G01Y385900D02*
X192200D01*
G01X145700Y374300D02*
Y349300D01*
G01X155500Y428800D02*
Y432800D01*
X148100D01*
G01X159350Y435300D02*
Y465300D01*
G01X137650Y435300D02*
X159350D01*
G01X137650Y465300D02*
Y435300D01*
G01X187350D02*
Y465300D01*
G01X165650Y435300D02*
X187350D01*
G01X165650Y465300D02*
Y435300D01*
G01X164900Y406900D02*
X153700D01*
G01X180900D02*
X192100D01*
G01X144800Y420900D02*
Y418400D01*
G01X143842Y420900D02*
X145758D01*
G01X148817Y420692D02*
X148567Y420817D01*
X148275Y420900D01*
X147942D01*
X147567Y420775D01*
X147275Y420567D01*
X147067Y420317D01*
X146900Y419900D01*
X146858Y419525D01*
X146942Y419150D01*
X147067Y418900D01*
X147317Y418650D01*
X147608Y418483D01*
X147900Y418400D01*
X148192D01*
X148483Y418483D01*
X148733Y418608D01*
X148942Y418775D01*
G01X150917Y418400D02*
X151000Y418942D01*
X151125Y419400D01*
X151292Y419817D01*
X151500Y420275D01*
X151833Y420900D01*
X150167D01*
G01X153700Y409400D02*
X164900D01*
G01X153700Y427400D02*
Y409400D01*
G01X164900Y427400D02*
X153700D01*
G01X192100Y409400D02*
X180900D01*
G01Y427400D02*
X192100D01*
G01X159350Y465300D02*
X137650D01*
G01X187350D02*
X165650D01*
G01X143908Y491467D02*
X143783Y491217D01*
X143700Y490925D01*
Y490592D01*
X143825Y490217D01*
X144033Y489925D01*
X144283Y489717D01*
X144700Y489550D01*
X145075Y489508D01*
X145450Y489592D01*
X145700Y489717D01*
X145950Y489967D01*
X146117Y490258D01*
X146200Y490550D01*
Y490842D01*
X146117Y491133D01*
X145992Y491383D01*
X145825Y491592D01*
G01X144117Y492858D02*
X143867Y493108D01*
X143742Y493400D01*
X143700Y493733D01*
X143783Y494150D01*
X143992Y494442D01*
X144242Y494525D01*
X144492Y494483D01*
X144700Y494317D01*
X145117Y493483D01*
X145408Y493108D01*
X145825Y492858D01*
X146200Y492775D01*
Y494525D01*
G01X145825Y495833D02*
X146033Y496083D01*
X146158Y496375D01*
X146200Y496750D01*
X146117Y497125D01*
X145950Y497417D01*
X145658Y497625D01*
X145325Y497667D01*
X144992Y497583D01*
X144783Y497375D01*
X144617Y497083D01*
X144575Y496792D01*
X144617Y496500D01*
X144783Y496125D01*
X143700Y496250D01*
Y497375D01*
G01X146200Y499767D02*
X145658Y499850D01*
X145200Y499975D01*
X144783Y500142D01*
X144325Y500350D01*
X143700Y500683D01*
Y499017D01*
G01X170017Y501500D02*
Y504000D01*
X171017D01*
X171350Y503875D01*
X171600Y503583D01*
X171683Y503250D01*
X171600Y502917D01*
X171392Y502667D01*
X171017Y502542D01*
X170017D01*
G01X173117Y501500D02*
Y504000D01*
X174158D01*
X174492Y503875D01*
X174700Y503708D01*
X174783Y503375D01*
X174700Y503042D01*
X174450Y502833D01*
X174158Y502708D01*
X173117D01*
G01X174158D02*
X174783Y501500D01*
G01X176258Y502542D02*
X176550Y502833D01*
X176800Y503000D01*
X177133Y503083D01*
X177425Y503000D01*
X177633Y502833D01*
X177800Y502583D01*
X177842Y502292D01*
X177800Y502042D01*
X177633Y501792D01*
X177383Y501583D01*
X177092Y501500D01*
X176758Y501583D01*
X176467Y501833D01*
X176300Y502208D01*
X176258Y502625D01*
X176342Y503167D01*
X176467Y503458D01*
X176675Y503750D01*
X176967Y503958D01*
X177258Y504000D01*
X177550Y503917D01*
X177758Y503708D01*
G01X179358Y503583D02*
X179608Y503833D01*
X179900Y503958D01*
X180233Y504000D01*
X180650Y503917D01*
X180942Y503708D01*
X181025Y503458D01*
X180983Y503208D01*
X180817Y503000D01*
X179983Y502583D01*
X179608Y502292D01*
X179358Y501875D01*
X179275Y501500D01*
X181025D01*
G01X168250Y497000D02*
X183750D01*
Y467000D01*
X168250D01*
Y497000D01*
G01X151517Y501500D02*
Y504000D01*
X152517D01*
X152850Y503875D01*
X153100Y503583D01*
X153183Y503250D01*
X153100Y502917D01*
X152892Y502667D01*
X152517Y502542D01*
X151517D01*
G01X154617Y501500D02*
Y504000D01*
X155658D01*
X155992Y503875D01*
X156200Y503708D01*
X156283Y503375D01*
X156200Y503042D01*
X155950Y502833D01*
X155658Y502708D01*
X154617D01*
G01X155658D02*
X156283Y501500D01*
G01X157758Y502542D02*
X158050Y502833D01*
X158300Y503000D01*
X158633Y503083D01*
X158925Y503000D01*
X159133Y502833D01*
X159300Y502583D01*
X159342Y502292D01*
X159300Y502042D01*
X159133Y501792D01*
X158883Y501583D01*
X158592Y501500D01*
X158258Y501583D01*
X157967Y501833D01*
X157800Y502208D01*
X157758Y502625D01*
X157842Y503167D01*
X157967Y503458D01*
X158175Y503750D01*
X158467Y503958D01*
X158758Y504000D01*
X159050Y503917D01*
X159258Y503708D01*
G01X160733Y502000D02*
X160983Y501708D01*
X161317Y501542D01*
X161692Y501500D01*
X162025Y501542D01*
X162358Y501750D01*
X162567Y502000D01*
X162608Y502250D01*
X162525Y502542D01*
X162233Y502750D01*
X161942Y502833D01*
X161567D01*
G01X161942D02*
X162192Y502958D01*
X162400Y503167D01*
X162483Y503417D01*
X162400Y503667D01*
X162192Y503875D01*
X161817Y504000D01*
X161442Y503958D01*
X161067Y503792D01*
G01X150250Y497000D02*
X165750D01*
Y467000D01*
X150250D01*
Y497000D01*
G01X140067Y532000D02*
Y534500D01*
X141067D01*
X141400Y534375D01*
X141650Y534083D01*
X141733Y533750D01*
X141650Y533417D01*
X141442Y533167D01*
X141067Y533042D01*
X140067D01*
G01X143083Y534500D02*
Y532708D01*
X143250Y532333D01*
X143583Y532083D01*
X144000Y532000D01*
X144417Y532083D01*
X144750Y532333D01*
X144917Y532708D01*
Y534500D01*
G01X147017Y532000D02*
X147100Y532542D01*
X147225Y533000D01*
X147392Y533417D01*
X147600Y533875D01*
X147933Y534500D01*
X146267D01*
G01X157100Y555100D02*
Y547100D01*
X144700D01*
Y555100D01*
X157100D01*
G01X155400Y551100D02*
X156900Y549600D01*
G01X155400Y551100D02*
X156900Y552600D01*
G01X159067Y518600D02*
Y521100D01*
X160067D01*
X160400Y520975D01*
X160650Y520683D01*
X160733Y520350D01*
X160650Y520017D01*
X160442Y519767D01*
X160067Y519642D01*
X159067D01*
G01X162167Y518600D02*
Y521100D01*
X163208D01*
X163542Y520975D01*
X163750Y520808D01*
X163833Y520475D01*
X163750Y520142D01*
X163500Y519933D01*
X163208Y519808D01*
X162167D01*
G01X163208D02*
X163833Y518600D01*
G01X166100D02*
Y521100D01*
X165600Y520600D01*
G01Y518600D02*
X166600D01*
G01X169200Y521100D02*
X168867Y521017D01*
X168617Y520808D01*
X168450Y520558D01*
X168325Y520225D01*
X168283Y519850D01*
X168325Y519475D01*
X168450Y519142D01*
X168617Y518892D01*
X168867Y518683D01*
X169200Y518600D01*
X169533Y518683D01*
X169783Y518892D01*
X169950Y519142D01*
X170075Y519475D01*
X170117Y519850D01*
X170075Y520225D01*
X169950Y520558D01*
X169783Y520808D01*
X169533Y521017D01*
X169200Y521100D01*
G01X172300Y518600D02*
Y521100D01*
X171800Y520600D01*
G01Y518600D02*
X172800D01*
G01X157900Y547600D02*
Y543600D01*
X165300D01*
G01X158967Y514500D02*
Y517000D01*
X159967D01*
X160300Y516875D01*
X160550Y516583D01*
X160633Y516250D01*
X160550Y515917D01*
X160342Y515667D01*
X159967Y515542D01*
X158967D01*
G01X162067Y514500D02*
Y517000D01*
X163108D01*
X163442Y516875D01*
X163650Y516708D01*
X163733Y516375D01*
X163650Y516042D01*
X163400Y515833D01*
X163108Y515708D01*
X162067D01*
G01X163108D02*
X163733Y514500D01*
G01X166000D02*
Y517000D01*
X165500Y516500D01*
G01Y514500D02*
X166500D01*
G01X169100Y517000D02*
X168767Y516917D01*
X168517Y516708D01*
X168350Y516458D01*
X168225Y516125D01*
X168183Y515750D01*
X168225Y515375D01*
X168350Y515042D01*
X168517Y514792D01*
X168767Y514583D01*
X169100Y514500D01*
X169433Y514583D01*
X169683Y514792D01*
X169850Y515042D01*
X169975Y515375D01*
X170017Y515750D01*
X169975Y516125D01*
X169850Y516458D01*
X169683Y516708D01*
X169433Y516917D01*
X169100Y517000D01*
G01X172200D02*
X171867Y516917D01*
X171617Y516708D01*
X171450Y516458D01*
X171325Y516125D01*
X171283Y515750D01*
X171325Y515375D01*
X171450Y515042D01*
X171617Y514792D01*
X171867Y514583D01*
X172200Y514500D01*
X172533Y514583D01*
X172783Y514792D01*
X172950Y515042D01*
X173075Y515375D01*
X173117Y515750D01*
X173075Y516125D01*
X172950Y516458D01*
X172783Y516708D01*
X172533Y516917D01*
X172200Y517000D01*
G01X182967Y548000D02*
Y550500D01*
X183967D01*
X184300Y550375D01*
X184550Y550083D01*
X184633Y549750D01*
X184550Y549417D01*
X184342Y549167D01*
X183967Y549042D01*
X182967D01*
G01X186067Y548000D02*
Y550500D01*
X187108D01*
X187442Y550375D01*
X187650Y550208D01*
X187733Y549875D01*
X187650Y549542D01*
X187400Y549333D01*
X187108Y549208D01*
X186067D01*
G01X187108D02*
X187733Y548000D01*
G01X190000D02*
Y550500D01*
X189500Y550000D01*
G01Y548000D02*
X190500D01*
G01X193100D02*
Y550500D01*
X192600Y550000D01*
G01Y548000D02*
X193600D01*
G01X196200D02*
Y550500D01*
X195700Y550000D01*
G01Y548000D02*
X196700D01*
G01X179500Y520017D02*
X177000D01*
Y521017D01*
X177125Y521350D01*
X177417Y521600D01*
X177750Y521683D01*
X178083Y521600D01*
X178333Y521392D01*
X178458Y521017D01*
Y520017D01*
G01X179500Y523117D02*
X177000D01*
Y524158D01*
X177125Y524492D01*
X177292Y524700D01*
X177625Y524783D01*
X177958Y524700D01*
X178167Y524450D01*
X178292Y524158D01*
Y523117D01*
G01Y524158D02*
X179500Y524783D01*
G01X179208Y526342D02*
X179417Y526633D01*
X179500Y526967D01*
X179417Y527300D01*
X179167Y527592D01*
X178792Y527800D01*
X178417Y527883D01*
X177958D01*
X177583Y527800D01*
X177250Y527592D01*
X177083Y527342D01*
X177000Y527050D01*
X177083Y526717D01*
X177250Y526467D01*
X177500Y526300D01*
X177833Y526217D01*
X178125Y526300D01*
X178417Y526508D01*
X178583Y526758D01*
X178625Y527050D01*
X178542Y527383D01*
X178333Y527633D01*
X177958Y527883D01*
G01X178458Y529358D02*
X178167Y529650D01*
X178000Y529900D01*
X177917Y530233D01*
X178000Y530525D01*
X178167Y530733D01*
X178417Y530900D01*
X178708Y530942D01*
X178958Y530900D01*
X179208Y530733D01*
X179417Y530483D01*
X179500Y530192D01*
X179417Y529858D01*
X179167Y529567D01*
X178792Y529400D01*
X178375Y529358D01*
X177833Y529442D01*
X177542Y529567D01*
X177250Y529775D01*
X177042Y530067D01*
X177000Y530358D01*
X177083Y530650D01*
X177292Y530858D01*
G01X172600Y534500D02*
X168600D01*
Y527100D01*
G01X155500Y514017D02*
X153000D01*
Y515017D01*
X153125Y515350D01*
X153417Y515600D01*
X153750Y515683D01*
X154083Y515600D01*
X154333Y515392D01*
X154458Y515017D01*
Y514017D01*
G01X155500Y517117D02*
X153000D01*
Y518158D01*
X153125Y518492D01*
X153292Y518700D01*
X153625Y518783D01*
X153958Y518700D01*
X154167Y518450D01*
X154292Y518158D01*
Y517117D01*
G01Y518158D02*
X155500Y518783D01*
G01X155208Y520342D02*
X155417Y520633D01*
X155500Y520967D01*
X155417Y521300D01*
X155167Y521592D01*
X154792Y521800D01*
X154417Y521883D01*
X153958D01*
X153583Y521800D01*
X153250Y521592D01*
X153083Y521342D01*
X153000Y521050D01*
X153083Y520717D01*
X153250Y520467D01*
X153500Y520300D01*
X153833Y520217D01*
X154125Y520300D01*
X154417Y520508D01*
X154583Y520758D01*
X154625Y521050D01*
X154542Y521383D01*
X154333Y521633D01*
X153958Y521883D01*
G01X155500Y524067D02*
X154958Y524150D01*
X154500Y524275D01*
X154083Y524442D01*
X153625Y524650D01*
X153000Y524983D01*
Y523317D01*
G01X157600Y534400D02*
X153600D01*
Y527000D01*
G01X188100Y530417D02*
X185600D01*
Y531417D01*
X185725Y531750D01*
X186017Y532000D01*
X186350Y532083D01*
X186683Y532000D01*
X186933Y531792D01*
X187058Y531417D01*
Y530417D01*
G01X185808Y535267D02*
X185683Y535017D01*
X185600Y534725D01*
Y534392D01*
X185725Y534017D01*
X185933Y533725D01*
X186183Y533517D01*
X186600Y533350D01*
X186975Y533308D01*
X187350Y533392D01*
X187600Y533517D01*
X187850Y533767D01*
X188017Y534058D01*
X188100Y534350D01*
Y534642D01*
X188017Y534933D01*
X187892Y535183D01*
X187725Y535392D01*
G01X187808Y536742D02*
X188017Y537033D01*
X188100Y537367D01*
X188017Y537700D01*
X187767Y537992D01*
X187392Y538200D01*
X187017Y538283D01*
X186558D01*
X186183Y538200D01*
X185850Y537992D01*
X185683Y537742D01*
X185600Y537450D01*
X185683Y537117D01*
X185850Y536867D01*
X186100Y536700D01*
X186433Y536617D01*
X186725Y536700D01*
X187017Y536908D01*
X187183Y537158D01*
X187225Y537450D01*
X187142Y537783D01*
X186933Y538033D01*
X186558Y538283D01*
G01X185600Y540550D02*
X185683Y540217D01*
X185892Y539967D01*
X186142Y539800D01*
X186475Y539675D01*
X186850Y539633D01*
X187225Y539675D01*
X187558Y539800D01*
X187808Y539967D01*
X188017Y540217D01*
X188100Y540550D01*
X188017Y540883D01*
X187808Y541133D01*
X187558Y541300D01*
X187225Y541425D01*
X186850Y541467D01*
X186475Y541425D01*
X186142Y541300D01*
X185892Y541133D01*
X185683Y540883D01*
X185600Y540550D01*
G01X183600Y530417D02*
X181100D01*
Y531417D01*
X181225Y531750D01*
X181517Y532000D01*
X181850Y532083D01*
X182183Y532000D01*
X182433Y531792D01*
X182558Y531417D01*
Y530417D01*
G01X181308Y535267D02*
X181183Y535017D01*
X181100Y534725D01*
Y534392D01*
X181225Y534017D01*
X181433Y533725D01*
X181683Y533517D01*
X182100Y533350D01*
X182475Y533308D01*
X182850Y533392D01*
X183100Y533517D01*
X183350Y533767D01*
X183517Y534058D01*
X183600Y534350D01*
Y534642D01*
X183517Y534933D01*
X183392Y535183D01*
X183225Y535392D01*
G01X183600Y537450D02*
X183558Y537742D01*
X183433Y538075D01*
X183225Y538283D01*
X182933Y538367D01*
X182642Y538283D01*
X182392Y538033D01*
X182267Y537658D01*
Y537242D01*
X182183Y536992D01*
X181975Y536783D01*
X181683Y536700D01*
X181392Y536825D01*
X181183Y537117D01*
X181100Y537450D01*
X181183Y537783D01*
X181392Y538075D01*
X181683Y538200D01*
X181975Y538117D01*
X182183Y537908D01*
X182267Y537658D01*
Y537242D01*
X182392Y536867D01*
X182642Y536617D01*
X182933Y536533D01*
X183225Y536617D01*
X183433Y536825D01*
X183558Y537158D01*
X183600Y537450D01*
G01Y540550D02*
X183558Y540842D01*
X183433Y541175D01*
X183225Y541383D01*
X182933Y541467D01*
X182642Y541383D01*
X182392Y541133D01*
X182267Y540758D01*
Y540342D01*
X182183Y540092D01*
X181975Y539883D01*
X181683Y539800D01*
X181392Y539925D01*
X181183Y540217D01*
X181100Y540550D01*
X181183Y540883D01*
X181392Y541175D01*
X181683Y541300D01*
X181975Y541217D01*
X182183Y541008D01*
X182267Y540758D01*
Y540342D01*
X182392Y539967D01*
X182642Y539717D01*
X182933Y539633D01*
X183225Y539717D01*
X183433Y539925D01*
X183558Y540258D01*
X183600Y540550D01*
G01X159017Y523000D02*
Y525500D01*
X160017D01*
X160350Y525375D01*
X160600Y525083D01*
X160683Y524750D01*
X160600Y524417D01*
X160392Y524167D01*
X160017Y524042D01*
X159017D01*
G01X163867Y525292D02*
X163617Y525417D01*
X163325Y525500D01*
X162992D01*
X162617Y525375D01*
X162325Y525167D01*
X162117Y524917D01*
X161950Y524500D01*
X161908Y524125D01*
X161992Y523750D01*
X162117Y523500D01*
X162367Y523250D01*
X162658Y523083D01*
X162950Y523000D01*
X163242D01*
X163533Y523083D01*
X163783Y523208D01*
X163992Y523375D01*
G01X166050Y523000D02*
X166342Y523042D01*
X166675Y523167D01*
X166883Y523375D01*
X166967Y523667D01*
X166883Y523958D01*
X166633Y524208D01*
X166258Y524333D01*
X165842D01*
X165592Y524417D01*
X165383Y524625D01*
X165300Y524917D01*
X165425Y525208D01*
X165717Y525417D01*
X166050Y525500D01*
X166383Y525417D01*
X166675Y525208D01*
X166800Y524917D01*
X166717Y524625D01*
X166508Y524417D01*
X166258Y524333D01*
X165842D01*
X165467Y524208D01*
X165217Y523958D01*
X165133Y523667D01*
X165217Y523375D01*
X165425Y523167D01*
X165758Y523042D01*
X166050Y523000D01*
G01X168358Y524042D02*
X168650Y524333D01*
X168900Y524500D01*
X169233Y524583D01*
X169525Y524500D01*
X169733Y524333D01*
X169900Y524083D01*
X169942Y523792D01*
X169900Y523542D01*
X169733Y523292D01*
X169483Y523083D01*
X169192Y523000D01*
X168858Y523083D01*
X168567Y523333D01*
X168400Y523708D01*
X168358Y524125D01*
X168442Y524667D01*
X168567Y524958D01*
X168775Y525250D01*
X169067Y525458D01*
X169358Y525500D01*
X169650Y525417D01*
X169858Y525208D01*
G01X179500Y540017D02*
X177000D01*
Y541017D01*
X177125Y541350D01*
X177417Y541600D01*
X177750Y541683D01*
X178083Y541600D01*
X178333Y541392D01*
X178458Y541017D01*
Y540017D01*
G01X177208Y544867D02*
X177083Y544617D01*
X177000Y544325D01*
Y543992D01*
X177125Y543617D01*
X177333Y543325D01*
X177583Y543117D01*
X178000Y542950D01*
X178375Y542908D01*
X178750Y542992D01*
X179000Y543117D01*
X179250Y543367D01*
X179417Y543658D01*
X179500Y543950D01*
Y544242D01*
X179417Y544533D01*
X179292Y544783D01*
X179125Y544992D01*
G01X179208Y546342D02*
X179417Y546633D01*
X179500Y546967D01*
X179417Y547300D01*
X179167Y547592D01*
X178792Y547800D01*
X178417Y547883D01*
X177958D01*
X177583Y547800D01*
X177250Y547592D01*
X177083Y547342D01*
X177000Y547050D01*
X177083Y546717D01*
X177250Y546467D01*
X177500Y546300D01*
X177833Y546217D01*
X178125Y546300D01*
X178417Y546508D01*
X178583Y546758D01*
X178625Y547050D01*
X178542Y547383D01*
X178333Y547633D01*
X177958Y547883D01*
G01X179125Y549233D02*
X179333Y549483D01*
X179458Y549775D01*
X179500Y550150D01*
X179417Y550525D01*
X179250Y550817D01*
X178958Y551025D01*
X178625Y551067D01*
X178292Y550983D01*
X178083Y550775D01*
X177917Y550483D01*
X177875Y550192D01*
X177917Y549900D01*
X178083Y549525D01*
X177000Y549650D01*
Y550775D01*
G01X161000Y557017D02*
X158500D01*
Y558017D01*
X158625Y558350D01*
X158917Y558600D01*
X159250Y558683D01*
X159583Y558600D01*
X159833Y558392D01*
X159958Y558017D01*
Y557017D01*
G01X158708Y561867D02*
X158583Y561617D01*
X158500Y561325D01*
Y560992D01*
X158625Y560617D01*
X158833Y560325D01*
X159083Y560117D01*
X159500Y559950D01*
X159875Y559908D01*
X160250Y559992D01*
X160500Y560117D01*
X160750Y560367D01*
X160917Y560658D01*
X161000Y560950D01*
Y561242D01*
X160917Y561533D01*
X160792Y561783D01*
X160625Y561992D01*
G01X160708Y563342D02*
X160917Y563633D01*
X161000Y563967D01*
X160917Y564300D01*
X160667Y564592D01*
X160292Y564800D01*
X159917Y564883D01*
X159458D01*
X159083Y564800D01*
X158750Y564592D01*
X158583Y564342D01*
X158500Y564050D01*
X158583Y563717D01*
X158750Y563467D01*
X159000Y563300D01*
X159333Y563217D01*
X159625Y563300D01*
X159917Y563508D01*
X160083Y563758D01*
X160125Y564050D01*
X160042Y564383D01*
X159833Y564633D01*
X159458Y564883D01*
G01X161000Y567150D02*
X160958Y567442D01*
X160833Y567775D01*
X160625Y567983D01*
X160333Y568067D01*
X160042Y567983D01*
X159792Y567733D01*
X159667Y567358D01*
Y566942D01*
X159583Y566692D01*
X159375Y566483D01*
X159083Y566400D01*
X158792Y566525D01*
X158583Y566817D01*
X158500Y567150D01*
X158583Y567483D01*
X158792Y567775D01*
X159083Y567900D01*
X159375Y567817D01*
X159583Y567608D01*
X159667Y567358D01*
Y566942D01*
X159792Y566567D01*
X160042Y566317D01*
X160333Y566233D01*
X160625Y566317D01*
X160833Y566525D01*
X160958Y566858D01*
X161000Y567150D01*
G01X147500Y586350D02*
X150000D01*
G01X147500Y585392D02*
Y587308D01*
G01X150000Y588617D02*
X147500D01*
Y589617D01*
X147625Y589950D01*
X147917Y590200D01*
X148250Y590283D01*
X148583Y590200D01*
X148833Y589992D01*
X148958Y589617D01*
Y588617D01*
G01X150000Y592550D02*
X147500D01*
X148000Y592050D01*
G01X150000D02*
Y593050D01*
G01Y596150D02*
X147500D01*
X149292Y594608D01*
Y596692D01*
G01X143500Y585850D02*
X146000D01*
G01X143500Y584892D02*
Y586808D01*
G01X146000Y588117D02*
X143500D01*
Y589117D01*
X143625Y589450D01*
X143917Y589700D01*
X144250Y589783D01*
X144583Y589700D01*
X144833Y589492D01*
X144958Y589117D01*
Y588117D01*
G01X146000Y592050D02*
X143500D01*
X144000Y591550D01*
G01X146000D02*
Y592550D01*
G01X145500Y594233D02*
X145792Y594483D01*
X145958Y594817D01*
X146000Y595192D01*
X145958Y595525D01*
X145750Y595858D01*
X145500Y596067D01*
X145250Y596108D01*
X144958Y596025D01*
X144750Y595733D01*
X144667Y595442D01*
Y595067D01*
G01Y595442D02*
X144542Y595692D01*
X144333Y595900D01*
X144083Y595983D01*
X143833Y595900D01*
X143625Y595692D01*
X143500Y595317D01*
X143542Y594942D01*
X143708Y594567D01*
G01X137500Y580350D02*
X140000D01*
G01X137500Y579392D02*
Y581308D01*
G01X140000Y582617D02*
X137500D01*
Y583617D01*
X137625Y583950D01*
X137917Y584200D01*
X138250Y584283D01*
X138583Y584200D01*
X138833Y583992D01*
X138958Y583617D01*
Y582617D01*
G01X140000Y586550D02*
X137500D01*
X138000Y586050D01*
G01X140000D02*
Y587050D01*
G01Y589650D02*
X137500D01*
X138000Y589150D01*
G01X140000D02*
Y590150D01*
G01X164000Y582967D02*
X161500D01*
Y583967D01*
X161625Y584300D01*
X161917Y584550D01*
X162250Y584633D01*
X162583Y584550D01*
X162833Y584342D01*
X162958Y583967D01*
Y582967D01*
G01X164000Y586067D02*
X161500D01*
Y587108D01*
X161625Y587442D01*
X161792Y587650D01*
X162125Y587733D01*
X162458Y587650D01*
X162667Y587400D01*
X162792Y587108D01*
Y586067D01*
G01Y587108D02*
X164000Y587733D01*
G01Y590000D02*
X161500D01*
X162000Y589500D01*
G01X164000D02*
Y590500D01*
G01Y593100D02*
X161500D01*
X162000Y592600D01*
G01X164000D02*
Y593600D01*
G01X163625Y595283D02*
X163833Y595533D01*
X163958Y595825D01*
X164000Y596200D01*
X163917Y596575D01*
X163750Y596867D01*
X163458Y597075D01*
X163125Y597117D01*
X162792Y597033D01*
X162583Y596825D01*
X162417Y596533D01*
X162375Y596242D01*
X162417Y595950D01*
X162583Y595575D01*
X161500Y595700D01*
Y596825D01*
G01X143300Y576800D02*
X147300D01*
Y584200D01*
G01X151500Y564600D02*
X155500D01*
Y572000D01*
G01X150700Y566000D02*
Y570000D01*
X143300D01*
G01X163467Y599000D02*
Y601500D01*
X164467D01*
X164800Y601375D01*
X165050Y601083D01*
X165133Y600750D01*
X165050Y600417D01*
X164842Y600167D01*
X164467Y600042D01*
X163467D01*
G01X166567Y599000D02*
Y601500D01*
X167608D01*
X167942Y601375D01*
X168150Y601208D01*
X168233Y600875D01*
X168150Y600542D01*
X167900Y600333D01*
X167608Y600208D01*
X166567D01*
G01X167608D02*
X168233Y599000D01*
G01X170500D02*
Y601500D01*
X170000Y601000D01*
G01Y599000D02*
X171000D01*
G01X173600Y601500D02*
X173267Y601417D01*
X173017Y601208D01*
X172850Y600958D01*
X172725Y600625D01*
X172683Y600250D01*
X172725Y599875D01*
X172850Y599542D01*
X173017Y599292D01*
X173267Y599083D01*
X173600Y599000D01*
X173933Y599083D01*
X174183Y599292D01*
X174350Y599542D01*
X174475Y599875D01*
X174517Y600250D01*
X174475Y600625D01*
X174350Y600958D01*
X174183Y601208D01*
X173933Y601417D01*
X173600Y601500D01*
G01X176700Y599000D02*
X176992Y599042D01*
X177325Y599167D01*
X177533Y599375D01*
X177617Y599667D01*
X177533Y599958D01*
X177283Y600208D01*
X176908Y600333D01*
X176492D01*
X176242Y600417D01*
X176033Y600625D01*
X175950Y600917D01*
X176075Y601208D01*
X176367Y601417D01*
X176700Y601500D01*
X177033Y601417D01*
X177325Y601208D01*
X177450Y600917D01*
X177367Y600625D01*
X177158Y600417D01*
X176908Y600333D01*
X176492D01*
X176117Y600208D01*
X175867Y599958D01*
X175783Y599667D01*
X175867Y599375D01*
X176075Y599167D01*
X176408Y599042D01*
X176700Y599000D01*
G01X158200Y585000D02*
Y589000D01*
X150800D01*
G01X182500Y588467D02*
X180000D01*
Y589467D01*
X180125Y589800D01*
X180417Y590050D01*
X180750Y590133D01*
X181083Y590050D01*
X181333Y589842D01*
X181458Y589467D01*
Y588467D01*
G01X182500Y591567D02*
X180000D01*
Y592608D01*
X180125Y592942D01*
X180292Y593150D01*
X180625Y593233D01*
X180958Y593150D01*
X181167Y592900D01*
X181292Y592608D01*
Y591567D01*
G01Y592608D02*
X182500Y593233D01*
G01Y595500D02*
X180000D01*
X180500Y595000D01*
G01X182500D02*
Y596000D01*
G01X180000Y598600D02*
X180083Y598267D01*
X180292Y598017D01*
X180542Y597850D01*
X180875Y597725D01*
X181250Y597683D01*
X181625Y597725D01*
X181958Y597850D01*
X182208Y598017D01*
X182417Y598267D01*
X182500Y598600D01*
X182417Y598933D01*
X182208Y599183D01*
X181958Y599350D01*
X181625Y599475D01*
X181250Y599517D01*
X180875Y599475D01*
X180542Y599350D01*
X180292Y599183D01*
X180083Y598933D01*
X180000Y598600D01*
G01X182208Y600992D02*
X182417Y601283D01*
X182500Y601617D01*
X182417Y601950D01*
X182167Y602242D01*
X181792Y602450D01*
X181417Y602533D01*
X180958D01*
X180583Y602450D01*
X180250Y602242D01*
X180083Y601992D01*
X180000Y601700D01*
X180083Y601367D01*
X180250Y601117D01*
X180500Y600950D01*
X180833Y600867D01*
X181125Y600950D01*
X181417Y601158D01*
X181583Y601408D01*
X181625Y601700D01*
X181542Y602033D01*
X181333Y602283D01*
X180958Y602533D01*
G01X160000Y580600D02*
X156000D01*
Y573200D01*
G01X157000Y596617D02*
X159500D01*
Y598283D01*
G01Y600550D02*
X157000D01*
X157500Y600050D01*
G01X159500D02*
Y601050D01*
G01X168500Y586017D02*
X166000D01*
Y587017D01*
X166125Y587350D01*
X166417Y587600D01*
X166750Y587683D01*
X167083Y587600D01*
X167333Y587392D01*
X167458Y587017D01*
Y586017D01*
G01X166208Y590867D02*
X166083Y590617D01*
X166000Y590325D01*
Y589992D01*
X166125Y589617D01*
X166333Y589325D01*
X166583Y589117D01*
X167000Y588950D01*
X167375Y588908D01*
X167750Y588992D01*
X168000Y589117D01*
X168250Y589367D01*
X168417Y589658D01*
X168500Y589950D01*
Y590242D01*
X168417Y590533D01*
X168292Y590783D01*
X168125Y590992D01*
G01X168208Y592342D02*
X168417Y592633D01*
X168500Y592967D01*
X168417Y593300D01*
X168167Y593592D01*
X167792Y593800D01*
X167417Y593883D01*
X166958D01*
X166583Y593800D01*
X166250Y593592D01*
X166083Y593342D01*
X166000Y593050D01*
X166083Y592717D01*
X166250Y592467D01*
X166500Y592300D01*
X166833Y592217D01*
X167125Y592300D01*
X167417Y592508D01*
X167583Y592758D01*
X167625Y593050D01*
X167542Y593383D01*
X167333Y593633D01*
X166958Y593883D01*
G01X168500Y596650D02*
X166000D01*
X167792Y595108D01*
Y597192D01*
G01X152208Y594367D02*
X152083Y594117D01*
X152000Y593825D01*
Y593492D01*
X152125Y593117D01*
X152333Y592825D01*
X152583Y592617D01*
X153000Y592450D01*
X153375Y592408D01*
X153750Y592492D01*
X154000Y592617D01*
X154250Y592867D01*
X154417Y593158D01*
X154500Y593450D01*
Y593742D01*
X154417Y594033D01*
X154292Y594283D01*
X154125Y594492D01*
G01X154500Y596550D02*
X152000D01*
X152500Y596050D01*
G01X154500D02*
Y597050D01*
G01X139835Y632284D02*
X142835D01*
G01X139835Y622439D02*
X141835D01*
G01X186500Y606350D02*
X189000D01*
G01X186500Y605392D02*
Y607308D01*
G01X189000Y608617D02*
X186500D01*
Y609617D01*
X186625Y609950D01*
X186917Y610200D01*
X187250Y610283D01*
X187583Y610200D01*
X187833Y609992D01*
X187958Y609617D01*
Y608617D01*
G01X189000Y612550D02*
X186500D01*
X187000Y612050D01*
G01X189000D02*
Y613050D01*
G01Y615567D02*
X188458Y615650D01*
X188000Y615775D01*
X187583Y615942D01*
X187125Y616150D01*
X186500Y616483D01*
Y614817D01*
G01X143800Y620850D02*
X146300D01*
G01X143800Y619892D02*
Y621808D01*
G01X146300Y623117D02*
X143800D01*
Y624117D01*
X143925Y624450D01*
X144217Y624700D01*
X144550Y624783D01*
X144883Y624700D01*
X145133Y624492D01*
X145258Y624117D01*
Y623117D01*
G01X146300Y627050D02*
X143800D01*
X144300Y626550D01*
G01X146300D02*
Y627550D01*
G01X145925Y629233D02*
X146133Y629483D01*
X146258Y629775D01*
X146300Y630150D01*
X146217Y630525D01*
X146050Y630817D01*
X145758Y631025D01*
X145425Y631067D01*
X145092Y630983D01*
X144883Y630775D01*
X144717Y630483D01*
X144675Y630192D01*
X144717Y629900D01*
X144883Y629525D01*
X143800Y629650D01*
Y630775D01*
G01X181900Y618350D02*
X184400D01*
G01X181900Y617392D02*
Y619308D01*
G01X184400Y620617D02*
X181900D01*
Y621617D01*
X182025Y621950D01*
X182317Y622200D01*
X182650Y622283D01*
X182983Y622200D01*
X183233Y621992D01*
X183358Y621617D01*
Y620617D01*
G01X184400Y624550D02*
X181900D01*
X182400Y624050D01*
G01X184400D02*
Y625050D01*
G01X182317Y626858D02*
X182067Y627108D01*
X181942Y627400D01*
X181900Y627733D01*
X181983Y628150D01*
X182192Y628442D01*
X182442Y628525D01*
X182692Y628483D01*
X182900Y628317D01*
X183317Y627483D01*
X183608Y627108D01*
X184025Y626858D01*
X184400Y626775D01*
Y628525D01*
G01X172200Y629100D02*
X168200D01*
Y621700D01*
G01X187067Y619500D02*
Y622000D01*
X188108D01*
X188442Y621875D01*
X188650Y621708D01*
X188733Y621375D01*
X188650Y621042D01*
X188400Y620833D01*
X188108Y620708D01*
X187067D01*
G01X188108D02*
X188733Y619500D01*
G01X190083Y619875D02*
X190333Y619667D01*
X190625Y619542D01*
X191000Y619500D01*
X191375Y619583D01*
X191667Y619750D01*
X191875Y620042D01*
X191917Y620375D01*
X191833Y620708D01*
X191625Y620917D01*
X191333Y621083D01*
X191042Y621125D01*
X190750Y621083D01*
X190375Y620917D01*
X190500Y622000D01*
X191625D01*
G01X194100D02*
X193767Y621917D01*
X193517Y621708D01*
X193350Y621458D01*
X193225Y621125D01*
X193183Y620750D01*
X193225Y620375D01*
X193350Y620042D01*
X193517Y619792D01*
X193767Y619583D01*
X194100Y619500D01*
X194433Y619583D01*
X194683Y619792D01*
X194850Y620042D01*
X194975Y620375D01*
X195017Y620750D01*
X194975Y621125D01*
X194850Y621458D01*
X194683Y621708D01*
X194433Y621917D01*
X194100Y622000D01*
G01X160700Y624700D02*
Y620700D01*
X168100D01*
G01X150117Y620900D02*
Y623400D01*
X151158D01*
X151492Y623275D01*
X151700Y623108D01*
X151783Y622775D01*
X151700Y622442D01*
X151450Y622233D01*
X151158Y622108D01*
X150117D01*
G01X151158D02*
X151783Y620900D01*
G01X153258Y621942D02*
X153550Y622233D01*
X153800Y622400D01*
X154133Y622483D01*
X154425Y622400D01*
X154633Y622233D01*
X154800Y621983D01*
X154842Y621692D01*
X154800Y621442D01*
X154633Y621192D01*
X154383Y620983D01*
X154092Y620900D01*
X153758Y620983D01*
X153467Y621233D01*
X153300Y621608D01*
X153258Y622025D01*
X153342Y622567D01*
X153467Y622858D01*
X153675Y623150D01*
X153967Y623358D01*
X154258Y623400D01*
X154550Y623317D01*
X154758Y623108D01*
G01X150329Y617065D02*
Y613065D01*
X157729D01*
G01X148500Y637117D02*
X146000D01*
Y638158D01*
X146125Y638492D01*
X146292Y638700D01*
X146625Y638783D01*
X146958Y638700D01*
X147167Y638450D01*
X147292Y638158D01*
Y637117D01*
G01Y638158D02*
X148500Y638783D01*
G01X148125Y640133D02*
X148333Y640383D01*
X148458Y640675D01*
X148500Y641050D01*
X148417Y641425D01*
X148250Y641717D01*
X147958Y641925D01*
X147625Y641967D01*
X147292Y641883D01*
X147083Y641675D01*
X146917Y641383D01*
X146875Y641092D01*
X146917Y640800D01*
X147083Y640425D01*
X146000Y640550D01*
Y641675D01*
G01X149335Y630429D02*
X153335D01*
Y637829D01*
G01X186000Y641617D02*
X183500D01*
Y642658D01*
X183625Y642992D01*
X183792Y643200D01*
X184125Y643283D01*
X184458Y643200D01*
X184667Y642950D01*
X184792Y642658D01*
Y641617D01*
G01Y642658D02*
X186000Y643283D01*
G01X185500Y644633D02*
X185792Y644883D01*
X185958Y645217D01*
X186000Y645592D01*
X185958Y645925D01*
X185750Y646258D01*
X185500Y646467D01*
X185250Y646508D01*
X184958Y646425D01*
X184750Y646133D01*
X184667Y645842D01*
Y645467D01*
G01Y645842D02*
X184542Y646092D01*
X184333Y646300D01*
X184083Y646383D01*
X183833Y646300D01*
X183625Y646092D01*
X183500Y645717D01*
X183542Y645342D01*
X183708Y644967D01*
G01X182365Y647771D02*
X178365D01*
Y640371D01*
G01X146435Y647929D02*
X150435D01*
Y655329D01*
G01X187067Y624500D02*
Y627000D01*
X188108D01*
X188442Y626875D01*
X188650Y626708D01*
X188733Y626375D01*
X188650Y626042D01*
X188400Y625833D01*
X188108Y625708D01*
X187067D01*
G01X188108D02*
X188733Y624500D01*
G01X191000D02*
Y627000D01*
X190500Y626500D01*
G01Y624500D02*
X191500D01*
G01X193183Y624875D02*
X193433Y624667D01*
X193725Y624542D01*
X194100Y624500D01*
X194475Y624583D01*
X194767Y624750D01*
X194975Y625042D01*
X195017Y625375D01*
X194933Y625708D01*
X194725Y625917D01*
X194433Y626083D01*
X194142Y626125D01*
X193850Y626083D01*
X193475Y625917D01*
X193600Y627000D01*
X194725D01*
G01X168100Y624700D02*
Y628700D01*
X160700D01*
G01X179700Y622300D02*
Y626300D01*
X172300D01*
G01X142235Y647929D02*
X146235D01*
Y655329D01*
G01X176435Y650029D02*
Y630629D01*
G01X154735Y650029D02*
X176435D01*
G01X154735Y630629D02*
Y650029D01*
G01X176435Y630629D02*
X154735D01*
G01X184208Y632367D02*
X184083Y632117D01*
X184000Y631825D01*
Y631492D01*
X184125Y631117D01*
X184333Y630825D01*
X184583Y630617D01*
X185000Y630450D01*
X185375Y630408D01*
X185750Y630492D01*
X186000Y630617D01*
X186250Y630867D01*
X186417Y631158D01*
X186500Y631450D01*
Y631742D01*
X186417Y632033D01*
X186292Y632283D01*
X186125Y632492D01*
G01X185458Y633758D02*
X185167Y634050D01*
X185000Y634300D01*
X184917Y634633D01*
X185000Y634925D01*
X185167Y635133D01*
X185417Y635300D01*
X185708Y635342D01*
X185958Y635300D01*
X186208Y635133D01*
X186417Y634883D01*
X186500Y634592D01*
X186417Y634258D01*
X186167Y633967D01*
X185792Y633800D01*
X185375Y633758D01*
X184833Y633842D01*
X184542Y633967D01*
X184250Y634175D01*
X184042Y634467D01*
X184000Y634758D01*
X184083Y635050D01*
X184292Y635258D01*
G01X144067Y615892D02*
X143817Y616017D01*
X143525Y616100D01*
X143192D01*
X142817Y615975D01*
X142525Y615767D01*
X142317Y615517D01*
X142150Y615100D01*
X142108Y614725D01*
X142192Y614350D01*
X142317Y614100D01*
X142567Y613850D01*
X142858Y613683D01*
X143150Y613600D01*
X143442D01*
X143733Y613683D01*
X143983Y613808D01*
X144192Y613975D01*
G01X145458Y615683D02*
X145708Y615933D01*
X146000Y616058D01*
X146333Y616100D01*
X146750Y616017D01*
X147042Y615808D01*
X147125Y615558D01*
X147083Y615308D01*
X146917Y615100D01*
X146083Y614683D01*
X145708Y614392D01*
X145458Y613975D01*
X145375Y613600D01*
X147125D01*
G01X156065Y658688D02*
X153565D01*
Y659729D01*
X153690Y660063D01*
X153857Y660271D01*
X154190Y660354D01*
X154523Y660271D01*
X154732Y660021D01*
X154857Y659729D01*
Y658688D01*
G01Y659729D02*
X156065Y660354D01*
G01X155773Y661913D02*
X155982Y662204D01*
X156065Y662538D01*
X155982Y662871D01*
X155732Y663163D01*
X155357Y663371D01*
X154982Y663454D01*
X154523D01*
X154148Y663371D01*
X153815Y663163D01*
X153648Y662913D01*
X153565Y662621D01*
X153648Y662288D01*
X153815Y662038D01*
X154065Y661871D01*
X154398Y661788D01*
X154690Y661871D01*
X154982Y662079D01*
X155148Y662329D01*
X155190Y662621D01*
X155107Y662954D01*
X154898Y663204D01*
X154523Y663454D01*
G01X147435Y658746D02*
X144935D01*
Y659787D01*
X145060Y660121D01*
X145227Y660329D01*
X145560Y660412D01*
X145893Y660329D01*
X146102Y660079D01*
X146227Y659787D01*
Y658746D01*
G01Y659787D02*
X147435Y660412D01*
G01Y662596D02*
X146893Y662679D01*
X146435Y662804D01*
X146018Y662971D01*
X145560Y663179D01*
X144935Y663512D01*
Y661846D01*
G01X165335Y656146D02*
X162835D01*
Y657187D01*
X162960Y657521D01*
X163127Y657729D01*
X163460Y657812D01*
X163793Y657729D01*
X164002Y657479D01*
X164127Y657187D01*
Y656146D01*
G01Y657187D02*
X165335Y657812D01*
G01X163252Y659287D02*
X163002Y659537D01*
X162877Y659829D01*
X162835Y660162D01*
X162918Y660579D01*
X163127Y660871D01*
X163377Y660954D01*
X163627Y660912D01*
X163835Y660746D01*
X164252Y659912D01*
X164543Y659537D01*
X164960Y659287D01*
X165335Y659204D01*
Y660954D01*
G01X151635Y658396D02*
X149135D01*
Y659437D01*
X149260Y659771D01*
X149427Y659979D01*
X149760Y660062D01*
X150093Y659979D01*
X150302Y659729D01*
X150427Y659437D01*
Y658396D01*
G01Y659437D02*
X151635Y660062D01*
G01Y662329D02*
X149135D01*
X149635Y661829D01*
G01X151635D02*
Y662829D01*
G01Y665429D02*
X149135D01*
X149635Y664929D01*
G01X151635D02*
Y665929D01*
G01X161135Y656146D02*
X158635D01*
Y657187D01*
X158760Y657521D01*
X158927Y657729D01*
X159260Y657812D01*
X159593Y657729D01*
X159802Y657479D01*
X159927Y657187D01*
Y656146D01*
G01Y657187D02*
X161135Y657812D01*
G01Y660079D02*
X158635D01*
X159135Y659579D01*
G01X161135D02*
Y660579D01*
G01X186000Y689517D02*
X183500D01*
Y690517D01*
X183625Y690850D01*
X183917Y691100D01*
X184250Y691183D01*
X184583Y691100D01*
X184833Y690892D01*
X184958Y690517D01*
Y689517D01*
G01X186000Y692617D02*
X183500D01*
Y693658D01*
X183625Y693992D01*
X183792Y694200D01*
X184125Y694283D01*
X184458Y694200D01*
X184667Y693950D01*
X184792Y693658D01*
Y692617D01*
G01Y693658D02*
X186000Y694283D01*
G01Y697050D02*
X183500D01*
X185292Y695508D01*
Y697592D01*
G01X185625Y698733D02*
X185833Y698983D01*
X185958Y699275D01*
X186000Y699650D01*
X185917Y700025D01*
X185750Y700317D01*
X185458Y700525D01*
X185125Y700567D01*
X184792Y700483D01*
X184583Y700275D01*
X184417Y699983D01*
X184375Y699692D01*
X184417Y699400D01*
X184583Y699025D01*
X183500Y699150D01*
Y700275D01*
G01X152500Y697300D02*
X156500D01*
Y704700D01*
G01X165700Y694200D02*
X169700D01*
Y701600D01*
G01X161500Y680617D02*
X159000D01*
Y681617D01*
X159125Y681950D01*
X159417Y682200D01*
X159750Y682283D01*
X160083Y682200D01*
X160333Y681992D01*
X160458Y681617D01*
Y680617D01*
G01X161500Y683717D02*
X159000D01*
Y684758D01*
X159125Y685092D01*
X159292Y685300D01*
X159625Y685383D01*
X159958Y685300D01*
X160167Y685050D01*
X160292Y684758D01*
Y683717D01*
G01Y684758D02*
X161500Y685383D01*
G01Y688150D02*
X159000D01*
X160792Y686608D01*
Y688692D01*
G01X161500Y691250D02*
X159000D01*
X160792Y689708D01*
Y691792D01*
G01X156500Y689200D02*
X152500D01*
Y681800D01*
G01X190000Y689517D02*
X187500D01*
Y690558D01*
X187625Y690892D01*
X187792Y691100D01*
X188125Y691183D01*
X188458Y691100D01*
X188667Y690850D01*
X188792Y690558D01*
Y689517D01*
G01Y690558D02*
X190000Y691183D01*
G01X187917Y692658D02*
X187667Y692908D01*
X187542Y693200D01*
X187500Y693533D01*
X187583Y693950D01*
X187792Y694242D01*
X188042Y694325D01*
X188292Y694283D01*
X188500Y694117D01*
X188917Y693283D01*
X189208Y692908D01*
X189625Y692658D01*
X190000Y692575D01*
Y694325D01*
G01X188958Y695758D02*
X188667Y696050D01*
X188500Y696300D01*
X188417Y696633D01*
X188500Y696925D01*
X188667Y697133D01*
X188917Y697300D01*
X189208Y697342D01*
X189458Y697300D01*
X189708Y697133D01*
X189917Y696883D01*
X190000Y696592D01*
X189917Y696258D01*
X189667Y695967D01*
X189292Y695800D01*
X188875Y695758D01*
X188333Y695842D01*
X188042Y695967D01*
X187750Y696175D01*
X187542Y696467D01*
X187500Y696758D01*
X187583Y697050D01*
X187792Y697258D01*
G01X187500Y699650D02*
X187583Y699317D01*
X187792Y699067D01*
X188042Y698900D01*
X188375Y698775D01*
X188750Y698733D01*
X189125Y698775D01*
X189458Y698900D01*
X189708Y699067D01*
X189917Y699317D01*
X190000Y699650D01*
X189917Y699983D01*
X189708Y700233D01*
X189458Y700400D01*
X189125Y700525D01*
X188750Y700567D01*
X188375Y700525D01*
X188042Y700400D01*
X187792Y700233D01*
X187583Y699983D01*
X187500Y699650D01*
G01X156500Y697300D02*
X160500D01*
Y704700D01*
G01X169800Y703100D02*
Y699100D01*
X177200D01*
G01X143200Y662017D02*
X140700D01*
Y663058D01*
X140825Y663392D01*
X140992Y663600D01*
X141325Y663683D01*
X141658Y663600D01*
X141867Y663350D01*
X141992Y663058D01*
Y662017D01*
G01Y663058D02*
X143200Y663683D01*
G01Y665950D02*
X140700D01*
X141200Y665450D01*
G01X143200D02*
Y666450D01*
G01X142158Y668258D02*
X141867Y668550D01*
X141700Y668800D01*
X141617Y669133D01*
X141700Y669425D01*
X141867Y669633D01*
X142117Y669800D01*
X142408Y669842D01*
X142658Y669800D01*
X142908Y669633D01*
X143117Y669383D01*
X143200Y669092D01*
X143117Y668758D01*
X142867Y668467D01*
X142492Y668300D01*
X142075Y668258D01*
X141533Y668342D01*
X141242Y668467D01*
X140950Y668675D01*
X140742Y668967D01*
X140700Y669258D01*
X140783Y669550D01*
X140992Y669758D01*
G01X143200Y672150D02*
X140700D01*
X141200Y671650D01*
G01X143200D02*
Y672650D01*
G01X155967Y676400D02*
Y678900D01*
X156967D01*
X157300Y678775D01*
X157550Y678483D01*
X157633Y678150D01*
X157550Y677817D01*
X157342Y677567D01*
X156967Y677442D01*
X155967D01*
G01X159900Y676400D02*
X159567Y676442D01*
X159275Y676608D01*
X159025Y676858D01*
X158858Y677150D01*
X158775Y677483D01*
Y677817D01*
X158858Y678150D01*
X159025Y678442D01*
X159275Y678692D01*
X159567Y678858D01*
X159900Y678900D01*
X160233Y678858D01*
X160525Y678692D01*
X160775Y678442D01*
X160942Y678150D01*
X161025Y677817D01*
Y677483D01*
X160942Y677150D01*
X160775Y676858D01*
X160525Y676608D01*
X160233Y676442D01*
X159900Y676400D01*
G01X160233Y677067D02*
X160733Y676400D01*
G01X162292Y676692D02*
X162583Y676483D01*
X162917Y676400D01*
X163250Y676483D01*
X163542Y676733D01*
X163750Y677108D01*
X163833Y677483D01*
Y677942D01*
X163750Y678317D01*
X163542Y678650D01*
X163292Y678817D01*
X163000Y678900D01*
X162667Y678817D01*
X162417Y678650D01*
X162250Y678400D01*
X162167Y678067D01*
X162250Y677775D01*
X162458Y677483D01*
X162708Y677317D01*
X163000Y677275D01*
X163333Y677358D01*
X163583Y677567D01*
X163833Y677942D01*
G01X139000Y693000D02*
Y679000D01*
G01X152000Y693000D02*
X139000D01*
G01X152000Y679000D02*
Y693000D01*
G01X139000Y679000D02*
X152000D01*
G01X171250Y656200D02*
X170917Y656242D01*
X170625Y656408D01*
X170375Y656658D01*
X170208Y656950D01*
X170125Y657283D01*
Y657617D01*
X170208Y657950D01*
X170375Y658242D01*
X170625Y658492D01*
X170917Y658658D01*
X171250Y658700D01*
X171583Y658658D01*
X171875Y658492D01*
X172125Y658242D01*
X172292Y657950D01*
X172375Y657617D01*
Y657283D01*
X172292Y656950D01*
X172125Y656658D01*
X171875Y656408D01*
X171583Y656242D01*
X171250Y656200D01*
G01X173475Y656533D02*
X173808Y656325D01*
X174183Y656200D01*
X174517D01*
X174850Y656325D01*
X175100Y656533D01*
X175225Y656825D01*
X175142Y657117D01*
X174933Y657367D01*
X174558Y657533D01*
X174058Y657617D01*
X173767Y657783D01*
X173642Y658075D01*
X173725Y658367D01*
X173933Y658575D01*
X174225Y658700D01*
X174517D01*
X174808Y658617D01*
X175058Y658408D01*
G01X178367Y658492D02*
X178117Y658617D01*
X177825Y658700D01*
X177492D01*
X177117Y658575D01*
X176825Y658367D01*
X176617Y658117D01*
X176450Y657700D01*
X176408Y657325D01*
X176492Y656950D01*
X176617Y656700D01*
X176867Y656450D01*
X177158Y656283D01*
X177450Y656200D01*
X177742D01*
X178033Y656283D01*
X178283Y656408D01*
X178492Y656575D01*
G01X180550Y656200D02*
Y658700D01*
X180050Y658200D01*
G01Y656200D02*
X181050D01*
G01X179708Y691267D02*
X179583Y691017D01*
X179500Y690725D01*
Y690392D01*
X179625Y690017D01*
X179833Y689725D01*
X180083Y689517D01*
X180500Y689350D01*
X180875Y689308D01*
X181250Y689392D01*
X181500Y689517D01*
X181750Y689767D01*
X181917Y690058D01*
X182000Y690350D01*
Y690642D01*
X181917Y690933D01*
X181792Y691183D01*
X181625Y691392D01*
G01X179917Y692658D02*
X179667Y692908D01*
X179542Y693200D01*
X179500Y693533D01*
X179583Y693950D01*
X179792Y694242D01*
X180042Y694325D01*
X180292Y694283D01*
X180500Y694117D01*
X180917Y693283D01*
X181208Y692908D01*
X181625Y692658D01*
X182000Y692575D01*
Y694325D01*
G01X181625Y695633D02*
X181833Y695883D01*
X181958Y696175D01*
X182000Y696550D01*
X181917Y696925D01*
X181750Y697217D01*
X181458Y697425D01*
X181125Y697467D01*
X180792Y697383D01*
X180583Y697175D01*
X180417Y696883D01*
X180375Y696592D01*
X180417Y696300D01*
X180583Y695925D01*
X179500Y696050D01*
Y697175D01*
G01X182000Y700150D02*
X179500D01*
X181292Y698608D01*
Y700692D01*
G01X180500Y711533D02*
X182292D01*
X182667Y711700D01*
X182917Y712033D01*
X183000Y712450D01*
X182917Y712867D01*
X182667Y713200D01*
X182292Y713367D01*
X180500D01*
G01X183000Y715550D02*
X182958Y715842D01*
X182833Y716175D01*
X182625Y716383D01*
X182333Y716467D01*
X182042Y716383D01*
X181792Y716133D01*
X181667Y715758D01*
Y715342D01*
X181583Y715092D01*
X181375Y714883D01*
X181083Y714800D01*
X180792Y714925D01*
X180583Y715217D01*
X180500Y715550D01*
X180583Y715883D01*
X180792Y716175D01*
X181083Y716300D01*
X181375Y716217D01*
X181583Y716008D01*
X181667Y715758D01*
Y715342D01*
X181792Y714967D01*
X182042Y714717D01*
X182333Y714633D01*
X182625Y714717D01*
X182833Y714925D01*
X182958Y715258D01*
X183000Y715550D01*
G01X171900Y728204D02*
Y714204D01*
X151800D01*
Y728204D01*
X171900D01*
G01X151950Y723054D02*
X152050D01*
X153900Y721204D01*
X152100Y719404D01*
X152000D01*
G01X151500Y737917D02*
X149000D01*
Y738917D01*
X149125Y739250D01*
X149417Y739500D01*
X149750Y739583D01*
X150083Y739500D01*
X150333Y739292D01*
X150458Y738917D01*
Y737917D01*
G01X149208Y742767D02*
X149083Y742517D01*
X149000Y742225D01*
Y741892D01*
X149125Y741517D01*
X149333Y741225D01*
X149583Y741017D01*
X150000Y740850D01*
X150375Y740808D01*
X150750Y740892D01*
X151000Y741017D01*
X151250Y741267D01*
X151417Y741558D01*
X151500Y741850D01*
Y742142D01*
X151417Y742433D01*
X151292Y742683D01*
X151125Y742892D01*
G01X151500Y744950D02*
X149000D01*
X149500Y744450D01*
G01X151500D02*
Y745450D01*
G01X149417Y747258D02*
X149167Y747508D01*
X149042Y747800D01*
X149000Y748133D01*
X149083Y748550D01*
X149292Y748842D01*
X149542Y748925D01*
X149792Y748883D01*
X150000Y748717D01*
X150417Y747883D01*
X150708Y747508D01*
X151125Y747258D01*
X151500Y747175D01*
Y748925D01*
G01X150458Y750358D02*
X150167Y750650D01*
X150000Y750900D01*
X149917Y751233D01*
X150000Y751525D01*
X150167Y751733D01*
X150417Y751900D01*
X150708Y751942D01*
X150958Y751900D01*
X151208Y751733D01*
X151417Y751483D01*
X151500Y751192D01*
X151417Y750858D01*
X151167Y750567D01*
X150792Y750400D01*
X150375Y750358D01*
X149833Y750442D01*
X149542Y750567D01*
X149250Y750775D01*
X149042Y751067D01*
X149000Y751358D01*
X149083Y751650D01*
X149292Y751858D01*
G01X149417Y753458D02*
X149167Y753708D01*
X149042Y754000D01*
X149000Y754333D01*
X149083Y754750D01*
X149292Y755042D01*
X149542Y755125D01*
X149792Y755083D01*
X150000Y754917D01*
X150417Y754083D01*
X150708Y753708D01*
X151125Y753458D01*
X151500Y753375D01*
Y755125D01*
G01X143000Y717700D02*
Y723200D01*
G01X151000Y717700D02*
X143000D01*
G01X151000Y723200D02*
Y717700D01*
G01Y735300D02*
Y729800D01*
G01X143000Y735300D02*
X151000D01*
G01X143000Y729800D02*
Y735300D01*
G01X186100Y707750D02*
X188600D01*
G01X186100Y706792D02*
Y708708D01*
G01X188600Y710017D02*
X186100D01*
Y711017D01*
X186225Y711350D01*
X186517Y711600D01*
X186850Y711683D01*
X187183Y711600D01*
X187433Y711392D01*
X187558Y711017D01*
Y710017D01*
G01X186517Y713158D02*
X186267Y713408D01*
X186142Y713700D01*
X186100Y714033D01*
X186183Y714450D01*
X186392Y714742D01*
X186642Y714825D01*
X186892Y714783D01*
X187100Y714617D01*
X187517Y713783D01*
X187808Y713408D01*
X188225Y713158D01*
X188600Y713075D01*
Y714825D01*
G01Y717050D02*
X186100D01*
X186600Y716550D01*
G01X188600D02*
Y717550D01*
G01X179000Y711517D02*
X176500D01*
Y712558D01*
X176625Y712892D01*
X176792Y713100D01*
X177125Y713183D01*
X177458Y713100D01*
X177667Y712850D01*
X177792Y712558D01*
Y711517D01*
G01Y712558D02*
X179000Y713183D01*
G01X176917Y714658D02*
X176667Y714908D01*
X176542Y715200D01*
X176500Y715533D01*
X176583Y715950D01*
X176792Y716242D01*
X177042Y716325D01*
X177292Y716283D01*
X177500Y716117D01*
X177917Y715283D01*
X178208Y714908D01*
X178625Y714658D01*
X179000Y714575D01*
Y716325D01*
G01X177958Y717758D02*
X177667Y718050D01*
X177500Y718300D01*
X177417Y718633D01*
X177500Y718925D01*
X177667Y719133D01*
X177917Y719300D01*
X178208Y719342D01*
X178458Y719300D01*
X178708Y719133D01*
X178917Y718883D01*
X179000Y718592D01*
X178917Y718258D01*
X178667Y717967D01*
X178292Y717800D01*
X177875Y717758D01*
X177333Y717842D01*
X177042Y717967D01*
X176750Y718175D01*
X176542Y718467D01*
X176500Y718758D01*
X176583Y719050D01*
X176792Y719258D01*
G01X179000Y721650D02*
X176500D01*
X177000Y721150D01*
G01X179000D02*
Y722150D01*
G01X151500Y713700D02*
X147500D01*
Y706300D01*
G01X139500Y735517D02*
X137000D01*
Y736517D01*
X137125Y736850D01*
X137417Y737100D01*
X137750Y737183D01*
X138083Y737100D01*
X138333Y736892D01*
X138458Y736517D01*
Y735517D01*
G01X139500Y739450D02*
X139458Y739117D01*
X139292Y738825D01*
X139042Y738575D01*
X138750Y738408D01*
X138417Y738325D01*
X138083D01*
X137750Y738408D01*
X137458Y738575D01*
X137208Y738825D01*
X137042Y739117D01*
X137000Y739450D01*
X137042Y739783D01*
X137208Y740075D01*
X137458Y740325D01*
X137750Y740492D01*
X138083Y740575D01*
X138417D01*
X138750Y740492D01*
X139042Y740325D01*
X139292Y740075D01*
X139458Y739783D01*
X139500Y739450D01*
G01X138833Y739783D02*
X139500Y740283D01*
G01Y742550D02*
X137000D01*
X137500Y742050D01*
G01X139500D02*
Y743050D01*
G01X137000Y745650D02*
X137083Y745317D01*
X137292Y745067D01*
X137542Y744900D01*
X137875Y744775D01*
X138250Y744733D01*
X138625Y744775D01*
X138958Y744900D01*
X139208Y745067D01*
X139417Y745317D01*
X139500Y745650D01*
X139417Y745983D01*
X139208Y746233D01*
X138958Y746400D01*
X138625Y746525D01*
X138250Y746567D01*
X137875Y746525D01*
X137542Y746400D01*
X137292Y746233D01*
X137083Y745983D01*
X137000Y745650D01*
G01X141900Y719300D02*
Y733300D01*
G01X158720Y871585D02*
Y873835D01*
G01X164600Y871585D02*
X158720D01*
G01X164600Y873835D02*
Y871585D01*
G01X161565Y872935D02*
Y871585D01*
G01X162930Y877335D02*
X158720D01*
G01X163815Y877105D02*
X162930Y877335D01*
G01X164400Y876655D02*
X163815Y877105D01*
G01X164600Y876090D02*
X164400Y876655D01*
G01Y875525D02*
X164600Y876090D01*
G01X163815Y875075D02*
X164400Y875525D01*
G01X162930Y874850D02*
X163815Y875075D01*
G01X158720Y874850D02*
X162930D01*
G01X164505Y883300D02*
X164600Y882855D01*
G01X164110Y883700D02*
X164505Y883300D01*
G01X163520Y884035D02*
X164110Y883700D01*
G01X162835Y884265D02*
X163520Y884035D01*
G01X162050Y884375D02*
X162835Y884265D01*
G01X161270Y884375D02*
X162050D01*
G01X160485Y884265D02*
X161270Y884375D01*
G01X159800Y884035D02*
X160485Y884265D01*
G01X159210Y883700D02*
X159800Y884035D01*
G01X158815Y883300D02*
X159210Y883700D01*
G01X158720Y882855D02*
X158815Y883300D01*
G01Y882405D02*
X158720Y882855D01*
G01X159210Y882005D02*
X158815Y882405D01*
G01X159800Y881670D02*
X159210Y882005D01*
G01X160485Y881440D02*
X159800Y881670D01*
G01X161270Y881330D02*
X160485Y881440D01*
G01X162050Y881330D02*
X161270D01*
G01X162835Y881440D02*
X162050Y881330D01*
G01X163520Y881670D02*
X162835Y881440D01*
G01X164110Y882005D02*
X163520Y881670D01*
G01X164505Y882405D02*
X164110Y882005D01*
G01X164600Y882855D02*
X164505Y882405D01*
G01X164600Y885280D02*
X160680D01*
G01X161860Y887190D02*
X164600D01*
G01X161170Y887020D02*
X161860Y887190D01*
G01X160780Y886680D02*
X161170Y887020D01*
G01X160680Y886290D02*
X160780Y886680D01*
G01Y885835D02*
X160680Y886290D01*
G01X161170Y885500D02*
X160780Y885835D01*
G01X161660Y885280D02*
X161170Y885500D01*
G01X164600Y889615D02*
X158720D01*
G01X163915Y893445D02*
X160680Y894180D01*
G01X165480Y893105D02*
X163915Y893445D01*
G01X165975Y892885D02*
X165480Y893105D01*
G01X166365Y892600D02*
X165975Y892885D01*
G01X166560Y892150D02*
X166365Y892600D01*
G01Y891810D02*
X166560Y892150D01*
G01X160680Y892380D02*
X163915Y893445D01*
G01X151000Y930567D02*
X148500D01*
Y931608D01*
X148625Y931942D01*
X148792Y932150D01*
X149125Y932233D01*
X149458Y932150D01*
X149667Y931900D01*
X149792Y931608D01*
Y930567D01*
G01Y931608D02*
X151000Y932233D01*
G01Y934500D02*
X148500D01*
X149000Y934000D01*
G01X151000D02*
Y935000D01*
G01X150625Y936683D02*
X150833Y936933D01*
X150958Y937225D01*
X151000Y937600D01*
X150917Y937975D01*
X150750Y938267D01*
X150458Y938475D01*
X150125Y938517D01*
X149792Y938433D01*
X149583Y938225D01*
X149417Y937933D01*
X149375Y937642D01*
X149417Y937350D01*
X149583Y936975D01*
X148500Y937100D01*
Y938225D01*
G01X151000Y940617D02*
X150458Y940700D01*
X150000Y940825D01*
X149583Y940992D01*
X149125Y941200D01*
X148500Y941533D01*
Y939867D01*
G01X147000Y943800D02*
X151000D01*
Y951200D01*
G01X155000Y930567D02*
X152500D01*
Y931608D01*
X152625Y931942D01*
X152792Y932150D01*
X153125Y932233D01*
X153458Y932150D01*
X153667Y931900D01*
X153792Y931608D01*
Y930567D01*
G01Y931608D02*
X155000Y932233D01*
G01Y934500D02*
X152500D01*
X153000Y934000D01*
G01X155000D02*
Y935000D01*
G01X154625Y936683D02*
X154833Y936933D01*
X154958Y937225D01*
X155000Y937600D01*
X154917Y937975D01*
X154750Y938267D01*
X154458Y938475D01*
X154125Y938517D01*
X153792Y938433D01*
X153583Y938225D01*
X153417Y937933D01*
X153375Y937642D01*
X153417Y937350D01*
X153583Y936975D01*
X152500Y937100D01*
Y938225D01*
G01X153958Y939908D02*
X153667Y940200D01*
X153500Y940450D01*
X153417Y940783D01*
X153500Y941075D01*
X153667Y941283D01*
X153917Y941450D01*
X154208Y941492D01*
X154458Y941450D01*
X154708Y941283D01*
X154917Y941033D01*
X155000Y940742D01*
X154917Y940408D01*
X154667Y940117D01*
X154292Y939950D01*
X153875Y939908D01*
X153333Y939992D01*
X153042Y940117D01*
X152750Y940325D01*
X152542Y940617D01*
X152500Y940908D01*
X152583Y941200D01*
X152792Y941408D01*
G01X151000Y943800D02*
X155000D01*
Y951200D01*
G01X159000Y930567D02*
X156500D01*
Y931608D01*
X156625Y931942D01*
X156792Y932150D01*
X157125Y932233D01*
X157458Y932150D01*
X157667Y931900D01*
X157792Y931608D01*
Y930567D01*
G01Y931608D02*
X159000Y932233D01*
G01Y934500D02*
X156500D01*
X157000Y934000D01*
G01X159000D02*
Y935000D01*
G01X158625Y936683D02*
X158833Y936933D01*
X158958Y937225D01*
X159000Y937600D01*
X158917Y937975D01*
X158750Y938267D01*
X158458Y938475D01*
X158125Y938517D01*
X157792Y938433D01*
X157583Y938225D01*
X157417Y937933D01*
X157375Y937642D01*
X157417Y937350D01*
X157583Y936975D01*
X156500Y937100D01*
Y938225D01*
G01X158625Y939783D02*
X158833Y940033D01*
X158958Y940325D01*
X159000Y940700D01*
X158917Y941075D01*
X158750Y941367D01*
X158458Y941575D01*
X158125Y941617D01*
X157792Y941533D01*
X157583Y941325D01*
X157417Y941033D01*
X157375Y940742D01*
X157417Y940450D01*
X157583Y940075D01*
X156500Y940200D01*
Y941325D01*
G01X155000Y943800D02*
X159000D01*
Y951200D01*
G01X147000Y930567D02*
X144500D01*
Y931608D01*
X144625Y931942D01*
X144792Y932150D01*
X145125Y932233D01*
X145458Y932150D01*
X145667Y931900D01*
X145792Y931608D01*
Y930567D01*
G01Y931608D02*
X147000Y932233D01*
G01Y934500D02*
X144500D01*
X145000Y934000D01*
G01X147000D02*
Y935000D01*
G01Y938100D02*
X144500D01*
X146292Y936558D01*
Y938642D01*
G01X147000Y940700D02*
X146958Y940992D01*
X146833Y941325D01*
X146625Y941533D01*
X146333Y941617D01*
X146042Y941533D01*
X145792Y941283D01*
X145667Y940908D01*
Y940492D01*
X145583Y940242D01*
X145375Y940033D01*
X145083Y939950D01*
X144792Y940075D01*
X144583Y940367D01*
X144500Y940700D01*
X144583Y941033D01*
X144792Y941325D01*
X145083Y941450D01*
X145375Y941367D01*
X145583Y941158D01*
X145667Y940908D01*
Y940492D01*
X145792Y940117D01*
X146042Y939867D01*
X146333Y939783D01*
X146625Y939867D01*
X146833Y940075D01*
X146958Y940408D01*
X147000Y940700D01*
G01X143000Y943800D02*
X147000D01*
Y951200D01*
G01X141500Y931067D02*
X139000D01*
Y932108D01*
X139125Y932442D01*
X139292Y932650D01*
X139625Y932733D01*
X139958Y932650D01*
X140167Y932400D01*
X140292Y932108D01*
Y931067D01*
G01Y932108D02*
X141500Y932733D01*
G01X141125Y934083D02*
X141333Y934333D01*
X141458Y934625D01*
X141500Y935000D01*
X141417Y935375D01*
X141250Y935667D01*
X140958Y935875D01*
X140625Y935917D01*
X140292Y935833D01*
X140083Y935625D01*
X139917Y935333D01*
X139875Y935042D01*
X139917Y934750D01*
X140083Y934375D01*
X139000Y934500D01*
Y935625D01*
G01X140458Y937308D02*
X140167Y937600D01*
X140000Y937850D01*
X139917Y938183D01*
X140000Y938475D01*
X140167Y938683D01*
X140417Y938850D01*
X140708Y938892D01*
X140958Y938850D01*
X141208Y938683D01*
X141417Y938433D01*
X141500Y938142D01*
X141417Y937808D01*
X141167Y937517D01*
X140792Y937350D01*
X140375Y937308D01*
X139833Y937392D01*
X139542Y937517D01*
X139250Y937725D01*
X139042Y938017D01*
X139000Y938308D01*
X139083Y938600D01*
X139292Y938808D01*
G01X138500Y942400D02*
X142500D01*
Y949800D01*
G01X160000Y970533D02*
X161792D01*
X162167Y970700D01*
X162417Y971033D01*
X162500Y971450D01*
X162417Y971867D01*
X162167Y972200D01*
X161792Y972367D01*
X160000D01*
G01X161458Y973758D02*
X161167Y974050D01*
X161000Y974300D01*
X160917Y974633D01*
X161000Y974925D01*
X161167Y975133D01*
X161417Y975300D01*
X161708Y975342D01*
X161958Y975300D01*
X162208Y975133D01*
X162417Y974883D01*
X162500Y974592D01*
X162417Y974258D01*
X162167Y973967D01*
X161792Y973800D01*
X161375Y973758D01*
X160833Y973842D01*
X160542Y973967D01*
X160250Y974175D01*
X160042Y974467D01*
X160000Y974758D01*
X160083Y975050D01*
X160292Y975258D01*
G01X155600Y977600D02*
Y963600D01*
G01X163500Y980350D02*
X166000D01*
G01X163500Y979392D02*
Y981308D01*
G01X166000Y982617D02*
X163500D01*
Y983617D01*
X163625Y983950D01*
X163917Y984200D01*
X164250Y984283D01*
X164583Y984200D01*
X164833Y983992D01*
X164958Y983617D01*
Y982617D01*
G01X163917Y985758D02*
X163667Y986008D01*
X163542Y986300D01*
X163500Y986633D01*
X163583Y987050D01*
X163792Y987342D01*
X164042Y987425D01*
X164292Y987383D01*
X164500Y987217D01*
X164917Y986383D01*
X165208Y986008D01*
X165625Y985758D01*
X166000Y985675D01*
Y987425D01*
G01X164958Y988858D02*
X164667Y989150D01*
X164500Y989400D01*
X164417Y989733D01*
X164500Y990025D01*
X164667Y990233D01*
X164917Y990400D01*
X165208Y990442D01*
X165458Y990400D01*
X165708Y990233D01*
X165917Y989983D01*
X166000Y989692D01*
X165917Y989358D01*
X165667Y989067D01*
X165292Y988900D01*
X164875Y988858D01*
X164333Y988942D01*
X164042Y989067D01*
X163750Y989275D01*
X163542Y989567D01*
X163500Y989858D01*
X163583Y990150D01*
X163792Y990358D01*
G01X167500Y980350D02*
X170000D01*
G01X167500Y979392D02*
Y981308D01*
G01X170000Y982617D02*
X167500D01*
Y983617D01*
X167625Y983950D01*
X167917Y984200D01*
X168250Y984283D01*
X168583Y984200D01*
X168833Y983992D01*
X168958Y983617D01*
Y982617D01*
G01X170000Y986550D02*
X167500D01*
X168000Y986050D01*
G01X170000D02*
Y987050D01*
G01X169708Y988942D02*
X169917Y989233D01*
X170000Y989567D01*
X169917Y989900D01*
X169667Y990192D01*
X169292Y990400D01*
X168917Y990483D01*
X168458D01*
X168083Y990400D01*
X167750Y990192D01*
X167583Y989942D01*
X167500Y989650D01*
X167583Y989317D01*
X167750Y989067D01*
X168000Y988900D01*
X168333Y988817D01*
X168625Y988900D01*
X168917Y989108D01*
X169083Y989358D01*
X169125Y989650D01*
X169042Y989983D01*
X168833Y990233D01*
X168458Y990483D01*
G01X159500Y980350D02*
X162000D01*
G01X159500Y979392D02*
Y981308D01*
G01X162000Y982617D02*
X159500D01*
Y983617D01*
X159625Y983950D01*
X159917Y984200D01*
X160250Y984283D01*
X160583Y984200D01*
X160833Y983992D01*
X160958Y983617D01*
Y982617D01*
G01X162000Y986550D02*
X159500D01*
X160000Y986050D01*
G01X162000D02*
Y987050D01*
G01Y989650D02*
X161958Y989942D01*
X161833Y990275D01*
X161625Y990483D01*
X161333Y990567D01*
X161042Y990483D01*
X160792Y990233D01*
X160667Y989858D01*
Y989442D01*
X160583Y989192D01*
X160375Y988983D01*
X160083Y988900D01*
X159792Y989025D01*
X159583Y989317D01*
X159500Y989650D01*
X159583Y989983D01*
X159792Y990275D01*
X160083Y990400D01*
X160375Y990317D01*
X160583Y990108D01*
X160667Y989858D01*
Y989442D01*
X160792Y989067D01*
X161042Y988817D01*
X161333Y988733D01*
X161625Y988817D01*
X161833Y989025D01*
X161958Y989358D01*
X162000Y989650D01*
G01X148800Y1010017D02*
X146300D01*
Y1011058D01*
X146425Y1011392D01*
X146592Y1011600D01*
X146925Y1011683D01*
X147258Y1011600D01*
X147467Y1011350D01*
X147592Y1011058D01*
Y1010017D01*
G01Y1011058D02*
X148800Y1011683D01*
G01X148425Y1013033D02*
X148633Y1013283D01*
X148758Y1013575D01*
X148800Y1013950D01*
X148717Y1014325D01*
X148550Y1014617D01*
X148258Y1014825D01*
X147925Y1014867D01*
X147592Y1014783D01*
X147383Y1014575D01*
X147217Y1014283D01*
X147175Y1013992D01*
X147217Y1013700D01*
X147383Y1013325D01*
X146300Y1013450D01*
Y1014575D01*
G01X148508Y1016342D02*
X148717Y1016633D01*
X148800Y1016967D01*
X148717Y1017300D01*
X148467Y1017592D01*
X148092Y1017800D01*
X147717Y1017883D01*
X147258D01*
X146883Y1017800D01*
X146550Y1017592D01*
X146383Y1017342D01*
X146300Y1017050D01*
X146383Y1016717D01*
X146550Y1016467D01*
X146800Y1016300D01*
X147133Y1016217D01*
X147425Y1016300D01*
X147717Y1016508D01*
X147883Y1016758D01*
X147925Y1017050D01*
X147842Y1017383D01*
X147633Y1017633D01*
X147258Y1017883D01*
G01X149900Y1005100D02*
X145900D01*
Y997700D01*
G01X152800Y1010017D02*
X150300D01*
Y1011058D01*
X150425Y1011392D01*
X150592Y1011600D01*
X150925Y1011683D01*
X151258Y1011600D01*
X151467Y1011350D01*
X151592Y1011058D01*
Y1010017D01*
G01Y1011058D02*
X152800Y1011683D01*
G01X152425Y1013033D02*
X152633Y1013283D01*
X152758Y1013575D01*
X152800Y1013950D01*
X152717Y1014325D01*
X152550Y1014617D01*
X152258Y1014825D01*
X151925Y1014867D01*
X151592Y1014783D01*
X151383Y1014575D01*
X151217Y1014283D01*
X151175Y1013992D01*
X151217Y1013700D01*
X151383Y1013325D01*
X150300Y1013450D01*
Y1014575D01*
G01X152800Y1017050D02*
X152758Y1017342D01*
X152633Y1017675D01*
X152425Y1017883D01*
X152133Y1017967D01*
X151842Y1017883D01*
X151592Y1017633D01*
X151467Y1017258D01*
Y1016842D01*
X151383Y1016592D01*
X151175Y1016383D01*
X150883Y1016300D01*
X150592Y1016425D01*
X150383Y1016717D01*
X150300Y1017050D01*
X150383Y1017383D01*
X150592Y1017675D01*
X150883Y1017800D01*
X151175Y1017717D01*
X151383Y1017508D01*
X151467Y1017258D01*
Y1016842D01*
X151592Y1016467D01*
X151842Y1016217D01*
X152133Y1016133D01*
X152425Y1016217D01*
X152633Y1016425D01*
X152758Y1016758D01*
X152800Y1017050D01*
G01X154100Y1005200D02*
X150100D01*
Y997800D01*
G01X165000Y1002017D02*
X162500D01*
Y1003058D01*
X162625Y1003392D01*
X162792Y1003600D01*
X163125Y1003683D01*
X163458Y1003600D01*
X163667Y1003350D01*
X163792Y1003058D01*
Y1002017D01*
G01Y1003058D02*
X165000Y1003683D01*
G01Y1005950D02*
X162500D01*
X163000Y1005450D01*
G01X165000D02*
Y1006450D01*
G01Y1009550D02*
X162500D01*
X164292Y1008008D01*
Y1010092D01*
G01X164708Y1011442D02*
X164917Y1011733D01*
X165000Y1012067D01*
X164917Y1012400D01*
X164667Y1012692D01*
X164292Y1012900D01*
X163917Y1012983D01*
X163458D01*
X163083Y1012900D01*
X162750Y1012692D01*
X162583Y1012442D01*
X162500Y1012150D01*
X162583Y1011817D01*
X162750Y1011567D01*
X163000Y1011400D01*
X163333Y1011317D01*
X163625Y1011400D01*
X163917Y1011608D01*
X164083Y1011858D01*
X164125Y1012150D01*
X164042Y1012483D01*
X163833Y1012733D01*
X163458Y1012983D01*
G01X165500Y999700D02*
X161500D01*
Y992300D01*
G01X161000Y1002017D02*
X158500D01*
Y1003058D01*
X158625Y1003392D01*
X158792Y1003600D01*
X159125Y1003683D01*
X159458Y1003600D01*
X159667Y1003350D01*
X159792Y1003058D01*
Y1002017D01*
G01Y1003058D02*
X161000Y1003683D01*
G01Y1005950D02*
X158500D01*
X159000Y1005450D01*
G01X161000D02*
Y1006450D01*
G01X158917Y1008258D02*
X158667Y1008508D01*
X158542Y1008800D01*
X158500Y1009133D01*
X158583Y1009550D01*
X158792Y1009842D01*
X159042Y1009925D01*
X159292Y1009883D01*
X159500Y1009717D01*
X159917Y1008883D01*
X160208Y1008508D01*
X160625Y1008258D01*
X161000Y1008175D01*
Y1009925D01*
G01X160708Y1011442D02*
X160917Y1011733D01*
X161000Y1012067D01*
X160917Y1012400D01*
X160667Y1012692D01*
X160292Y1012900D01*
X159917Y1012983D01*
X159458D01*
X159083Y1012900D01*
X158750Y1012692D01*
X158583Y1012442D01*
X158500Y1012150D01*
X158583Y1011817D01*
X158750Y1011567D01*
X159000Y1011400D01*
X159333Y1011317D01*
X159625Y1011400D01*
X159917Y1011608D01*
X160083Y1011858D01*
X160125Y1012150D01*
X160042Y1012483D01*
X159833Y1012733D01*
X159458Y1012983D01*
G01X161500Y999700D02*
X157500D01*
Y992300D01*
G01X144800Y1010017D02*
X142300D01*
Y1011058D01*
X142425Y1011392D01*
X142592Y1011600D01*
X142925Y1011683D01*
X143258Y1011600D01*
X143467Y1011350D01*
X143592Y1011058D01*
Y1010017D01*
G01Y1011058D02*
X144800Y1011683D01*
G01Y1014450D02*
X142300D01*
X144092Y1012908D01*
Y1014992D01*
G01X144800Y1017050D02*
X144758Y1017342D01*
X144633Y1017675D01*
X144425Y1017883D01*
X144133Y1017967D01*
X143842Y1017883D01*
X143592Y1017633D01*
X143467Y1017258D01*
Y1016842D01*
X143383Y1016592D01*
X143175Y1016383D01*
X142883Y1016300D01*
X142592Y1016425D01*
X142383Y1016717D01*
X142300Y1017050D01*
X142383Y1017383D01*
X142592Y1017675D01*
X142883Y1017800D01*
X143175Y1017717D01*
X143383Y1017508D01*
X143467Y1017258D01*
Y1016842D01*
X143592Y1016467D01*
X143842Y1016217D01*
X144133Y1016133D01*
X144425Y1016217D01*
X144633Y1016425D01*
X144758Y1016758D01*
X144800Y1017050D01*
G01X145800Y1005200D02*
X141800D01*
Y997800D01*
G01X140500Y1007517D02*
X138000D01*
Y1008558D01*
X138125Y1008892D01*
X138292Y1009100D01*
X138625Y1009183D01*
X138958Y1009100D01*
X139167Y1008850D01*
X139292Y1008558D01*
Y1007517D01*
G01Y1008558D02*
X140500Y1009183D01*
G01Y1011450D02*
X138000D01*
X138500Y1010950D01*
G01X140500D02*
Y1011950D01*
G01X138000Y1014550D02*
X138083Y1014217D01*
X138292Y1013967D01*
X138542Y1013800D01*
X138875Y1013675D01*
X139250Y1013633D01*
X139625Y1013675D01*
X139958Y1013800D01*
X140208Y1013967D01*
X140417Y1014217D01*
X140500Y1014550D01*
X140417Y1014883D01*
X140208Y1015133D01*
X139958Y1015300D01*
X139625Y1015425D01*
X139250Y1015467D01*
X138875Y1015425D01*
X138542Y1015300D01*
X138292Y1015133D01*
X138083Y1014883D01*
X138000Y1014550D01*
G01X140500Y1017567D02*
X139958Y1017650D01*
X139500Y1017775D01*
X139083Y1017942D01*
X138625Y1018150D01*
X138000Y1018483D01*
Y1016817D01*
G01X137100Y997700D02*
X141100D01*
Y1005100D01*
G01X138208Y1111317D02*
X138083Y1111067D01*
X138000Y1110775D01*
Y1110442D01*
X138125Y1110067D01*
X138333Y1109775D01*
X138583Y1109567D01*
X139000Y1109400D01*
X139375Y1109358D01*
X139750Y1109442D01*
X140000Y1109567D01*
X140250Y1109817D01*
X140417Y1110108D01*
X140500Y1110400D01*
Y1110692D01*
X140417Y1110983D01*
X140292Y1111233D01*
X140125Y1111442D01*
G01X140500Y1114000D02*
X138000D01*
X139792Y1112458D01*
Y1114542D01*
G01X140500Y1116517D02*
X139958Y1116600D01*
X139500Y1116725D01*
X139083Y1116892D01*
X138625Y1117100D01*
X138000Y1117433D01*
Y1115767D01*
G01X141350Y1162500D02*
Y1160000D01*
G01X140392Y1162500D02*
X142308D01*
G01X145367Y1162292D02*
X145117Y1162417D01*
X144825Y1162500D01*
X144492D01*
X144117Y1162375D01*
X143825Y1162167D01*
X143617Y1161917D01*
X143450Y1161500D01*
X143408Y1161125D01*
X143492Y1160750D01*
X143617Y1160500D01*
X143867Y1160250D01*
X144158Y1160083D01*
X144450Y1160000D01*
X144742D01*
X145033Y1160083D01*
X145283Y1160208D01*
X145492Y1160375D01*
G01X147550Y1160000D02*
Y1162500D01*
X147050Y1162000D01*
G01Y1160000D02*
X148050D01*
G01X150567D02*
X150650Y1160542D01*
X150775Y1161000D01*
X150942Y1161417D01*
X151150Y1161875D01*
X151483Y1162500D01*
X149817D01*
G01X154798Y1119703D02*
Y1130903D01*
G01X136798Y1119703D02*
X154798D01*
G01X136798Y1130903D02*
Y1119703D01*
G01X154798Y1158103D02*
Y1146903D01*
G01X136798Y1158103D02*
X154798D01*
G01X136798Y1146903D02*
Y1158103D01*
G01X177075Y1139000D02*
Y1141500D01*
G01X178825D02*
Y1139000D01*
G01Y1140250D02*
X177075D01*
G01X180258Y1140042D02*
X180550Y1140333D01*
X180800Y1140500D01*
X181133Y1140583D01*
X181425Y1140500D01*
X181633Y1140333D01*
X181800Y1140083D01*
X181842Y1139792D01*
X181800Y1139542D01*
X181633Y1139292D01*
X181383Y1139083D01*
X181092Y1139000D01*
X180758Y1139083D01*
X180467Y1139333D01*
X180300Y1139708D01*
X180258Y1140125D01*
X180342Y1140667D01*
X180467Y1140958D01*
X180675Y1141250D01*
X180967Y1141458D01*
X181258Y1141500D01*
X181550Y1141417D01*
X181758Y1141208D01*
G01X165500Y1354067D02*
X165750Y1354275D01*
X165917Y1354525D01*
X166000Y1354817D01*
X165917Y1355150D01*
X165750Y1355400D01*
X165500Y1355650D01*
X165167Y1355733D01*
X163500D01*
G01X166000Y1357167D02*
X163500D01*
Y1358167D01*
X163625Y1358500D01*
X163917Y1358750D01*
X164250Y1358833D01*
X164583Y1358750D01*
X164833Y1358542D01*
X164958Y1358167D01*
Y1357167D01*
G01X166000Y1361100D02*
X163500D01*
X164000Y1360600D01*
G01X166000D02*
Y1361600D01*
G01X170900Y1365000D02*
Y1396000D01*
X159100D01*
Y1365000D01*
X170900D01*
G01X138996Y1396300D02*
Y1388300D01*
G01X142767Y1375292D02*
X142517Y1375417D01*
X142225Y1375500D01*
X141892D01*
X141517Y1375375D01*
X141225Y1375167D01*
X141017Y1374917D01*
X140850Y1374500D01*
X140808Y1374125D01*
X140892Y1373750D01*
X141017Y1373500D01*
X141267Y1373250D01*
X141558Y1373083D01*
X141850Y1373000D01*
X142142D01*
X142433Y1373083D01*
X142683Y1373208D01*
X142892Y1373375D01*
G01X144158Y1375083D02*
X144408Y1375333D01*
X144700Y1375458D01*
X145033Y1375500D01*
X145450Y1375417D01*
X145742Y1375208D01*
X145825Y1374958D01*
X145783Y1374708D01*
X145617Y1374500D01*
X144783Y1374083D01*
X144408Y1373792D01*
X144158Y1373375D01*
X144075Y1373000D01*
X145825D01*
G01X147258Y1374042D02*
X147550Y1374333D01*
X147800Y1374500D01*
X148133Y1374583D01*
X148425Y1374500D01*
X148633Y1374333D01*
X148800Y1374083D01*
X148842Y1373792D01*
X148800Y1373542D01*
X148633Y1373292D01*
X148383Y1373083D01*
X148092Y1373000D01*
X147758Y1373083D01*
X147467Y1373333D01*
X147300Y1373708D01*
X147258Y1374125D01*
X147342Y1374667D01*
X147467Y1374958D01*
X147675Y1375250D01*
X147967Y1375458D01*
X148258Y1375500D01*
X148550Y1375417D01*
X148758Y1375208D01*
G01X151150Y1373000D02*
Y1375500D01*
X150650Y1375000D01*
G01Y1373000D02*
X151650D01*
G01X139700Y1391500D02*
X145200D01*
G01X139700Y1383500D02*
Y1391500D01*
G01X145200Y1383500D02*
X139700D01*
G01X157300D02*
X151800D01*
G01X157300Y1391500D02*
Y1383500D01*
G01X151800Y1391500D02*
X157300D01*
G01X179000Y1422017D02*
X176500D01*
Y1423017D01*
X176625Y1423350D01*
X176917Y1423600D01*
X177250Y1423683D01*
X177583Y1423600D01*
X177833Y1423392D01*
X177958Y1423017D01*
Y1422017D01*
G01X179000Y1425117D02*
X176500D01*
Y1426158D01*
X176625Y1426492D01*
X176792Y1426700D01*
X177125Y1426783D01*
X177458Y1426700D01*
X177667Y1426450D01*
X177792Y1426158D01*
Y1425117D01*
G01Y1426158D02*
X179000Y1426783D01*
G01Y1429550D02*
X176500D01*
X178292Y1428008D01*
Y1430092D01*
G01X176917Y1431358D02*
X176667Y1431608D01*
X176542Y1431900D01*
X176500Y1432233D01*
X176583Y1432650D01*
X176792Y1432942D01*
X177042Y1433025D01*
X177292Y1432983D01*
X177500Y1432817D01*
X177917Y1431983D01*
X178208Y1431608D01*
X178625Y1431358D01*
X179000Y1431275D01*
Y1433025D01*
G01X182500Y1422017D02*
X180000D01*
Y1423017D01*
X180125Y1423350D01*
X180417Y1423600D01*
X180750Y1423683D01*
X181083Y1423600D01*
X181333Y1423392D01*
X181458Y1423017D01*
Y1422017D01*
G01X182500Y1425117D02*
X180000D01*
Y1426158D01*
X180125Y1426492D01*
X180292Y1426700D01*
X180625Y1426783D01*
X180958Y1426700D01*
X181167Y1426450D01*
X181292Y1426158D01*
Y1425117D01*
G01Y1426158D02*
X182500Y1426783D01*
G01Y1429550D02*
X180000D01*
X181792Y1428008D01*
Y1430092D01*
G01X182500Y1432150D02*
X180000D01*
X180500Y1431650D01*
G01X182500D02*
Y1432650D01*
G01X175500Y1422017D02*
X173000D01*
Y1423017D01*
X173125Y1423350D01*
X173417Y1423600D01*
X173750Y1423683D01*
X174083Y1423600D01*
X174333Y1423392D01*
X174458Y1423017D01*
Y1422017D01*
G01X175500Y1425117D02*
X173000D01*
Y1426158D01*
X173125Y1426492D01*
X173292Y1426700D01*
X173625Y1426783D01*
X173958Y1426700D01*
X174167Y1426450D01*
X174292Y1426158D01*
Y1425117D01*
G01Y1426158D02*
X175500Y1426783D01*
G01Y1429550D02*
X173000D01*
X174792Y1428008D01*
Y1430092D01*
G01X173000Y1432150D02*
X173083Y1431817D01*
X173292Y1431567D01*
X173542Y1431400D01*
X173875Y1431275D01*
X174250Y1431233D01*
X174625Y1431275D01*
X174958Y1431400D01*
X175208Y1431567D01*
X175417Y1431817D01*
X175500Y1432150D01*
X175417Y1432483D01*
X175208Y1432733D01*
X174958Y1432900D01*
X174625Y1433025D01*
X174250Y1433067D01*
X173875Y1433025D01*
X173542Y1432900D01*
X173292Y1432733D01*
X173083Y1432483D01*
X173000Y1432150D01*
G01X162017Y1418000D02*
Y1420500D01*
X163017D01*
X163350Y1420375D01*
X163600Y1420083D01*
X163683Y1419750D01*
X163600Y1419417D01*
X163392Y1419167D01*
X163017Y1419042D01*
X162017D01*
G01X165117Y1418000D02*
Y1420500D01*
X166158D01*
X166492Y1420375D01*
X166700Y1420208D01*
X166783Y1419875D01*
X166700Y1419542D01*
X166450Y1419333D01*
X166158Y1419208D01*
X165117D01*
G01X166158D02*
X166783Y1418000D01*
G01X169550D02*
Y1420500D01*
X168008Y1418708D01*
X170092D01*
G01X171358Y1419042D02*
X171650Y1419333D01*
X171900Y1419500D01*
X172233Y1419583D01*
X172525Y1419500D01*
X172733Y1419333D01*
X172900Y1419083D01*
X172942Y1418792D01*
X172900Y1418542D01*
X172733Y1418292D01*
X172483Y1418083D01*
X172192Y1418000D01*
X171858Y1418083D01*
X171567Y1418333D01*
X171400Y1418708D01*
X171358Y1419125D01*
X171442Y1419667D01*
X171567Y1419958D01*
X171775Y1420250D01*
X172067Y1420458D01*
X172358Y1420500D01*
X172650Y1420417D01*
X172858Y1420208D01*
G01X150100Y1425400D02*
Y1421400D01*
X157500D01*
G01X186000Y1422017D02*
X183500D01*
Y1423017D01*
X183625Y1423350D01*
X183917Y1423600D01*
X184250Y1423683D01*
X184583Y1423600D01*
X184833Y1423392D01*
X184958Y1423017D01*
Y1422017D01*
G01X186000Y1425117D02*
X183500D01*
Y1426158D01*
X183625Y1426492D01*
X183792Y1426700D01*
X184125Y1426783D01*
X184458Y1426700D01*
X184667Y1426450D01*
X184792Y1426158D01*
Y1425117D01*
G01Y1426158D02*
X186000Y1426783D01*
G01Y1429550D02*
X183500D01*
X185292Y1428008D01*
Y1430092D01*
G01X185708Y1431442D02*
X185917Y1431733D01*
X186000Y1432067D01*
X185917Y1432400D01*
X185667Y1432692D01*
X185292Y1432900D01*
X184917Y1432983D01*
X184458D01*
X184083Y1432900D01*
X183750Y1432692D01*
X183583Y1432442D01*
X183500Y1432150D01*
X183583Y1431817D01*
X183750Y1431567D01*
X184000Y1431400D01*
X184333Y1431317D01*
X184625Y1431400D01*
X184917Y1431608D01*
X185083Y1431858D01*
X185125Y1432150D01*
X185042Y1432483D01*
X184833Y1432733D01*
X184458Y1432983D01*
G01X162500Y1398017D02*
X160000D01*
Y1399058D01*
X160125Y1399392D01*
X160292Y1399600D01*
X160625Y1399683D01*
X160958Y1399600D01*
X161167Y1399350D01*
X161292Y1399058D01*
Y1398017D01*
G01Y1399058D02*
X162500Y1399683D01*
G01X162000Y1401033D02*
X162292Y1401283D01*
X162458Y1401617D01*
X162500Y1401992D01*
X162458Y1402325D01*
X162250Y1402658D01*
X162000Y1402867D01*
X161750Y1402908D01*
X161458Y1402825D01*
X161250Y1402533D01*
X161167Y1402242D01*
Y1401867D01*
G01Y1402242D02*
X161042Y1402492D01*
X160833Y1402700D01*
X160583Y1402783D01*
X160333Y1402700D01*
X160125Y1402492D01*
X160000Y1402117D01*
X160042Y1401742D01*
X160208Y1401367D01*
G01X161458Y1404258D02*
X161167Y1404550D01*
X161000Y1404800D01*
X160917Y1405133D01*
X161000Y1405425D01*
X161167Y1405633D01*
X161417Y1405800D01*
X161708Y1405842D01*
X161958Y1405800D01*
X162208Y1405633D01*
X162417Y1405383D01*
X162500Y1405092D01*
X162417Y1404758D01*
X162167Y1404467D01*
X161792Y1404300D01*
X161375Y1404258D01*
X160833Y1404342D01*
X160542Y1404467D01*
X160250Y1404675D01*
X160042Y1404967D01*
X160000Y1405258D01*
X160083Y1405550D01*
X160292Y1405758D01*
G01X162500Y1408650D02*
X160000D01*
X161792Y1407108D01*
Y1409192D01*
G01X166500Y1398017D02*
X164000D01*
Y1399058D01*
X164125Y1399392D01*
X164292Y1399600D01*
X164625Y1399683D01*
X164958Y1399600D01*
X165167Y1399350D01*
X165292Y1399058D01*
Y1398017D01*
G01Y1399058D02*
X166500Y1399683D01*
G01X166000Y1401033D02*
X166292Y1401283D01*
X166458Y1401617D01*
X166500Y1401992D01*
X166458Y1402325D01*
X166250Y1402658D01*
X166000Y1402867D01*
X165750Y1402908D01*
X165458Y1402825D01*
X165250Y1402533D01*
X165167Y1402242D01*
Y1401867D01*
G01Y1402242D02*
X165042Y1402492D01*
X164833Y1402700D01*
X164583Y1402783D01*
X164333Y1402700D01*
X164125Y1402492D01*
X164000Y1402117D01*
X164042Y1401742D01*
X164208Y1401367D01*
G01X165458Y1404258D02*
X165167Y1404550D01*
X165000Y1404800D01*
X164917Y1405133D01*
X165000Y1405425D01*
X165167Y1405633D01*
X165417Y1405800D01*
X165708Y1405842D01*
X165958Y1405800D01*
X166208Y1405633D01*
X166417Y1405383D01*
X166500Y1405092D01*
X166417Y1404758D01*
X166167Y1404467D01*
X165792Y1404300D01*
X165375Y1404258D01*
X164833Y1404342D01*
X164542Y1404467D01*
X164250Y1404675D01*
X164042Y1404967D01*
X164000Y1405258D01*
X164083Y1405550D01*
X164292Y1405758D01*
G01X166125Y1407233D02*
X166333Y1407483D01*
X166458Y1407775D01*
X166500Y1408150D01*
X166417Y1408525D01*
X166250Y1408817D01*
X165958Y1409025D01*
X165625Y1409067D01*
X165292Y1408983D01*
X165083Y1408775D01*
X164917Y1408483D01*
X164875Y1408192D01*
X164917Y1407900D01*
X165083Y1407525D01*
X164000Y1407650D01*
Y1408775D01*
G01X144517Y1379000D02*
Y1381500D01*
X145558D01*
X145892Y1381375D01*
X146100Y1381208D01*
X146183Y1380875D01*
X146100Y1380542D01*
X145850Y1380333D01*
X145558Y1380208D01*
X144517D01*
G01X145558D02*
X146183Y1379000D01*
G01X147533Y1379500D02*
X147783Y1379208D01*
X148117Y1379042D01*
X148492Y1379000D01*
X148825Y1379042D01*
X149158Y1379250D01*
X149367Y1379500D01*
X149408Y1379750D01*
X149325Y1380042D01*
X149033Y1380250D01*
X148742Y1380333D01*
X148367D01*
G01X148742D02*
X148992Y1380458D01*
X149200Y1380667D01*
X149283Y1380917D01*
X149200Y1381167D01*
X148992Y1381375D01*
X148617Y1381500D01*
X148242Y1381458D01*
X147867Y1381292D01*
G01X150758Y1380042D02*
X151050Y1380333D01*
X151300Y1380500D01*
X151633Y1380583D01*
X151925Y1380500D01*
X152133Y1380333D01*
X152300Y1380083D01*
X152342Y1379792D01*
X152300Y1379542D01*
X152133Y1379292D01*
X151883Y1379083D01*
X151592Y1379000D01*
X151258Y1379083D01*
X150967Y1379333D01*
X150800Y1379708D01*
X150758Y1380125D01*
X150842Y1380667D01*
X150967Y1380958D01*
X151175Y1381250D01*
X151467Y1381458D01*
X151758Y1381500D01*
X152050Y1381417D01*
X152258Y1381208D01*
G01X153733Y1379500D02*
X153983Y1379208D01*
X154317Y1379042D01*
X154692Y1379000D01*
X155025Y1379042D01*
X155358Y1379250D01*
X155567Y1379500D01*
X155608Y1379750D01*
X155525Y1380042D01*
X155233Y1380250D01*
X154942Y1380333D01*
X154567D01*
G01X154942D02*
X155192Y1380458D01*
X155400Y1380667D01*
X155483Y1380917D01*
X155400Y1381167D01*
X155192Y1381375D01*
X154817Y1381500D01*
X154442Y1381458D01*
X154067Y1381292D01*
G01X153404Y1392000D02*
Y1396000D01*
X146004D01*
G01X162017Y1414500D02*
Y1417000D01*
X163017D01*
X163350Y1416875D01*
X163600Y1416583D01*
X163683Y1416250D01*
X163600Y1415917D01*
X163392Y1415667D01*
X163017Y1415542D01*
X162017D01*
G01X165117Y1414500D02*
Y1417000D01*
X166158D01*
X166492Y1416875D01*
X166700Y1416708D01*
X166783Y1416375D01*
X166700Y1416042D01*
X166450Y1415833D01*
X166158Y1415708D01*
X165117D01*
G01X166158D02*
X166783Y1414500D01*
G01X168133Y1414875D02*
X168383Y1414667D01*
X168675Y1414542D01*
X169050Y1414500D01*
X169425Y1414583D01*
X169717Y1414750D01*
X169925Y1415042D01*
X169967Y1415375D01*
X169883Y1415708D01*
X169675Y1415917D01*
X169383Y1416083D01*
X169092Y1416125D01*
X168800Y1416083D01*
X168425Y1415917D01*
X168550Y1417000D01*
X169675D01*
G01X171442Y1414792D02*
X171733Y1414583D01*
X172067Y1414500D01*
X172400Y1414583D01*
X172692Y1414833D01*
X172900Y1415208D01*
X172983Y1415583D01*
Y1416042D01*
X172900Y1416417D01*
X172692Y1416750D01*
X172442Y1416917D01*
X172150Y1417000D01*
X171817Y1416917D01*
X171567Y1416750D01*
X171400Y1416500D01*
X171317Y1416167D01*
X171400Y1415875D01*
X171608Y1415583D01*
X171858Y1415417D01*
X172150Y1415375D01*
X172483Y1415458D01*
X172733Y1415667D01*
X172983Y1416042D01*
G01X150096Y1421200D02*
Y1417200D01*
X157496D01*
G01X162017Y1411000D02*
Y1413500D01*
X163017D01*
X163350Y1413375D01*
X163600Y1413083D01*
X163683Y1412750D01*
X163600Y1412417D01*
X163392Y1412167D01*
X163017Y1412042D01*
X162017D01*
G01X165117Y1411000D02*
Y1413500D01*
X166158D01*
X166492Y1413375D01*
X166700Y1413208D01*
X166783Y1412875D01*
X166700Y1412542D01*
X166450Y1412333D01*
X166158Y1412208D01*
X165117D01*
G01X166158D02*
X166783Y1411000D01*
G01X168133Y1411375D02*
X168383Y1411167D01*
X168675Y1411042D01*
X169050Y1411000D01*
X169425Y1411083D01*
X169717Y1411250D01*
X169925Y1411542D01*
X169967Y1411875D01*
X169883Y1412208D01*
X169675Y1412417D01*
X169383Y1412583D01*
X169092Y1412625D01*
X168800Y1412583D01*
X168425Y1412417D01*
X168550Y1413500D01*
X169675D01*
G01X172150Y1411000D02*
X172442Y1411042D01*
X172775Y1411167D01*
X172983Y1411375D01*
X173067Y1411667D01*
X172983Y1411958D01*
X172733Y1412208D01*
X172358Y1412333D01*
X171942D01*
X171692Y1412417D01*
X171483Y1412625D01*
X171400Y1412917D01*
X171525Y1413208D01*
X171817Y1413417D01*
X172150Y1413500D01*
X172483Y1413417D01*
X172775Y1413208D01*
X172900Y1412917D01*
X172817Y1412625D01*
X172608Y1412417D01*
X172358Y1412333D01*
X171942D01*
X171567Y1412208D01*
X171317Y1411958D01*
X171233Y1411667D01*
X171317Y1411375D01*
X171525Y1411167D01*
X171858Y1411042D01*
X172150Y1411000D01*
G01X150096Y1417000D02*
Y1413000D01*
X157496D01*
G01X171500Y1422067D02*
X169000D01*
Y1423067D01*
X169125Y1423400D01*
X169417Y1423650D01*
X169750Y1423733D01*
X170083Y1423650D01*
X170333Y1423442D01*
X170458Y1423067D01*
Y1422067D01*
G01X171500Y1426000D02*
X171458Y1425667D01*
X171292Y1425375D01*
X171042Y1425125D01*
X170750Y1424958D01*
X170417Y1424875D01*
X170083D01*
X169750Y1424958D01*
X169458Y1425125D01*
X169208Y1425375D01*
X169042Y1425667D01*
X169000Y1426000D01*
X169042Y1426333D01*
X169208Y1426625D01*
X169458Y1426875D01*
X169750Y1427042D01*
X170083Y1427125D01*
X170417D01*
X170750Y1427042D01*
X171042Y1426875D01*
X171292Y1426625D01*
X171458Y1426333D01*
X171500Y1426000D01*
G01X170833Y1426333D02*
X171500Y1426833D01*
G01X171125Y1428183D02*
X171333Y1428433D01*
X171458Y1428725D01*
X171500Y1429100D01*
X171417Y1429475D01*
X171250Y1429767D01*
X170958Y1429975D01*
X170625Y1430017D01*
X170292Y1429933D01*
X170083Y1429725D01*
X169917Y1429433D01*
X169875Y1429142D01*
X169917Y1428850D01*
X170083Y1428475D01*
X169000Y1428600D01*
Y1429725D01*
G01X149069Y1419019D02*
Y1433019D01*
G01X174500Y1398017D02*
X172000D01*
Y1399017D01*
X172125Y1399350D01*
X172417Y1399600D01*
X172750Y1399683D01*
X173083Y1399600D01*
X173333Y1399392D01*
X173458Y1399017D01*
Y1398017D01*
G01X174500Y1401950D02*
X174458Y1401617D01*
X174292Y1401325D01*
X174042Y1401075D01*
X173750Y1400908D01*
X173417Y1400825D01*
X173083D01*
X172750Y1400908D01*
X172458Y1401075D01*
X172208Y1401325D01*
X172042Y1401617D01*
X172000Y1401950D01*
X172042Y1402283D01*
X172208Y1402575D01*
X172458Y1402825D01*
X172750Y1402992D01*
X173083Y1403075D01*
X173417D01*
X173750Y1402992D01*
X174042Y1402825D01*
X174292Y1402575D01*
X174458Y1402283D01*
X174500Y1401950D01*
G01X173833Y1402283D02*
X174500Y1402783D01*
G01Y1405050D02*
X172000D01*
X172500Y1404550D01*
G01X174500D02*
Y1405550D01*
G01Y1408650D02*
X172000D01*
X173792Y1407108D01*
Y1409192D01*
G01X145400Y1412204D02*
Y1398204D01*
G01X158400Y1412204D02*
X145400D01*
G01X158400Y1398204D02*
Y1412204D01*
G01X145400Y1398204D02*
X158400D01*
G01X170500Y1397983D02*
X168000D01*
Y1398817D01*
X168125Y1399150D01*
X168292Y1399400D01*
X168542Y1399608D01*
X168833Y1399775D01*
X169250Y1399817D01*
X169667Y1399775D01*
X169958Y1399608D01*
X170208Y1399400D01*
X170375Y1399150D01*
X170500Y1398817D01*
Y1397983D01*
G01Y1402000D02*
X168000D01*
X168500Y1401500D01*
G01X170500D02*
Y1402500D01*
G01X170208Y1404392D02*
X170417Y1404683D01*
X170500Y1405017D01*
X170417Y1405350D01*
X170167Y1405642D01*
X169792Y1405850D01*
X169417Y1405933D01*
X168958D01*
X168583Y1405850D01*
X168250Y1405642D01*
X168083Y1405392D01*
X168000Y1405100D01*
X168083Y1404767D01*
X168250Y1404517D01*
X168500Y1404350D01*
X168833Y1404267D01*
X169125Y1404350D01*
X169417Y1404558D01*
X169583Y1404808D01*
X169625Y1405100D01*
X169542Y1405433D01*
X169333Y1405683D01*
X168958Y1405933D01*
G01X137900Y1413296D02*
Y1398496D01*
G01X144300Y1413296D02*
X137900D01*
G01X144300Y1398496D02*
Y1413296D01*
G01X137900Y1398496D02*
X144300D01*
G01X184500Y1436567D02*
X182000D01*
Y1437567D01*
X182125Y1437900D01*
X182417Y1438150D01*
X182750Y1438233D01*
X183083Y1438150D01*
X183333Y1437942D01*
X183458Y1437567D01*
Y1436567D01*
G01X184500Y1440500D02*
X184458Y1440167D01*
X184292Y1439875D01*
X184042Y1439625D01*
X183750Y1439458D01*
X183417Y1439375D01*
X183083D01*
X182750Y1439458D01*
X182458Y1439625D01*
X182208Y1439875D01*
X182042Y1440167D01*
X182000Y1440500D01*
X182042Y1440833D01*
X182208Y1441125D01*
X182458Y1441375D01*
X182750Y1441542D01*
X183083Y1441625D01*
X183417D01*
X183750Y1441542D01*
X184042Y1441375D01*
X184292Y1441125D01*
X184458Y1440833D01*
X184500Y1440500D01*
G01X183833Y1440833D02*
X184500Y1441333D01*
G01Y1444100D02*
X182000D01*
X183792Y1442558D01*
Y1444642D01*
G01X154000Y1434000D02*
Y1448000D01*
G01X141000Y1434000D02*
X154000D01*
G01X141000Y1448000D02*
Y1434000D01*
G01X154000Y1448000D02*
X141000D01*
G01X145800Y1484800D02*
Y1468700D01*
G01X138800D02*
Y1484800D01*
G01X145800Y1468700D02*
X138800D01*
G01X186267Y1465792D02*
X186017Y1465917D01*
X185725Y1466000D01*
X185392D01*
X185017Y1465875D01*
X184725Y1465667D01*
X184517Y1465417D01*
X184350Y1465000D01*
X184308Y1464625D01*
X184392Y1464250D01*
X184517Y1464000D01*
X184767Y1463750D01*
X185058Y1463583D01*
X185350Y1463500D01*
X185642D01*
X185933Y1463583D01*
X186183Y1463708D01*
X186392Y1463875D01*
G01X187658Y1465583D02*
X187908Y1465833D01*
X188200Y1465958D01*
X188533Y1466000D01*
X188950Y1465917D01*
X189242Y1465708D01*
X189325Y1465458D01*
X189283Y1465208D01*
X189117Y1465000D01*
X188283Y1464583D01*
X187908Y1464292D01*
X187658Y1463875D01*
X187575Y1463500D01*
X189325D01*
G01X190633Y1463875D02*
X190883Y1463667D01*
X191175Y1463542D01*
X191550Y1463500D01*
X191925Y1463583D01*
X192217Y1463750D01*
X192425Y1464042D01*
X192467Y1464375D01*
X192383Y1464708D01*
X192175Y1464917D01*
X191883Y1465083D01*
X191592Y1465125D01*
X191300Y1465083D01*
X190925Y1464917D01*
X191050Y1466000D01*
X192175D01*
G01X193733Y1463875D02*
X193983Y1463667D01*
X194275Y1463542D01*
X194650Y1463500D01*
X195025Y1463583D01*
X195317Y1463750D01*
X195525Y1464042D01*
X195567Y1464375D01*
X195483Y1464708D01*
X195275Y1464917D01*
X194983Y1465083D01*
X194692Y1465125D01*
X194400Y1465083D01*
X194025Y1464917D01*
X194150Y1466000D01*
X195275D01*
G01X168500Y1469417D02*
X166000D01*
Y1470417D01*
X166125Y1470750D01*
X166417Y1471000D01*
X166750Y1471083D01*
X167083Y1471000D01*
X167333Y1470792D01*
X167458Y1470417D01*
Y1469417D01*
G01X168500Y1472517D02*
X166000D01*
Y1473558D01*
X166125Y1473892D01*
X166292Y1474100D01*
X166625Y1474183D01*
X166958Y1474100D01*
X167167Y1473850D01*
X167292Y1473558D01*
Y1472517D01*
G01Y1473558D02*
X168500Y1474183D01*
G01Y1476950D02*
X166000D01*
X167792Y1475408D01*
Y1477492D01*
G01X168000Y1478633D02*
X168292Y1478883D01*
X168458Y1479217D01*
X168500Y1479592D01*
X168458Y1479925D01*
X168250Y1480258D01*
X168000Y1480467D01*
X167750Y1480508D01*
X167458Y1480425D01*
X167250Y1480133D01*
X167167Y1479842D01*
Y1479467D01*
G01Y1479842D02*
X167042Y1480092D01*
X166833Y1480300D01*
X166583Y1480383D01*
X166333Y1480300D01*
X166125Y1480092D01*
X166000Y1479717D01*
X166042Y1479342D01*
X166208Y1478967D01*
G01X170500Y1468200D02*
Y1463000D01*
G01X163500Y1468200D02*
Y1460400D01*
G01X170500Y1468200D02*
X163500D01*
G01X170500Y1454800D02*
Y1463500D01*
G01X163500Y1454800D02*
X170500D01*
G01X163500Y1461200D02*
Y1454800D01*
G01X154631Y1425681D02*
X158631D01*
Y1433081D01*
G01X158831Y1424881D02*
X162831D01*
Y1432281D01*
G01X150331Y1425681D02*
X154331D01*
Y1433081D01*
G01X180500Y1436517D02*
X178000D01*
Y1437517D01*
X178125Y1437850D01*
X178417Y1438100D01*
X178750Y1438183D01*
X179083Y1438100D01*
X179333Y1437892D01*
X179458Y1437517D01*
Y1436517D01*
G01X180500Y1439617D02*
X178000D01*
Y1440658D01*
X178125Y1440992D01*
X178292Y1441200D01*
X178625Y1441283D01*
X178958Y1441200D01*
X179167Y1440950D01*
X179292Y1440658D01*
Y1439617D01*
G01Y1440658D02*
X180500Y1441283D01*
G01X180000Y1442633D02*
X180292Y1442883D01*
X180458Y1443217D01*
X180500Y1443592D01*
X180458Y1443925D01*
X180250Y1444258D01*
X180000Y1444467D01*
X179750Y1444508D01*
X179458Y1444425D01*
X179250Y1444133D01*
X179167Y1443842D01*
Y1443467D01*
G01Y1443842D02*
X179042Y1444092D01*
X178833Y1444300D01*
X178583Y1444383D01*
X178333Y1444300D01*
X178125Y1444092D01*
X178000Y1443717D01*
X178042Y1443342D01*
X178208Y1442967D01*
G01X180500Y1446650D02*
X180458Y1446942D01*
X180333Y1447275D01*
X180125Y1447483D01*
X179833Y1447567D01*
X179542Y1447483D01*
X179292Y1447233D01*
X179167Y1446858D01*
Y1446442D01*
X179083Y1446192D01*
X178875Y1445983D01*
X178583Y1445900D01*
X178292Y1446025D01*
X178083Y1446317D01*
X178000Y1446650D01*
X178083Y1446983D01*
X178292Y1447275D01*
X178583Y1447400D01*
X178875Y1447317D01*
X179083Y1447108D01*
X179167Y1446858D01*
Y1446442D01*
X179292Y1446067D01*
X179542Y1445817D01*
X179833Y1445733D01*
X180125Y1445817D01*
X180333Y1446025D01*
X180458Y1446358D01*
X180500Y1446650D01*
G01X174167Y1457200D02*
Y1459700D01*
X175167D01*
X175500Y1459575D01*
X175750Y1459283D01*
X175833Y1458950D01*
X175750Y1458617D01*
X175542Y1458367D01*
X175167Y1458242D01*
X174167D01*
G01X177267Y1457200D02*
Y1459700D01*
X178308D01*
X178642Y1459575D01*
X178850Y1459408D01*
X178933Y1459075D01*
X178850Y1458742D01*
X178600Y1458533D01*
X178308Y1458408D01*
X177267D01*
G01X178308D02*
X178933Y1457200D01*
G01X181200D02*
X181492Y1457242D01*
X181825Y1457367D01*
X182033Y1457575D01*
X182117Y1457867D01*
X182033Y1458158D01*
X181783Y1458408D01*
X181408Y1458533D01*
X180992D01*
X180742Y1458617D01*
X180533Y1458825D01*
X180450Y1459117D01*
X180575Y1459408D01*
X180867Y1459617D01*
X181200Y1459700D01*
X181533Y1459617D01*
X181825Y1459408D01*
X181950Y1459117D01*
X181867Y1458825D01*
X181658Y1458617D01*
X181408Y1458533D01*
X180992D01*
X180617Y1458408D01*
X180367Y1458158D01*
X180283Y1457867D01*
X180367Y1457575D01*
X180575Y1457367D01*
X180908Y1457242D01*
X181200Y1457200D01*
G01X138500Y1460400D02*
Y1456400D01*
X145900D01*
G01X174167Y1465200D02*
Y1467700D01*
X175167D01*
X175500Y1467575D01*
X175750Y1467283D01*
X175833Y1466950D01*
X175750Y1466617D01*
X175542Y1466367D01*
X175167Y1466242D01*
X174167D01*
G01X177267Y1465200D02*
Y1467700D01*
X178308D01*
X178642Y1467575D01*
X178850Y1467408D01*
X178933Y1467075D01*
X178850Y1466742D01*
X178600Y1466533D01*
X178308Y1466408D01*
X177267D01*
G01X178308D02*
X178933Y1465200D01*
G01X181117D02*
X181200Y1465742D01*
X181325Y1466200D01*
X181492Y1466617D01*
X181700Y1467075D01*
X182033Y1467700D01*
X180367D01*
G01X145900Y1464400D02*
Y1468400D01*
X138500D01*
G01X174167Y1461200D02*
Y1463700D01*
X175167D01*
X175500Y1463575D01*
X175750Y1463283D01*
X175833Y1462950D01*
X175750Y1462617D01*
X175542Y1462367D01*
X175167Y1462242D01*
X174167D01*
G01X177267Y1461200D02*
Y1463700D01*
X178308D01*
X178642Y1463575D01*
X178850Y1463408D01*
X178933Y1463075D01*
X178850Y1462742D01*
X178600Y1462533D01*
X178308Y1462408D01*
X177267D01*
G01X178308D02*
X178933Y1461200D01*
G01X180408Y1462242D02*
X180700Y1462533D01*
X180950Y1462700D01*
X181283Y1462783D01*
X181575Y1462700D01*
X181783Y1462533D01*
X181950Y1462283D01*
X181992Y1461992D01*
X181950Y1461742D01*
X181783Y1461492D01*
X181533Y1461283D01*
X181242Y1461200D01*
X180908Y1461283D01*
X180617Y1461533D01*
X180450Y1461908D01*
X180408Y1462325D01*
X180492Y1462867D01*
X180617Y1463158D01*
X180825Y1463450D01*
X181117Y1463658D01*
X181408Y1463700D01*
X181700Y1463617D01*
X181908Y1463408D01*
G01X145900Y1460400D02*
Y1464400D01*
X138500D01*
G01X173867Y1452100D02*
Y1454600D01*
X174867D01*
X175200Y1454475D01*
X175450Y1454183D01*
X175533Y1453850D01*
X175450Y1453517D01*
X175242Y1453267D01*
X174867Y1453142D01*
X173867D01*
G01X176967Y1452100D02*
Y1454600D01*
X178008D01*
X178342Y1454475D01*
X178550Y1454308D01*
X178633Y1453975D01*
X178550Y1453642D01*
X178300Y1453433D01*
X178008Y1453308D01*
X176967D01*
G01X178008D02*
X178633Y1452100D01*
G01X181400D02*
Y1454600D01*
X179858Y1452808D01*
X181942D01*
G01X145600Y1451300D02*
Y1455300D01*
X138200D01*
G01X155000Y1468017D02*
X152500D01*
Y1469017D01*
X152625Y1469350D01*
X152917Y1469600D01*
X153250Y1469683D01*
X153583Y1469600D01*
X153833Y1469392D01*
X153958Y1469017D01*
Y1468017D01*
G01X155000Y1471117D02*
X152500D01*
Y1472158D01*
X152625Y1472492D01*
X152792Y1472700D01*
X153125Y1472783D01*
X153458Y1472700D01*
X153667Y1472450D01*
X153792Y1472158D01*
Y1471117D01*
G01Y1472158D02*
X155000Y1472783D01*
G01X152917Y1474258D02*
X152667Y1474508D01*
X152542Y1474800D01*
X152500Y1475133D01*
X152583Y1475550D01*
X152792Y1475842D01*
X153042Y1475925D01*
X153292Y1475883D01*
X153500Y1475717D01*
X153917Y1474883D01*
X154208Y1474508D01*
X154625Y1474258D01*
X155000Y1474175D01*
Y1475925D01*
G01X154625Y1477233D02*
X154833Y1477483D01*
X154958Y1477775D01*
X155000Y1478150D01*
X154917Y1478525D01*
X154750Y1478817D01*
X154458Y1479025D01*
X154125Y1479067D01*
X153792Y1478983D01*
X153583Y1478775D01*
X153417Y1478483D01*
X153375Y1478192D01*
X153417Y1477900D01*
X153583Y1477525D01*
X152500Y1477650D01*
Y1478775D01*
G01X146500Y1468700D02*
X150500D01*
Y1476100D01*
G01X185017Y1458500D02*
Y1461000D01*
X186017D01*
X186350Y1460875D01*
X186600Y1460583D01*
X186683Y1460250D01*
X186600Y1459917D01*
X186392Y1459667D01*
X186017Y1459542D01*
X185017D01*
G01X188117Y1458500D02*
Y1461000D01*
X189158D01*
X189492Y1460875D01*
X189700Y1460708D01*
X189783Y1460375D01*
X189700Y1460042D01*
X189450Y1459833D01*
X189158Y1459708D01*
X188117D01*
G01X189158D02*
X189783Y1458500D01*
G01X192550D02*
Y1461000D01*
X191008Y1459208D01*
X193092D01*
G01X195150Y1458500D02*
X195442Y1458542D01*
X195775Y1458667D01*
X195983Y1458875D01*
X196067Y1459167D01*
X195983Y1459458D01*
X195733Y1459708D01*
X195358Y1459833D01*
X194942D01*
X194692Y1459917D01*
X194483Y1460125D01*
X194400Y1460417D01*
X194525Y1460708D01*
X194817Y1460917D01*
X195150Y1461000D01*
X195483Y1460917D01*
X195775Y1460708D01*
X195900Y1460417D01*
X195817Y1460125D01*
X195608Y1459917D01*
X195358Y1459833D01*
X194942D01*
X194567Y1459708D01*
X194317Y1459458D01*
X194233Y1459167D01*
X194317Y1458875D01*
X194525Y1458667D01*
X194858Y1458542D01*
X195150Y1458500D01*
G01X162700Y1456000D02*
Y1460000D01*
X155300D01*
G01X163400Y1424800D02*
X167400D01*
Y1432200D01*
G01X162869Y1448219D02*
Y1434219D01*
G01X175869Y1448219D02*
X162869D01*
G01X175869Y1434219D02*
Y1448219D01*
G01X162869Y1434219D02*
X175869D01*
G01X188500Y1436983D02*
X186000D01*
Y1437817D01*
X186125Y1438150D01*
X186292Y1438400D01*
X186542Y1438608D01*
X186833Y1438775D01*
X187250Y1438817D01*
X187667Y1438775D01*
X187958Y1438608D01*
X188208Y1438400D01*
X188375Y1438150D01*
X188500Y1437817D01*
Y1436983D01*
G01Y1441000D02*
X186000D01*
X186500Y1440500D01*
G01X188500D02*
Y1441500D01*
G01Y1444100D02*
X188458Y1444392D01*
X188333Y1444725D01*
X188125Y1444933D01*
X187833Y1445017D01*
X187542Y1444933D01*
X187292Y1444683D01*
X187167Y1444308D01*
Y1443892D01*
X187083Y1443642D01*
X186875Y1443433D01*
X186583Y1443350D01*
X186292Y1443475D01*
X186083Y1443767D01*
X186000Y1444100D01*
X186083Y1444433D01*
X186292Y1444725D01*
X186583Y1444850D01*
X186875Y1444767D01*
X187083Y1444558D01*
X187167Y1444308D01*
Y1443892D01*
X187292Y1443517D01*
X187542Y1443267D01*
X187833Y1443183D01*
X188125Y1443267D01*
X188333Y1443475D01*
X188458Y1443808D01*
X188500Y1444100D01*
G01X161800Y1434804D02*
Y1449604D01*
G01X155400Y1434804D02*
X161800D01*
G01X155400Y1449604D02*
Y1434804D01*
G01X161800Y1449604D02*
X155400D01*
G01X169600Y1482617D02*
X167100D01*
Y1483617D01*
X167225Y1483950D01*
X167517Y1484200D01*
X167850Y1484283D01*
X168183Y1484200D01*
X168433Y1483992D01*
X168558Y1483617D01*
Y1482617D01*
G01X169600Y1485717D02*
X167100D01*
Y1486758D01*
X167225Y1487092D01*
X167392Y1487300D01*
X167725Y1487383D01*
X168058Y1487300D01*
X168267Y1487050D01*
X168392Y1486758D01*
Y1485717D01*
G01Y1486758D02*
X169600Y1487383D01*
G01X167517Y1488858D02*
X167267Y1489108D01*
X167142Y1489400D01*
X167100Y1489733D01*
X167183Y1490150D01*
X167392Y1490442D01*
X167642Y1490525D01*
X167892Y1490483D01*
X168100Y1490317D01*
X168517Y1489483D01*
X168808Y1489108D01*
X169225Y1488858D01*
X169600Y1488775D01*
Y1490525D01*
G01Y1492750D02*
X169558Y1493042D01*
X169433Y1493375D01*
X169225Y1493583D01*
X168933Y1493667D01*
X168642Y1493583D01*
X168392Y1493333D01*
X168267Y1492958D01*
Y1492542D01*
X168183Y1492292D01*
X167975Y1492083D01*
X167683Y1492000D01*
X167392Y1492125D01*
X167183Y1492417D01*
X167100Y1492750D01*
X167183Y1493083D01*
X167392Y1493375D01*
X167683Y1493500D01*
X167975Y1493417D01*
X168183Y1493208D01*
X168267Y1492958D01*
Y1492542D01*
X168392Y1492167D01*
X168642Y1491917D01*
X168933Y1491833D01*
X169225Y1491917D01*
X169433Y1492125D01*
X169558Y1492458D01*
X169600Y1492750D01*
G01X149000Y1485800D02*
X153000D01*
Y1493200D01*
G01X165600Y1482617D02*
X163100D01*
Y1483617D01*
X163225Y1483950D01*
X163517Y1484200D01*
X163850Y1484283D01*
X164183Y1484200D01*
X164433Y1483992D01*
X164558Y1483617D01*
Y1482617D01*
G01X165600Y1485717D02*
X163100D01*
Y1486758D01*
X163225Y1487092D01*
X163392Y1487300D01*
X163725Y1487383D01*
X164058Y1487300D01*
X164267Y1487050D01*
X164392Y1486758D01*
Y1485717D01*
G01Y1486758D02*
X165600Y1487383D01*
G01X163517Y1488858D02*
X163267Y1489108D01*
X163142Y1489400D01*
X163100Y1489733D01*
X163183Y1490150D01*
X163392Y1490442D01*
X163642Y1490525D01*
X163892Y1490483D01*
X164100Y1490317D01*
X164517Y1489483D01*
X164808Y1489108D01*
X165225Y1488858D01*
X165600Y1488775D01*
Y1490525D01*
G01Y1492667D02*
X165058Y1492750D01*
X164600Y1492875D01*
X164183Y1493042D01*
X163725Y1493250D01*
X163100Y1493583D01*
Y1491917D01*
G01X144500Y1485800D02*
X148500D01*
Y1493200D01*
G01X161600Y1482617D02*
X159100D01*
Y1483617D01*
X159225Y1483950D01*
X159517Y1484200D01*
X159850Y1484283D01*
X160183Y1484200D01*
X160433Y1483992D01*
X160558Y1483617D01*
Y1482617D01*
G01X161600Y1485717D02*
X159100D01*
Y1486758D01*
X159225Y1487092D01*
X159392Y1487300D01*
X159725Y1487383D01*
X160058Y1487300D01*
X160267Y1487050D01*
X160392Y1486758D01*
Y1485717D01*
G01Y1486758D02*
X161600Y1487383D01*
G01X159517Y1488858D02*
X159267Y1489108D01*
X159142Y1489400D01*
X159100Y1489733D01*
X159183Y1490150D01*
X159392Y1490442D01*
X159642Y1490525D01*
X159892Y1490483D01*
X160100Y1490317D01*
X160517Y1489483D01*
X160808Y1489108D01*
X161225Y1488858D01*
X161600Y1488775D01*
Y1490525D01*
G01X160558Y1491958D02*
X160267Y1492250D01*
X160100Y1492500D01*
X160017Y1492833D01*
X160100Y1493125D01*
X160267Y1493333D01*
X160517Y1493500D01*
X160808Y1493542D01*
X161058Y1493500D01*
X161308Y1493333D01*
X161517Y1493083D01*
X161600Y1492792D01*
X161517Y1492458D01*
X161267Y1492167D01*
X160892Y1492000D01*
X160475Y1491958D01*
X159933Y1492042D01*
X159642Y1492167D01*
X159350Y1492375D01*
X159142Y1492667D01*
X159100Y1492958D01*
X159183Y1493250D01*
X159392Y1493458D01*
G01X140000Y1485800D02*
X144000D01*
Y1493200D01*
G01X157500Y1482517D02*
X155000D01*
Y1483517D01*
X155125Y1483850D01*
X155417Y1484100D01*
X155750Y1484183D01*
X156083Y1484100D01*
X156333Y1483892D01*
X156458Y1483517D01*
Y1482517D01*
G01X157500Y1485617D02*
X155000D01*
Y1486658D01*
X155125Y1486992D01*
X155292Y1487200D01*
X155625Y1487283D01*
X155958Y1487200D01*
X156167Y1486950D01*
X156292Y1486658D01*
Y1485617D01*
G01Y1486658D02*
X157500Y1487283D01*
G01X157125Y1488633D02*
X157333Y1488883D01*
X157458Y1489175D01*
X157500Y1489550D01*
X157417Y1489925D01*
X157250Y1490217D01*
X156958Y1490425D01*
X156625Y1490467D01*
X156292Y1490383D01*
X156083Y1490175D01*
X155917Y1489883D01*
X155875Y1489592D01*
X155917Y1489300D01*
X156083Y1488925D01*
X155000Y1489050D01*
Y1490175D01*
G01X157500Y1492650D02*
X155000D01*
X155500Y1492150D01*
G01X157500D02*
Y1493150D01*
G01X138800Y1484800D02*
X145800D01*
G01X153300Y1522500D02*
X164500D01*
G01X153300Y1540500D02*
Y1522500D01*
G01X191700D02*
X180500D01*
G01X152600Y1520200D02*
X192800D01*
G01X152600Y1495200D02*
Y1520200D01*
G01X192800Y1495200D02*
X152600D01*
G01X180850Y1571300D02*
Y1601300D01*
G01X159150Y1571300D02*
X180850D01*
G01X159150Y1601300D02*
Y1571300D01*
G01X146850D02*
Y1601300D01*
G01X164500Y1540500D02*
X153300D01*
G01X180500D02*
X191700D01*
G01X153400Y1542600D02*
X164600D01*
G01X153400Y1560600D02*
Y1542600D01*
G01X164600Y1560600D02*
X153400D01*
G01X191800Y1542600D02*
X180600D01*
G01Y1560600D02*
X191800D01*
G01X164967Y1604100D02*
Y1606600D01*
X165967D01*
X166300Y1606475D01*
X166550Y1606183D01*
X166633Y1605850D01*
X166550Y1605517D01*
X166342Y1605267D01*
X165967Y1605142D01*
X164967D01*
G01X168900Y1604100D02*
X168567Y1604142D01*
X168275Y1604308D01*
X168025Y1604558D01*
X167858Y1604850D01*
X167775Y1605183D01*
Y1605517D01*
X167858Y1605850D01*
X168025Y1606142D01*
X168275Y1606392D01*
X168567Y1606558D01*
X168900Y1606600D01*
X169233Y1606558D01*
X169525Y1606392D01*
X169775Y1606142D01*
X169942Y1605850D01*
X170025Y1605517D01*
Y1605183D01*
X169942Y1604850D01*
X169775Y1604558D01*
X169525Y1604308D01*
X169233Y1604142D01*
X168900Y1604100D01*
G01X169233Y1604767D02*
X169733Y1604100D01*
G01X171083Y1604600D02*
X171333Y1604308D01*
X171667Y1604142D01*
X172042Y1604100D01*
X172375Y1604142D01*
X172708Y1604350D01*
X172917Y1604600D01*
X172958Y1604850D01*
X172875Y1605142D01*
X172583Y1605350D01*
X172292Y1605433D01*
X171917D01*
G01X172292D02*
X172542Y1605558D01*
X172750Y1605767D01*
X172833Y1606017D01*
X172750Y1606267D01*
X172542Y1606475D01*
X172167Y1606600D01*
X171792Y1606558D01*
X171417Y1606392D01*
G01X180850Y1601300D02*
X159150D01*
G01X183067Y1612000D02*
Y1614500D01*
X184067D01*
X184400Y1614375D01*
X184650Y1614083D01*
X184733Y1613750D01*
X184650Y1613417D01*
X184442Y1613167D01*
X184067Y1613042D01*
X183067D01*
G01X187917Y1614292D02*
X187667Y1614417D01*
X187375Y1614500D01*
X187042D01*
X186667Y1614375D01*
X186375Y1614167D01*
X186167Y1613917D01*
X186000Y1613500D01*
X185958Y1613125D01*
X186042Y1612750D01*
X186167Y1612500D01*
X186417Y1612250D01*
X186708Y1612083D01*
X187000Y1612000D01*
X187292D01*
X187583Y1612083D01*
X187833Y1612208D01*
X188042Y1612375D01*
G01X190017Y1612000D02*
X190100Y1612542D01*
X190225Y1613000D01*
X190392Y1613417D01*
X190600Y1613875D01*
X190933Y1614500D01*
X189267D01*
G01X172000Y1611517D02*
X169500D01*
Y1612517D01*
X169625Y1612850D01*
X169917Y1613100D01*
X170250Y1613183D01*
X170583Y1613100D01*
X170833Y1612892D01*
X170958Y1612517D01*
Y1611517D01*
G01X172000Y1614617D02*
X169500D01*
Y1615658D01*
X169625Y1615992D01*
X169792Y1616200D01*
X170125Y1616283D01*
X170458Y1616200D01*
X170667Y1615950D01*
X170792Y1615658D01*
Y1614617D01*
G01Y1615658D02*
X172000Y1616283D01*
G01X171500Y1617633D02*
X171792Y1617883D01*
X171958Y1618217D01*
X172000Y1618592D01*
X171958Y1618925D01*
X171750Y1619258D01*
X171500Y1619467D01*
X171250Y1619508D01*
X170958Y1619425D01*
X170750Y1619133D01*
X170667Y1618842D01*
Y1618467D01*
G01Y1618842D02*
X170542Y1619092D01*
X170333Y1619300D01*
X170083Y1619383D01*
X169833Y1619300D01*
X169625Y1619092D01*
X169500Y1618717D01*
X169542Y1618342D01*
X169708Y1617967D01*
G01X169917Y1620858D02*
X169667Y1621108D01*
X169542Y1621400D01*
X169500Y1621733D01*
X169583Y1622150D01*
X169792Y1622442D01*
X170042Y1622525D01*
X170292Y1622483D01*
X170500Y1622317D01*
X170917Y1621483D01*
X171208Y1621108D01*
X171625Y1620858D01*
X172000Y1620775D01*
Y1622525D01*
G01X152250Y1610000D02*
Y1623000D01*
X167750D01*
Y1610000D01*
X152250D01*
G01X144500Y1612017D02*
X142000D01*
Y1613017D01*
X142125Y1613350D01*
X142417Y1613600D01*
X142750Y1613683D01*
X143083Y1613600D01*
X143333Y1613392D01*
X143458Y1613017D01*
Y1612017D01*
G01X144500Y1615117D02*
X142000D01*
Y1616158D01*
X142125Y1616492D01*
X142292Y1616700D01*
X142625Y1616783D01*
X142958Y1616700D01*
X143167Y1616450D01*
X143292Y1616158D01*
Y1615117D01*
G01Y1616158D02*
X144500Y1616783D01*
G01X144000Y1618133D02*
X144292Y1618383D01*
X144458Y1618717D01*
X144500Y1619092D01*
X144458Y1619425D01*
X144250Y1619758D01*
X144000Y1619967D01*
X143750Y1620008D01*
X143458Y1619925D01*
X143250Y1619633D01*
X143167Y1619342D01*
Y1618967D01*
G01Y1619342D02*
X143042Y1619592D01*
X142833Y1619800D01*
X142583Y1619883D01*
X142333Y1619800D01*
X142125Y1619592D01*
X142000Y1619217D01*
X142042Y1618842D01*
X142208Y1618467D01*
G01X144500Y1622150D02*
X142000D01*
X142500Y1621650D01*
G01X144500D02*
Y1622650D01*
G01X152517Y1861500D02*
Y1864000D01*
X153517D01*
X153850Y1863875D01*
X154100Y1863583D01*
X154183Y1863250D01*
X154100Y1862917D01*
X153892Y1862667D01*
X153517Y1862542D01*
X152517D01*
G01X155408Y1861500D02*
X156450Y1864000D01*
X157492Y1861500D01*
G01X157117Y1862375D02*
X155783D01*
G01X158633Y1861500D02*
Y1864000D01*
X159467D01*
X159800Y1863875D01*
X160050Y1863708D01*
X160258Y1863458D01*
X160425Y1863167D01*
X160467Y1862750D01*
X160425Y1862333D01*
X160258Y1862042D01*
X160050Y1861792D01*
X159800Y1861625D01*
X159467Y1861500D01*
X158633D01*
G01X161858Y1863583D02*
X162108Y1863833D01*
X162400Y1863958D01*
X162733Y1864000D01*
X163150Y1863917D01*
X163442Y1863708D01*
X163525Y1863458D01*
X163483Y1863208D01*
X163317Y1863000D01*
X162483Y1862583D01*
X162108Y1862292D01*
X161858Y1861875D01*
X161775Y1861500D01*
X163525D01*
G01X144317Y1889792D02*
X144067Y1889917D01*
X143775Y1890000D01*
X143442D01*
X143067Y1889875D01*
X142775Y1889667D01*
X142567Y1889417D01*
X142400Y1889000D01*
X142358Y1888625D01*
X142442Y1888250D01*
X142567Y1888000D01*
X142817Y1887750D01*
X143108Y1887583D01*
X143400Y1887500D01*
X143692D01*
X143983Y1887583D01*
X144233Y1887708D01*
X144442Y1887875D01*
G01X145583D02*
X145833Y1887667D01*
X146125Y1887542D01*
X146500Y1887500D01*
X146875Y1887583D01*
X147167Y1887750D01*
X147375Y1888042D01*
X147417Y1888375D01*
X147333Y1888708D01*
X147125Y1888917D01*
X146833Y1889083D01*
X146542Y1889125D01*
X146250Y1889083D01*
X145875Y1888917D01*
X146000Y1890000D01*
X147125D01*
G01X149600D02*
X149267Y1889917D01*
X149017Y1889708D01*
X148850Y1889458D01*
X148725Y1889125D01*
X148683Y1888750D01*
X148725Y1888375D01*
X148850Y1888042D01*
X149017Y1887792D01*
X149267Y1887583D01*
X149600Y1887500D01*
X149933Y1887583D01*
X150183Y1887792D01*
X150350Y1888042D01*
X150475Y1888375D01*
X150517Y1888750D01*
X150475Y1889125D01*
X150350Y1889458D01*
X150183Y1889708D01*
X149933Y1889917D01*
X149600Y1890000D01*
G01X144317Y1894292D02*
X144067Y1894417D01*
X143775Y1894500D01*
X143442D01*
X143067Y1894375D01*
X142775Y1894167D01*
X142567Y1893917D01*
X142400Y1893500D01*
X142358Y1893125D01*
X142442Y1892750D01*
X142567Y1892500D01*
X142817Y1892250D01*
X143108Y1892083D01*
X143400Y1892000D01*
X143692D01*
X143983Y1892083D01*
X144233Y1892208D01*
X144442Y1892375D01*
G01X147000Y1892000D02*
Y1894500D01*
X145458Y1892708D01*
X147542D01*
G01X148892Y1892292D02*
X149183Y1892083D01*
X149517Y1892000D01*
X149850Y1892083D01*
X150142Y1892333D01*
X150350Y1892708D01*
X150433Y1893083D01*
Y1893542D01*
X150350Y1893917D01*
X150142Y1894250D01*
X149892Y1894417D01*
X149600Y1894500D01*
X149267Y1894417D01*
X149017Y1894250D01*
X148850Y1894000D01*
X148767Y1893667D01*
X148850Y1893375D01*
X149058Y1893083D01*
X149308Y1892917D01*
X149600Y1892875D01*
X149933Y1892958D01*
X150183Y1893167D01*
X150433Y1893542D01*
G01X176575Y1908500D02*
Y1911000D01*
G01X178325D02*
Y1908500D01*
G01Y1909750D02*
X176575D01*
G01X179633Y1909000D02*
X179883Y1908708D01*
X180217Y1908542D01*
X180592Y1908500D01*
X180925Y1908542D01*
X181258Y1908750D01*
X181467Y1909000D01*
X181508Y1909250D01*
X181425Y1909542D01*
X181133Y1909750D01*
X180842Y1909833D01*
X180467D01*
G01X180842D02*
X181092Y1909958D01*
X181300Y1910167D01*
X181383Y1910417D01*
X181300Y1910667D01*
X181092Y1910875D01*
X180717Y1911000D01*
X180342Y1910958D01*
X179967Y1910792D01*
G01X167814Y1966620D02*
X168214Y1967020D01*
X168681Y1967220D01*
X169214Y1967287D01*
X169881Y1967154D01*
X170348Y1966820D01*
X170481Y1966420D01*
X170414Y1966020D01*
X170148Y1965687D01*
X168814Y1965020D01*
X168214Y1964554D01*
X167814Y1963887D01*
X167681Y1963287D01*
X170481D01*
G01X192000Y365700D02*
Y347700D01*
G01X192100Y406900D02*
Y388900D01*
G01X192200Y385900D02*
Y367900D01*
G01X188967Y443500D02*
Y446000D01*
X189967D01*
X190300Y445875D01*
X190550Y445583D01*
X190633Y445250D01*
X190550Y444917D01*
X190342Y444667D01*
X189967Y444542D01*
X188967D01*
G01X192067Y443500D02*
Y446000D01*
X193108D01*
X193442Y445875D01*
X193650Y445708D01*
X193733Y445375D01*
X193650Y445042D01*
X193400Y444833D01*
X193108Y444708D01*
X192067D01*
G01X193108D02*
X193733Y443500D01*
G01X196000D02*
Y446000D01*
X195500Y445500D01*
G01Y443500D02*
X196500D01*
G01X199100D02*
Y446000D01*
X198600Y445500D01*
G01Y443500D02*
X199600D01*
G01X201492Y443792D02*
X201783Y443583D01*
X202117Y443500D01*
X202450Y443583D01*
X202742Y443833D01*
X202950Y444208D01*
X203033Y444583D01*
Y445042D01*
X202950Y445417D01*
X202742Y445750D01*
X202492Y445917D01*
X202200Y446000D01*
X201867Y445917D01*
X201617Y445750D01*
X201450Y445500D01*
X201367Y445167D01*
X201450Y444875D01*
X201658Y444583D01*
X201908Y444417D01*
X202200Y444375D01*
X202533Y444458D01*
X202783Y444667D01*
X203033Y445042D01*
G01X188800Y441500D02*
Y437500D01*
X196200D01*
G01X192100Y427400D02*
Y409400D01*
G01X189017Y455500D02*
Y458000D01*
X190017D01*
X190350Y457875D01*
X190600Y457583D01*
X190683Y457250D01*
X190600Y456917D01*
X190392Y456667D01*
X190017Y456542D01*
X189017D01*
G01X192950Y455500D02*
X192617Y455542D01*
X192325Y455708D01*
X192075Y455958D01*
X191908Y456250D01*
X191825Y456583D01*
Y456917D01*
X191908Y457250D01*
X192075Y457542D01*
X192325Y457792D01*
X192617Y457958D01*
X192950Y458000D01*
X193283Y457958D01*
X193575Y457792D01*
X193825Y457542D01*
X193992Y457250D01*
X194075Y456917D01*
Y456583D01*
X193992Y456250D01*
X193825Y455958D01*
X193575Y455708D01*
X193283Y455542D01*
X192950Y455500D01*
G01X193283Y456167D02*
X193783Y455500D01*
G01X196050D02*
Y458000D01*
X195550Y457500D01*
G01Y455500D02*
X196550D01*
G01X198358Y457583D02*
X198608Y457833D01*
X198900Y457958D01*
X199233Y458000D01*
X199650Y457917D01*
X199942Y457708D01*
X200025Y457458D01*
X199983Y457208D01*
X199817Y457000D01*
X198983Y456583D01*
X198608Y456292D01*
X198358Y455875D01*
X198275Y455500D01*
X200025D01*
G01X201000Y547967D02*
X198500D01*
Y548967D01*
X198625Y549300D01*
X198917Y549550D01*
X199250Y549633D01*
X199583Y549550D01*
X199833Y549342D01*
X199958Y548967D01*
Y547967D01*
G01X201000Y551067D02*
X198500D01*
Y552108D01*
X198625Y552442D01*
X198792Y552650D01*
X199125Y552733D01*
X199458Y552650D01*
X199667Y552400D01*
X199792Y552108D01*
Y551067D01*
G01Y552108D02*
X201000Y552733D01*
G01Y555000D02*
X198500D01*
X199000Y554500D01*
G01X201000D02*
Y555500D01*
G01Y558100D02*
X198500D01*
X199000Y557600D01*
G01X201000D02*
Y558600D01*
G01X200500Y560283D02*
X200792Y560533D01*
X200958Y560867D01*
X201000Y561242D01*
X200958Y561575D01*
X200750Y561908D01*
X200500Y562117D01*
X200250Y562158D01*
X199958Y562075D01*
X199750Y561783D01*
X199667Y561492D01*
Y561117D01*
G01Y561492D02*
X199542Y561742D01*
X199333Y561950D01*
X199083Y562033D01*
X198833Y561950D01*
X198625Y561742D01*
X198500Y561367D01*
X198542Y560992D01*
X198708Y560617D01*
G01X188575Y588500D02*
Y591000D01*
G01X190325D02*
Y588500D01*
G01Y589750D02*
X188575D01*
G01X192550Y588500D02*
X192842Y588542D01*
X193175Y588667D01*
X193383Y588875D01*
X193467Y589167D01*
X193383Y589458D01*
X193133Y589708D01*
X192758Y589833D01*
X192342D01*
X192092Y589917D01*
X191883Y590125D01*
X191800Y590417D01*
X191925Y590708D01*
X192217Y590917D01*
X192550Y591000D01*
X192883Y590917D01*
X193175Y590708D01*
X193300Y590417D01*
X193217Y590125D01*
X193008Y589917D01*
X192758Y589833D01*
X192342D01*
X191967Y589708D01*
X191717Y589458D01*
X191633Y589167D01*
X191717Y588875D01*
X191925Y588667D01*
X192258Y588542D01*
X192550Y588500D01*
G01X195900Y632800D02*
X195817Y632133D01*
X195483Y631550D01*
X194983Y631050D01*
X194400Y630717D01*
X193733Y630550D01*
X193067D01*
X192400Y630717D01*
X191817Y631050D01*
X191317Y631550D01*
X190983Y632133D01*
X190900Y632800D01*
X190983Y633467D01*
X191317Y634050D01*
X191817Y634550D01*
X192400Y634883D01*
X193067Y635050D01*
X193733D01*
X194400Y634883D01*
X194983Y634550D01*
X195483Y634050D01*
X195817Y633467D01*
X195900Y632800D01*
G01X195233Y636650D02*
X195650Y637317D01*
X195900Y638067D01*
Y638733D01*
X195650Y639400D01*
X195233Y639900D01*
X194650Y640150D01*
X194067Y639983D01*
X193567Y639567D01*
X193233Y638817D01*
X193067Y637817D01*
X192733Y637233D01*
X192150Y636983D01*
X191567Y637150D01*
X191150Y637567D01*
X190900Y638150D01*
Y638733D01*
X191067Y639317D01*
X191483Y639817D01*
G01X191317Y645833D02*
X191067Y645333D01*
X190900Y644750D01*
Y644083D01*
X191150Y643333D01*
X191567Y642750D01*
X192067Y642333D01*
X192900Y642000D01*
X193650Y641917D01*
X194400Y642083D01*
X194900Y642333D01*
X195400Y642833D01*
X195733Y643417D01*
X195900Y644000D01*
Y644583D01*
X195733Y645167D01*
X195483Y645667D01*
X195150Y646083D01*
G01X195900Y649600D02*
X190900D01*
X191900Y648600D01*
G01X195900D02*
Y650600D01*
G01X196067Y655200D02*
X195983Y655033D01*
X195817D01*
X195733Y655200D01*
X195817Y655367D01*
X195983D01*
X196067Y655200D01*
G01X193817D02*
X193733Y655033D01*
X193567D01*
X193483Y655200D01*
X193567Y655367D01*
X193733D01*
X193817Y655200D01*
G01X194900Y658967D02*
X195483Y659467D01*
X195817Y660133D01*
X195900Y660883D01*
X195817Y661550D01*
X195400Y662217D01*
X194900Y662633D01*
X194400Y662717D01*
X193817Y662550D01*
X193400Y661967D01*
X193233Y661383D01*
Y660633D01*
G01Y661383D02*
X192983Y661883D01*
X192567Y662300D01*
X192067Y662467D01*
X191567Y662300D01*
X191150Y661883D01*
X190900Y661133D01*
X190983Y660383D01*
X191317Y659633D01*
G01X194900Y664567D02*
X195483Y665067D01*
X195817Y665733D01*
X195900Y666483D01*
X195817Y667150D01*
X195400Y667817D01*
X194900Y668233D01*
X194400Y668317D01*
X193817Y668150D01*
X193400Y667567D01*
X193233Y666983D01*
Y666233D01*
G01Y666983D02*
X192983Y667483D01*
X192567Y667900D01*
X192067Y668067D01*
X191567Y667900D01*
X191150Y667483D01*
X190900Y666733D01*
X190983Y665983D01*
X191317Y665233D01*
G01X195900Y669833D02*
X190900D01*
X195067Y672000D01*
X190900Y674167D01*
X195900D01*
G01Y675850D02*
X190900D01*
G01Y679350D02*
X195900D01*
G01X193400D02*
Y675850D01*
G01X190900Y681617D02*
Y684783D01*
X195900Y681617D01*
Y684783D01*
G01X199500Y619567D02*
X197000D01*
Y620608D01*
X197125Y620942D01*
X197292Y621150D01*
X197625Y621233D01*
X197958Y621150D01*
X198167Y620900D01*
X198292Y620608D01*
Y619567D01*
G01Y620608D02*
X199500Y621233D01*
G01X199125Y622583D02*
X199333Y622833D01*
X199458Y623125D01*
X199500Y623500D01*
X199417Y623875D01*
X199250Y624167D01*
X198958Y624375D01*
X198625Y624417D01*
X198292Y624333D01*
X198083Y624125D01*
X197917Y623833D01*
X197875Y623542D01*
X197917Y623250D01*
X198083Y622875D01*
X197000Y623000D01*
Y624125D01*
G01X199500Y626600D02*
X197000D01*
X197500Y626100D01*
G01X199500D02*
Y627100D01*
G01X203500Y619067D02*
X201000D01*
Y620108D01*
X201125Y620442D01*
X201292Y620650D01*
X201625Y620733D01*
X201958Y620650D01*
X202167Y620400D01*
X202292Y620108D01*
Y619067D01*
G01Y620108D02*
X203500Y620733D01*
G01Y623000D02*
X201000D01*
X201500Y622500D01*
G01X203500D02*
Y623500D01*
G01Y626600D02*
X201000D01*
X202792Y625058D01*
Y627142D01*
G01X198500Y605517D02*
X201000D01*
Y607183D01*
G01X198917Y608658D02*
X198667Y608908D01*
X198542Y609200D01*
X198500Y609533D01*
X198583Y609950D01*
X198792Y610242D01*
X199042Y610325D01*
X199292Y610283D01*
X199500Y610117D01*
X199917Y609283D01*
X200208Y608908D01*
X200625Y608658D01*
X201000Y608575D01*
Y610325D01*
G01X190708Y607267D02*
X190583Y607017D01*
X190500Y606725D01*
Y606392D01*
X190625Y606017D01*
X190833Y605725D01*
X191083Y605517D01*
X191500Y605350D01*
X191875Y605308D01*
X192250Y605392D01*
X192500Y605517D01*
X192750Y605767D01*
X192917Y606058D01*
X193000Y606350D01*
Y606642D01*
X192917Y606933D01*
X192792Y607183D01*
X192625Y607392D01*
G01X193000Y609950D02*
X190500D01*
X192292Y608408D01*
Y610492D01*
G01X194708Y607267D02*
X194583Y607017D01*
X194500Y606725D01*
Y606392D01*
X194625Y606017D01*
X194833Y605725D01*
X195083Y605517D01*
X195500Y605350D01*
X195875Y605308D01*
X196250Y605392D01*
X196500Y605517D01*
X196750Y605767D01*
X196917Y606058D01*
X197000Y606350D01*
Y606642D01*
X196917Y606933D01*
X196792Y607183D01*
X196625Y607392D01*
G01X196500Y608533D02*
X196792Y608783D01*
X196958Y609117D01*
X197000Y609492D01*
X196958Y609825D01*
X196750Y610158D01*
X196500Y610367D01*
X196250Y610408D01*
X195958Y610325D01*
X195750Y610033D01*
X195667Y609742D01*
Y609367D01*
G01Y609742D02*
X195542Y609992D01*
X195333Y610200D01*
X195083Y610283D01*
X194833Y610200D01*
X194625Y609992D01*
X194500Y609617D01*
X194542Y609242D01*
X194708Y608867D01*
G01X191708Y691267D02*
X191583Y691017D01*
X191500Y690725D01*
Y690392D01*
X191625Y690017D01*
X191833Y689725D01*
X192083Y689517D01*
X192500Y689350D01*
X192875Y689308D01*
X193250Y689392D01*
X193500Y689517D01*
X193750Y689767D01*
X193917Y690058D01*
X194000Y690350D01*
Y690642D01*
X193917Y690933D01*
X193792Y691183D01*
X193625Y691392D01*
G01X191917Y692658D02*
X191667Y692908D01*
X191542Y693200D01*
X191500Y693533D01*
X191583Y693950D01*
X191792Y694242D01*
X192042Y694325D01*
X192292Y694283D01*
X192500Y694117D01*
X192917Y693283D01*
X193208Y692908D01*
X193625Y692658D01*
X194000Y692575D01*
Y694325D01*
G01X193625Y695633D02*
X193833Y695883D01*
X193958Y696175D01*
X194000Y696550D01*
X193917Y696925D01*
X193750Y697217D01*
X193458Y697425D01*
X193125Y697467D01*
X192792Y697383D01*
X192583Y697175D01*
X192417Y696883D01*
X192375Y696592D01*
X192417Y696300D01*
X192583Y695925D01*
X191500Y696050D01*
Y697175D01*
G01X193500Y698733D02*
X193792Y698983D01*
X193958Y699317D01*
X194000Y699692D01*
X193958Y700025D01*
X193750Y700358D01*
X193500Y700567D01*
X193250Y700608D01*
X192958Y700525D01*
X192750Y700233D01*
X192667Y699942D01*
Y699567D01*
G01Y699942D02*
X192542Y700192D01*
X192333Y700400D01*
X192083Y700483D01*
X191833Y700400D01*
X191625Y700192D01*
X191500Y699817D01*
X191542Y699442D01*
X191708Y699067D01*
G01X198000Y689517D02*
X195500D01*
Y690517D01*
X195625Y690850D01*
X195917Y691100D01*
X196250Y691183D01*
X196583Y691100D01*
X196833Y690892D01*
X196958Y690517D01*
Y689517D01*
G01X198000Y692617D02*
X195500D01*
Y693658D01*
X195625Y693992D01*
X195792Y694200D01*
X196125Y694283D01*
X196458Y694200D01*
X196667Y693950D01*
X196792Y693658D01*
Y692617D01*
G01Y693658D02*
X198000Y694283D01*
G01Y697050D02*
X195500D01*
X197292Y695508D01*
Y697592D01*
G01X198000Y699567D02*
X197458Y699650D01*
X197000Y699775D01*
X196583Y699942D01*
X196125Y700150D01*
X195500Y700483D01*
Y698817D01*
G01X201500Y689517D02*
X199000D01*
Y690558D01*
X199125Y690892D01*
X199292Y691100D01*
X199625Y691183D01*
X199958Y691100D01*
X200167Y690850D01*
X200292Y690558D01*
Y689517D01*
G01Y690558D02*
X201500Y691183D01*
G01X199417Y692658D02*
X199167Y692908D01*
X199042Y693200D01*
X199000Y693533D01*
X199083Y693950D01*
X199292Y694242D01*
X199542Y694325D01*
X199792Y694283D01*
X200000Y694117D01*
X200417Y693283D01*
X200708Y692908D01*
X201125Y692658D01*
X201500Y692575D01*
Y694325D01*
G01Y696467D02*
X200958Y696550D01*
X200500Y696675D01*
X200083Y696842D01*
X199625Y697050D01*
X199000Y697383D01*
Y695717D01*
G01Y699650D02*
X199083Y699317D01*
X199292Y699067D01*
X199542Y698900D01*
X199875Y698775D01*
X200250Y698733D01*
X200625Y698775D01*
X200958Y698900D01*
X201208Y699067D01*
X201417Y699317D01*
X201500Y699650D01*
X201417Y699983D01*
X201208Y700233D01*
X200958Y700400D01*
X200625Y700525D01*
X200250Y700567D01*
X199875Y700525D01*
X199542Y700400D01*
X199292Y700233D01*
X199083Y699983D01*
X199000Y699650D01*
G01X192500Y1437067D02*
X190000D01*
Y1438067D01*
X190125Y1438400D01*
X190417Y1438650D01*
X190750Y1438733D01*
X191083Y1438650D01*
X191333Y1438442D01*
X191458Y1438067D01*
Y1437067D01*
G01X192500Y1441000D02*
X192458Y1440667D01*
X192292Y1440375D01*
X192042Y1440125D01*
X191750Y1439958D01*
X191417Y1439875D01*
X191083D01*
X190750Y1439958D01*
X190458Y1440125D01*
X190208Y1440375D01*
X190042Y1440667D01*
X190000Y1441000D01*
X190042Y1441333D01*
X190208Y1441625D01*
X190458Y1441875D01*
X190750Y1442042D01*
X191083Y1442125D01*
X191417D01*
X191750Y1442042D01*
X192042Y1441875D01*
X192292Y1441625D01*
X192458Y1441333D01*
X192500Y1441000D01*
G01X191833Y1441333D02*
X192500Y1441833D01*
G01X191458Y1443308D02*
X191167Y1443600D01*
X191000Y1443850D01*
X190917Y1444183D01*
X191000Y1444475D01*
X191167Y1444683D01*
X191417Y1444850D01*
X191708Y1444892D01*
X191958Y1444850D01*
X192208Y1444683D01*
X192417Y1444433D01*
X192500Y1444142D01*
X192417Y1443808D01*
X192167Y1443517D01*
X191792Y1443350D01*
X191375Y1443308D01*
X190833Y1443392D01*
X190542Y1443517D01*
X190250Y1443725D01*
X190042Y1444017D01*
X190000Y1444308D01*
X190083Y1444600D01*
X190292Y1444808D01*
G01X191700Y1540500D02*
Y1522500D01*
G01X194483Y1508000D02*
Y1510500D01*
X195317D01*
X195650Y1510375D01*
X195900Y1510208D01*
X196108Y1509958D01*
X196275Y1509667D01*
X196317Y1509250D01*
X196275Y1508833D01*
X196108Y1508542D01*
X195900Y1508292D01*
X195650Y1508125D01*
X195317Y1508000D01*
X194483D01*
G01X198500D02*
Y1510500D01*
X198000Y1510000D01*
G01Y1508000D02*
X199000D01*
G01X202100D02*
Y1510500D01*
X200558Y1508708D01*
X202642D01*
G01X192800Y1520200D02*
Y1495200D01*
G01X195900Y1528900D02*
Y1526400D01*
G01X194942Y1528900D02*
X196858D01*
G01X199917Y1528692D02*
X199667Y1528817D01*
X199375Y1528900D01*
X199042D01*
X198667Y1528775D01*
X198375Y1528567D01*
X198167Y1528317D01*
X198000Y1527900D01*
X197958Y1527525D01*
X198042Y1527150D01*
X198167Y1526900D01*
X198417Y1526650D01*
X198708Y1526483D01*
X199000Y1526400D01*
X199292D01*
X199583Y1526483D01*
X199833Y1526608D01*
X200042Y1526775D01*
G01X201392Y1526692D02*
X201683Y1526483D01*
X202017Y1526400D01*
X202350Y1526483D01*
X202642Y1526733D01*
X202850Y1527108D01*
X202933Y1527483D01*
Y1527942D01*
X202850Y1528317D01*
X202642Y1528650D01*
X202392Y1528817D01*
X202100Y1528900D01*
X201767Y1528817D01*
X201517Y1528650D01*
X201350Y1528400D01*
X201267Y1528067D01*
X201350Y1527775D01*
X201558Y1527483D01*
X201808Y1527317D01*
X202100Y1527275D01*
X202433Y1527358D01*
X202683Y1527567D01*
X202933Y1527942D01*
G01X194350Y1549000D02*
Y1546500D01*
G01X193392Y1549000D02*
X195308D01*
G01X198367Y1548792D02*
X198117Y1548917D01*
X197825Y1549000D01*
X197492D01*
X197117Y1548875D01*
X196825Y1548667D01*
X196617Y1548417D01*
X196450Y1548000D01*
X196408Y1547625D01*
X196492Y1547250D01*
X196617Y1547000D01*
X196867Y1546750D01*
X197158Y1546583D01*
X197450Y1546500D01*
X197742D01*
X198033Y1546583D01*
X198283Y1546708D01*
X198492Y1546875D01*
G01X200550Y1546500D02*
Y1549000D01*
X200050Y1548500D01*
G01Y1546500D02*
X201050D01*
G01X203650Y1549000D02*
X203317Y1548917D01*
X203067Y1548708D01*
X202900Y1548458D01*
X202775Y1548125D01*
X202733Y1547750D01*
X202775Y1547375D01*
X202900Y1547042D01*
X203067Y1546792D01*
X203317Y1546583D01*
X203650Y1546500D01*
X203983Y1546583D01*
X204233Y1546792D01*
X204400Y1547042D01*
X204525Y1547375D01*
X204567Y1547750D01*
X204525Y1548125D01*
X204400Y1548458D01*
X204233Y1548708D01*
X203983Y1548917D01*
X203650Y1549000D01*
G01X191800Y1560600D02*
Y1542600D01*
G01X194067Y1639500D02*
Y1642000D01*
X195067D01*
X195400Y1641875D01*
X195650Y1641583D01*
X195733Y1641250D01*
X195650Y1640917D01*
X195442Y1640667D01*
X195067Y1640542D01*
X194067D01*
G01X198917Y1641792D02*
X198667Y1641917D01*
X198375Y1642000D01*
X198042D01*
X197667Y1641875D01*
X197375Y1641667D01*
X197167Y1641417D01*
X197000Y1641000D01*
X196958Y1640625D01*
X197042Y1640250D01*
X197167Y1640000D01*
X197417Y1639750D01*
X197708Y1639583D01*
X198000Y1639500D01*
X198292D01*
X198583Y1639583D01*
X198833Y1639708D01*
X199042Y1639875D01*
G01X201100Y1639500D02*
X201392Y1639542D01*
X201725Y1639667D01*
X201933Y1639875D01*
X202017Y1640167D01*
X201933Y1640458D01*
X201683Y1640708D01*
X201308Y1640833D01*
X200892D01*
X200642Y1640917D01*
X200433Y1641125D01*
X200350Y1641417D01*
X200475Y1641708D01*
X200767Y1641917D01*
X201100Y1642000D01*
X201433Y1641917D01*
X201725Y1641708D01*
X201850Y1641417D01*
X201767Y1641125D01*
X201558Y1640917D01*
X201308Y1640833D01*
X200892D01*
X200517Y1640708D01*
X200267Y1640458D01*
X200183Y1640167D01*
X200267Y1639875D01*
X200475Y1639667D01*
X200808Y1639542D01*
X201100Y1639500D01*
G01X196317Y1653292D02*
X196067Y1653417D01*
X195775Y1653500D01*
X195442D01*
X195067Y1653375D01*
X194775Y1653167D01*
X194567Y1652917D01*
X194400Y1652500D01*
X194358Y1652125D01*
X194442Y1651750D01*
X194567Y1651500D01*
X194817Y1651250D01*
X195108Y1651083D01*
X195400Y1651000D01*
X195692D01*
X195983Y1651083D01*
X196233Y1651208D01*
X196442Y1651375D01*
G01X197708Y1653083D02*
X197958Y1653333D01*
X198250Y1653458D01*
X198583Y1653500D01*
X199000Y1653417D01*
X199292Y1653208D01*
X199375Y1652958D01*
X199333Y1652708D01*
X199167Y1652500D01*
X198333Y1652083D01*
X197958Y1651792D01*
X197708Y1651375D01*
X197625Y1651000D01*
X199375D01*
G01X200808Y1652042D02*
X201100Y1652333D01*
X201350Y1652500D01*
X201683Y1652583D01*
X201975Y1652500D01*
X202183Y1652333D01*
X202350Y1652083D01*
X202392Y1651792D01*
X202350Y1651542D01*
X202183Y1651292D01*
X201933Y1651083D01*
X201642Y1651000D01*
X201308Y1651083D01*
X201017Y1651333D01*
X200850Y1651708D01*
X200808Y1652125D01*
X200892Y1652667D01*
X201017Y1652958D01*
X201225Y1653250D01*
X201517Y1653458D01*
X201808Y1653500D01*
X202100Y1653417D01*
X202308Y1653208D01*
G01X196317Y1649292D02*
X196067Y1649417D01*
X195775Y1649500D01*
X195442D01*
X195067Y1649375D01*
X194775Y1649167D01*
X194567Y1648917D01*
X194400Y1648500D01*
X194358Y1648125D01*
X194442Y1647750D01*
X194567Y1647500D01*
X194817Y1647250D01*
X195108Y1647083D01*
X195400Y1647000D01*
X195692D01*
X195983Y1647083D01*
X196233Y1647208D01*
X196442Y1647375D01*
G01X197708Y1649083D02*
X197958Y1649333D01*
X198250Y1649458D01*
X198583Y1649500D01*
X199000Y1649417D01*
X199292Y1649208D01*
X199375Y1648958D01*
X199333Y1648708D01*
X199167Y1648500D01*
X198333Y1648083D01*
X197958Y1647792D01*
X197708Y1647375D01*
X197625Y1647000D01*
X199375D01*
G01X200683Y1647375D02*
X200933Y1647167D01*
X201225Y1647042D01*
X201600Y1647000D01*
X201975Y1647083D01*
X202267Y1647250D01*
X202475Y1647542D01*
X202517Y1647875D01*
X202433Y1648208D01*
X202225Y1648417D01*
X201933Y1648583D01*
X201642Y1648625D01*
X201350Y1648583D01*
X200975Y1648417D01*
X201100Y1649500D01*
X202225D01*
G01X232871Y1963287D02*
Y1967287D01*
X230404Y1964420D01*
X233738D01*
G01X199109Y1964087D02*
X199509Y1963620D01*
X200043Y1963354D01*
X200643Y1963287D01*
X201176Y1963354D01*
X201709Y1963687D01*
X202043Y1964087D01*
X202109Y1964487D01*
X201976Y1964954D01*
X201509Y1965287D01*
X201043Y1965420D01*
X200443D01*
G01X201043D02*
X201443Y1965620D01*
X201776Y1965954D01*
X201909Y1966354D01*
X201776Y1966754D01*
X201443Y1967087D01*
X200843Y1967287D01*
X200243Y1967220D01*
X199643Y1966954D01*
G01X262099Y1963887D02*
X262499Y1963554D01*
X262966Y1963354D01*
X263566Y1963287D01*
X264166Y1963420D01*
X264633Y1963687D01*
X264966Y1964154D01*
X265033Y1964687D01*
X264899Y1965220D01*
X264566Y1965554D01*
X264099Y1965820D01*
X263633Y1965887D01*
X263166Y1965820D01*
X262566Y1965554D01*
X262766Y1967287D01*
X264566D01*
G01X293795Y1964954D02*
X294262Y1965420D01*
X294662Y1965687D01*
X295195Y1965820D01*
X295662Y1965687D01*
X295995Y1965420D01*
X296262Y1965020D01*
X296329Y1964554D01*
X296262Y1964154D01*
X295995Y1963754D01*
X295595Y1963420D01*
X295129Y1963287D01*
X294595Y1963420D01*
X294129Y1963820D01*
X293862Y1964420D01*
X293795Y1965087D01*
X293929Y1965954D01*
X294129Y1966420D01*
X294462Y1966887D01*
X294929Y1967220D01*
X295395Y1967287D01*
X295862Y1967154D01*
X296195Y1966820D01*
M02*
